BODY ORDERED NET LIST - 1  
C1A1             CAP_0805LF-22UF,4V,20%,X6S,C95A 1        PVDDQ_KLM               
                                  2        GND                     
C1A2             CAP_A_0402V-1.0UF,6.3V,10%,X6SA 1        P5V_STBY                
                                  2        GND                     
C1A4             CAP_0805-10UF,16V,10%,X7R,G106A 1        P12V_NVDIMM_KLM         
                                  2        GND                     
C1A5             CAP_A_0402V-0.01UF,25V,10%,X7RA 1        M_M_VREF                
                                  2        GND                     
C1A6             CAP_0402-1.0UF,16V,10%,X6S,D97A 1        VR_PVDDQ_KLM_PH2_VCIN   
                                  2        GND                     
C1A8             CAP_0402-0.220UF,16V,10%,X7R,AA 1        VR_PVDDQ_KLM_PH2_BOOT   
                                  2        VR_PVDDQ_KLM_PH2_PHASE  
C1A9             CAP_0402-1.0UF,16V,10%,X6S,D97A 1        VR_FET_SW_P12V_STBY_PVDDQ_KLM
                                  2        GND                     
C1A10            CAP_A_0402V-0.1UF,16V,10%,X7R,A 1        VR_FET_SW_P12V_STBY_PVDDQ_KLM
                                  2        GND                     
C1A11            CAP_A_0402V-1.0UF,6.3V,10%,X6SA 1        P5V_STBY                
                                  2        GND                     
C1A12            CAP_0805LF-22UF,4V,20%,X6S,C95A 1        PVDDQ_KLM               
                                  2        GND                     
C1A13            CAP_0402-0.22UF,16V,10%,X7R,A3A 1        P5V_STBY                
                                  2        GND                     
C1A16            CAP_0805-10UF,16V,10%,X7R,G106A 1        P12V_NVDIMM_KLM         
                                  2        GND                     
C1A17            CAP_A_0402V-0.01UF,25V,10%,X7RA 1        M_L_VREF                
                                  2        GND                     
C1A18            CAP_0402-0.220UF,16V,10%,X7R,AA 1        VR_PVDDQ_KLM_PH1_BOOT   
                                  2        VR_PVDDQ_KLM_PH1_PHASE  
C1A19            CAP_0402-1.0UF,16V,10%,X6S,D97A 1        VR_FET_SW_P12V_STBY_PVDDQ_KLM
                                  2        GND                     
C1A20            CAP_A_0402V-0.1UF,16V,10%,X7R,A 1        VR_FET_SW_P12V_STBY_PVDDQ_KLM
                                  2        GND                     
C1B2             CAP_A_0402V-0.1UF,16V,10%,X7R,A 1        VR_PVDDQ_KLM_VD12       
                                  2        GND                     
C1B3             CAP_A_0402V-1.0UF,6.3V,10%,X6SA 1        VR_PVDDQ_KLM_VD12       
                                  2        GND                     
C1B4             CAP_0402LF-1000PF,50V,10%,X7R,A 1        PWRGD_PVDDQ_KLM_R       
                                  2        GND                     
C1B5             CAP_A_0402V-0.1UF,16V,10%,X7R,A 1        VR_PVDDQ_KLM_VDD        
                                  2        GND                     
C1B6             CAP_A_0402V-1.0UF,6.3V,10%,X6SA 1        VR_PVDDQ_KLM_VDD        
                                  2        GND                     
C1B7             CAP_0805-10UF,16V,10%,X7R,G106A 1        P12V_NVDIMM_KLM         
                                  2        GND                     
C1B8             CAP_0402LF-1000PF,50V,10%,X7R,A 1        VR_PVDDQ_KLM_VINSEN     
                                  2        GND                     
C1B9             CAP_A_0402V-0.01UF,25V,10%,X7RA 1        M_K_VREF                
                                  2        GND                     
C1B10            CAPP_2626-270UF,16V,20%,OSCON,A 1        VR_FET_SW_P12V_STBY_PVDDQ_KLM
                                  2        GND                     
C1B11            CAP_0402LF-220PF,50V,10%,X7R,AA 1        A_TSENSE_PVDDQ_KLM      
                                  2        GND                     
C1B12            CAP_0402LF-220PF,50V,10%,X7R,AA 1        VR_PVDDQ_KLM_AVSP       
                                  2        VSENSE_PVDDQ_KLM_N      
C1B14            CAPP_4040LF-470UF,16V,20%,ALUMA 1        P12V_STBY               
                                  2        GND                     
C1B15            CAP_A_0402V-0.01UF,25V,10%,X7RA 1        FAN_TACH2               
                                  2        GND                     
C1B16            CAP_A_0402V-0.1UF,16V,10%,EMPTA 1        VR_FET_SW_P12V_PVCCIN_CPU1_R
                                  2        GND                     
C1B17            CAP_A_0402V-0.01UF,25V,10%,X7RA 1        FAN_TACH3               
                                  2        GND                     
C1B18            CAP_0805-10UF,16V,10%,X6S,C953A 1        P12V_FAN                
                                  2        GND                     
C1B19            CAP_A_0402V-0.1UF,16V,10%,X7R,A 1        P12V_FAN                
                                  2        GND                     
C1B20            CAP_0402-1.0UF,16V,10%,X6S,D97A 1        VR_PVDDQ_KLM_PH1_VCIN   
                                  2        GND                     
C1B21            CAP_0402-0.22UF,16V,10%,X7R,A3A 1        P5V_STBY                
                                  2        GND                     
C1C1             CAPP_2626-270UF,16V,20%,OSCON,A 1        VR_FET_SW_P12V_STBY_PVCCIN_CPU1
                                  2        GND                     
C1C2             CAPP_2626-270UF,16V,20%,OSCON,A 1        VR_FET_SW_P12V_STBY_PVCCIN_CPU1
                                  2        GND                     
C1C3             CAP_A_0402V-1.0UF,6.3V,10%,X6SA 1        P5V_STBY                
                                  2        GND                     
C1C4             CAP_0402-0.22UF,16V,10%,X7R,A3A 1        P5V_STBY                
                                  2        GND                     
C1C5             CAP_0402-1.0UF,16V,10%,X6S,D97A 1        VR_PVSA_CPU1_VCIN       
                                  2        GND                     
C1C7             CAP_A_0402V-1.0UF,6.3V,10%,X6SA 1        VR_PVCCIN_CPU1_VDD      
                                  2        GND                     
C1C8             CAP_0402LF-1000PF,50V,10%,X7R,A 1        VR_PVCCIN_CPU1_AVINSEN  
                                  2        GND                     
C1C9             CAP_A_0402V-0.1UF,16V,10%,X7R,A 1        VR_PVCCIN_CPU1_VDD      
                                  2        GND                     
C1C10            CAP_0402LF-220PF,50V,10%,X7R,AA 1        A_TSENSE_PVCCIN_CPU1    
                                  2        GND                     
C1C11            CAP_0402LF-220PF,50V,10%,X7R,AA 1        A_TSENSE_PVSA_CPU1      
                                  2        GND                     
C1C12            CAP_0402-0.220UF,16V,10%,X7R,AA 1        VR_PVSA_CPU1_BOOT       
                                  2        VR_PVSA_CPU1_PHASE      
C1C13            CAP_A_0402V-1.0UF,6.3V,10%,X6SA 1        VR_PVCCIN_CPU1_VD12     
                                  2        GND                     
C1C14            CAP_A_0402V-0.1UF,16V,10%,X7R,A 1        VR_PVCCIN_CPU1_VD12     
                                  2        GND                     
C1C15            CAP_0402-1.0UF,16V,10%,X6S,D97A 1        VR_FET_SW_P12V_STBY_PVCCIN_CPU1
                                  2        GND                     
C1C16            CAP_0402LF-220PF,50V,10%,X7R,AA 1        VSENSE_PVSA_CPU1_BVSP   
                                  2        VSENSE_PVSA_CPU1_N      
C1C17            CAP_A_0402V-0.1UF,16V,10%,X7R,A 1        VR_FET_SW_P12V_STBY_PVCCIN_CPU1
                                  2        GND                     
C1C18            CAP_A_0402V-1.0UF,6.3V,10%,X6SA 1        P5V_STBY                
                                  2        GND                     
C1C19            CAP_A_0603V-22.0UF,4V,20%,X6S,A 1        PVSA_CPU1               
                                  2        GND                     
C1C23            CAP_0402LF-1000PF,50V,10%,X7R,A 1        VR_VRRDY_PVCCIN_CPU1    
                                  2        GND                     
C1C24            CAP_0402-0.220UF,16V,10%,X7R,AA 1        VR_PVCCIN_CPU1_PH5_BOOT 
                                  2        VR_PVCCIN_CPU1_PH5_PHASE
C1C25            CAP_A_0402V-0.1UF,16V,10%,X7R,A 1        VR_FET_SW_P12V_STBY_PVCCIN_CPU1
                                  2        GND                     
C1C26            CAP_0402-1.0UF,16V,10%,X6S,D97A 1        VR_FET_SW_P12V_STBY_PVCCIN_CPU1
                                  2        GND                     
C1D1             CAP_0402LF-220PF,50V,10%,X7R,AA 1        VSENSE_PVCCIN_CPU1_AVSP 
                                  2        VSENSE_PVCCIN_CPU1_N    
C1D3             CAP_A_0603V-22.0UF,4V,20%,X6S,A 1        PVCCIN_CPU1             
                                  2        GND                     
C1D5             CAP_A_0402V-1.0UF,6.3V,10%,X6SA 1        P5V_STBY                
                                  2        GND                     
C1D6             CAP_0402-0.22UF,16V,10%,X7R,A3A 1        P5V_STBY                
                                  2        GND                     
C1D7             CAP_0402-1.0UF,16V,10%,X6S,D97A 1        VR_PVCCIN_CPU1_PH4_VCIN 
                                  2        GND                     
C1D9             CAP_A_0402V-0.1UF,16V,10%,X7R,A 1        P12V_STBY               
                                  2        AGND_HSC                
C1D10            CAP_0402-0.220UF,16V,10%,X7R,AA 1        VR_PVCCIN_CPU1_PH4_BOOT 
                                  2        VR_PVCCIN_CPU1_PH4_PHASE
C1D11            CAP_A_0402V-0.1UF,16V,10%,X7R,A 1        FM_P12V_HOTSWAP0_EN     
                                  2        AGND_HSC                
C1D12            CAP_0402-1.0UF,16V,10%,X6S,D97A 1        VR_FET_SW_P12V_STBY_PVCCIN_CPU1
                                  2        GND                     
C1D13            CAP_A_0402V-0.1UF,16V,10%,X7R,A 1        VR_FET_SW_P12V_STBY_PVCCIN_CPU1
                                  2        GND                     
C1D14            CAP_A_0603V-22.0UF,4V,20%,X6S,A 1        PVCCIN_CPU1             
                                  2        GND                     
C1D15            CAP_A_0402V-1.0UF,6.3V,10%,X6SA 1        P5V_STBY                
                                  2        GND                     
C1D16            CAP_0402-0.22UF,16V,10%,X7R,A3A 1        P5V_STBY                
                                  2        GND                     
C1D17            CAP_0402-1.0UF,16V,10%,X6S,D97A 1        VR_PVCCIN_CPU1_PH3_VCIN 
                                  2        GND                     
C1D19            CAP_0402-1.0UF,16V,10%,X6S,D97A 1        A_HSC_VCAP              
                                  2        AGND_HSC                
C1D20            CAP_0402-0.220UF,16V,10%,X7R,AA 1        VR_PVCCIN_CPU1_PH3_BOOT 
                                  2        VR_PVCCIN_CPU1_PH3_PHASE
C1D21            CAP_A_0402V-0.1UF,16V,10%,X7R,A 1        A_HSC_PSET              
                                  2        AGND_HSC                
C1D22            CAP_A_0402V-0.1UF,16V,10%,EMPTA 1        A_HSC_MON               
                                  2        A_HSC_MOP               
C1D23            CAP_0402-1.0UF,16V,10%,X6S,D97A 1        VR_FET_SW_P12V_STBY_PVCCIN_CPU1
                                  2        GND                     
C1D24            CAP_A_0603V-22.0UF,4V,20%,X6S,A 1        PVCCIN_CPU1             
                                  2        GND                     
C1D25            CAP_0402-1.0UF,16V,10%,X6S,D97A 1        P12V_HSC_VCC            
                                  2        AGND_HSC                
C1D26            CAP_A_0402V-0.1UF,16V,10%,X7R,A 1        A_HSC_UV                
                                  2        AGND_HSC                
C1D27            CAP_A_0402V-0.1UF,16V,10%,X7R,A 1        A_HSC_OV                
                                  2        AGND_HSC                
C1D28            CAP_A_0402V-0.1UF,16V,10%,X7R,A 1        VR_FET_SW_P12V_STBY_PVCCIN_CPU1
                                  2        GND                     
C1D32            CAP_0402-1.0UF,16V,10%,X6S,D97A 1        VR_PVCCIN_CPU1_PH5_VCIN 
                                  2        GND                     
C1D33            CAP_0402-0.22UF,16V,10%,X7R,A3A 1        P5V_STBY                
                                  2        GND                     
C1D34            CAP_A_0402V-0.1UF,16V,10%,X7R,A 1        VR_FET_SW_P12V_STBY_PVCCIN_CPU1
                                  2        GND                     
C1D35            CAP_0402-1.0UF,16V,10%,X6S,D97A 1        VR_FET_SW_P12V_STBY_PVCCIN_CPU1
                                  2        GND                     
C1D36            CAP_0402-0.220UF,16V,10%,X7R,AA 1        VR_PVCCIN_CPU1_PH2_BOOT 
                                  2        VR_PVCCIN_CPU1_PH2_PHASE
C1E2             CAP_1206-0.068UF,50V,20%,X7R,1A 1        A_HSC_C                 
                                  2        GND                     
C1E3             CAP_A_0603V-22.0UF,4V,20%,X6S,A 1        PVCCIN_CPU1             
                                  2        GND                     
C1E6             CAP_A_0402V-1.0UF,6.3V,10%,X6SA 1        P5V_STBY                
                                  2        GND                     
C1E7             CAP_0402-0.22UF,16V,10%,X7R,A3A 1        P5V_STBY                
                                  2        GND                     
C1E8             CAP_0402-1.0UF,16V,10%,X6S,D97A 1        VR_PVCCIN_CPU1_PH1_VCIN 
                                  2        GND                     
C1E9             CAP_A_0603V-22.0UF,4V,20%,X6S,A 1        PVCCIN_CPU1             
                                  2        GND                     
C1E11            CAP_0402-0.220UF,16V,10%,X7R,AA 1        VR_PVCCIN_CPU1_PH1_BOOT 
                                  2        VR_PVCCIN_CPU1_PH1_PHASE
C1E12            CAP_0805-10UF,16V,10%,X6S,C953A 1        P12V_PSU                
                                  2        GND                     
C1E13            CAP_0402-1.0UF,16V,10%,X6S,D97A 1        VR_FET_SW_P12V_STBY_PVCCIN_CPU1
                                  2        GND                     
C1E14            CAP_A_0402V-0.1UF,16V,10%,X7R,A 1        VR_FET_SW_P12V_STBY_PVCCIN_CPU1
                                  2        GND                     
C1E15            CAP_0805-10UF,16V,10%,X6S,C953A 1        P12V_PSU                
                                  2        GND                     
C1E16            CAP_A_0402V-0.1UF,16V,10%,X7R,A 1        P12V_PSU                
                                  2        GND                     
C1E17            CAP_A_0402V-0.1UF,16V,10%,X7R,A 1        P12V_PSU                
                                  2        GND                     
C1E18            CAPP_2626-270UF,16V,20%,OSCON,A 1        VR_FET_SW_P12V_STBY_PVCCIN_CPU1
                                  2        GND                     
C1E19            CAP_0402LF-47.0PF,50V,5%,EMPTYA 1        ISENSE_TMP421_2_DXP     
                                  2        ISENSE_TMP421_2_DXN     
C1E20            CAP_A_0402V-0.1UF,16V,10%,X7R,A 1        P12V_FAN                
                                  2        GND                     
C1E21            CAP_0805-10UF,16V,10%,X6S,C953A 1        P12V_FAN                
                                  2        GND                     
C1E22            CAP_A_0402V-0.1UF,16V,10%,X7R,A 1        P3V3_STBY               
                                  2        GND                     
C1E23            CAP_A_0402V-1.0UF,6.3V,10%,X6SA 1        P5V_STBY                
                                  2        GND                     
C1E24            CAP_0402-1.0UF,16V,10%,X6S,D97A 1        VR_PVCCIN_CPU1_PH2_VCIN 
                                  2        GND                     
C1E25            CAP_0402-0.22UF,16V,10%,X7R,A3A 1        P5V_STBY                
                                  2        GND                     
C1F2             CAP_0402-0.22UF,16V,10%,X7R,A3A 1        P3E_CPU1_PE3_MP_C_TXP<7>
                                  2        P3E_CPU1_PE3_MP_TXP<7>  
C1F3             CAP_0402-0.22UF,16V,10%,X7R,A3A 1        P3E_CPU1_PE3_MP_C_TXN<7>
                                  2        P3E_CPU1_PE3_MP_TXN<7>  
C1F4             CAP_0402-0.22UF,16V,10%,X7R,A3A 1        P3E_CPU1_PE3_MP_C_TXN<6>
                                  2        P3E_CPU1_PE3_MP_TXN<6>  
C1F5             CAP_0402-0.22UF,16V,10%,X7R,A3A 1        P3E_CPU1_PE3_MP_C_TXP<6>
                                  2        P3E_CPU1_PE3_MP_TXP<6>  
C1F6             CAP_0402-0.22UF,16V,10%,X7R,A3A 1        P3E_CPU1_PE3_MP_C_TXP<5>
                                  2        P3E_CPU1_PE3_MP_TXP<5>  
C1F7             CAPP_4040LF-470UF,16V,20%,ALUMA 1        P12V_STBY               
                                  2        GND                     
C1F8             CAP_0402-0.22UF,16V,10%,X7R,A3A 1        P3E_CPU1_PE3_MP_C_TXN<5>
                                  2        P3E_CPU1_PE3_MP_TXN<5>  
C1F9             CAP_A_0402V-0.01UF,25V,10%,X7RA 1        FAN_TACH0               
                                  2        GND                     
C1F10            CAP_0402-0.22UF,16V,10%,X7R,A3A 1        P3E_CPU1_PE3_MP_C_TXN<4>
                                  2        P3E_CPU1_PE3_MP_TXN<4>  
C1F11            CAP_0402-0.22UF,16V,10%,X7R,A3A 1        P3E_CPU1_PE3_MP_C_TXP<4>
                                  2        P3E_CPU1_PE3_MP_TXP<4>  
C1F12            CAP_0402-0.22UF,16V,10%,X7R,A3A 1        P3E_CPU1_PE3_MP_C_TXP<3>
                                  2        P3E_CPU1_PE3_MP_TXP<3>  
C1F13            CAP_0402-0.22UF,16V,10%,X7R,A3A 1        P3E_CPU1_PE3_MP_C_TXN<3>
                                  2        P3E_CPU1_PE3_MP_TXN<3>  
C1F14            CAP_0402-0.22UF,16V,10%,X7R,A3A 1        P3E_CPU1_PE3_MP_C_TXP<2>
                                  2        P3E_CPU1_PE3_MP_TXP<2>  
C1F15            CAP_0402-0.22UF,16V,10%,X7R,A3A 1        P3E_CPU1_PE3_MP_C_TXN<2>
                                  2        P3E_CPU1_PE3_MP_TXN<2>  
C1F16            CAP_0402-0.22UF,16V,10%,X7R,A3A 1        P3E_CPU1_PE3_MP_C_TXN<1>
                                  2        P3E_CPU1_PE3_MP_TXN<1>  
C1F17            CAP_0402-0.22UF,16V,10%,X7R,A3A 1        P3E_CPU1_PE3_MP_C_TXP<1>
                                  2        P3E_CPU1_PE3_MP_TXP<1>  
C1F18            CAP_0402-0.22UF,16V,10%,X7R,A3A 1        P3E_CPU1_PE3_MP_C_TXP<0>
                                  2        P3E_CPU1_PE3_MP_TXP<0>  
C1F19            CAP_A_0402V-0.01UF,25V,10%,X7RA 1        M_G_CPU_VREF            
                                  2        GND                     
C1F20            CAP_0402-0.22UF,16V,10%,X7R,A3A 1        P3E_CPU1_PE3_MP_C_TXN<0>
                                  2        P3E_CPU1_PE3_MP_TXN<0>  
C1F21            CAP_A_0402V-1.0UF,6.3V,10%,X6SA 1        P5V_STBY                
                                  2        GND                     
C1F22            CAP_A_0402V-0.01UF,25V,10%,X7RA 1        M_G_VREF                
                                  2        GND                     
C1F26            CAP_0402-0.220UF,16V,10%,X7R,AA 1        VR_PVDDQ_GHJ_PH2_BOOT   
                                  2        VR_PVDDQ_GHJ_PH2_PHASE  
C1F27            CAP_0402-1.0UF,16V,10%,X6S,D97A 1        VR_FET_SW_P12V_STBY_PVDDQ_GHJ
                                  2        GND                     
C1F28            CAP_A_0402V-0.1UF,16V,10%,X7R,A 1        VR_FET_SW_P12V_STBY_PVDDQ_GHJ
                                  2        GND                     
C1G2             CAP_1210-47UF,16V,20%,X6S,D384A 1        VR_FET_SW_P12V_STBY_PVDDQ_GHJ
                                  2        GND                     
C1G4             CAP_A_0402V-1.0UF,6.3V,10%,X6SA 1        P5V_STBY                
                                  2        GND                     
C1G5             CAP_0402-0.22UF,16V,10%,X7R,A3A 1        P5V_STBY                
                                  2        GND                     
C1G6             CAP_0402-1.0UF,16V,10%,X6S,D97A 1        VR_PVDDQ_GHJ_PH1_VCIN   
                                  2        GND                     
C1G7             CAP_1210-47UF,16V,20%,X6S,D384A 1        VR_FET_SW_P12V_STBY_PVDDQ_GHJ
                                  2        GND                     
C1G8             CAP_A_0402V-0.01UF,25V,10%,X7RA 1        M_H_CPU_VREF            
                                  2        GND                     
C1G10            CAP_A_0402V-0.01UF,25V,10%,X7RA 1        M_H_VREF                
                                  2        GND                     
C1G11            CAP_0402-0.220UF,16V,10%,X7R,AA 1        VR_PVDDQ_GHJ_PH1_BOOT   
                                  2        VR_PVDDQ_GHJ_PH1_PHASE  
C1G12            CAP_1210-47UF,16V,20%,X6S,D384A 1        VR_FET_SW_P12V_STBY_PVDDQ_GHJ
                                  2        GND                     
C1G13            CAP_0402-1.0UF,16V,10%,X6S,D97A 1        VR_FET_SW_P12V_STBY_PVDDQ_GHJ
                                  2        GND                     
C1G14            CAP_A_0402V-0.1UF,16V,10%,X7R,A 1        VR_FET_SW_P12V_STBY_PVDDQ_GHJ
                                  2        GND                     
C1G15            CAP_1210-47UF,16V,20%,X6S,D384A 1        VR_FET_SW_P12V_STBY_PVDDQ_GHJ
                                  2        GND                     
C1G16            CAP_0402LF-220PF,50V,10%,X7R,AA 1        VR_PVDDQ_GHJ_AVSP       
                                  2        VSENSE_PVDDQ_GHJ_N      
C1G17            CAP_0805LF-22UF,4V,20%,X6S,C95A 1        PVDDQ_GHJ               
                                  2        GND                     
C1G18            CAP_A_0402V-0.01UF,25V,10%,X7RA 1        M_J_CPU_VREF            
                                  2        GND                     
C1G19            CAP_A_0402V-0.01UF,25V,10%,X7RA 1        M_J_VREF                
                                  2        GND                     
C1G20            CAP_0805LF-22UF,4V,20%,X6S,C95A 1        PVDDQ_GHJ               
                                  2        GND                     
C1G21            CAP_0402LF-1000PF,50V,10%,X7R,A 1        PWRGD_PVDDQ_GHJ_R       
                                  2        GND                     
C1G22            CAP_A_0402V-0.1UF,16V,10%,X7R,A 1        VR_PVDDQ_GHJ_VD12       
                                  2        GND                     
C1G23            CAP_A_0402V-1.0UF,6.3V,10%,X6SA 1        VR_PVDDQ_GHJ_VD12       
                                  2        GND                     
C1G24            CAP_0402LF-220PF,50V,10%,X7R,AA 1        A_TSENSE_PVDDQ_GHJ      
                                  2        GND                     
C1G25            CAP_A_0402V-0.1UF,16V,10%,X7R,A 1        VR_PVDDQ_GHJ_VDD        
                                  2        GND                     
C1G26            CAP_0402LF-1000PF,50V,10%,X7R,A 1        VR_PVDDQ_GHJ_VINSEN     
                                  2        GND                     
C1G27            CAP_A_0402V-1.0UF,6.3V,10%,X6SA 1        VR_PVDDQ_GHJ_VDD        
                                  2        GND                     
C1G28            CAP_0402-1.0UF,16V,10%,X6S,D97A 1        VR_PVDDQ_GHJ_PH2_VCIN   
                                  2        GND                     
C1G29            CAP_0402-0.22UF,16V,10%,X7R,A3A 1        P5V_STBY                
                                  2        GND                     
C1L1             CAP_0402-1.0UF,16V,10%,X6S,D97A 1        P3V3_STBY               
                                  2        GND                     
C1L2             CAP_A_0402V-0.01UF,25V,10%,X7RA 1        SATA6G_P8_TX_C_DP       
                                  2        SATA6G_TX_DP<0>         
C1L3             CAP_A_0402V-0.01UF,25V,10%,X7RA 1        SATA6G_P8_TX_C_DN       
                                  2        SATA6G_TX_DN<0>         
C1L4             CAP_A_0402V-0.1UF,16V,10%,X7R,A 1        P5V_STBY                
                                  2        GND                     
C1L5             CAP_A_0402V-1.0UF,6.3V,10%,X6SA 1        P1V05_PCH_STBY          
                                  2        GND                     
C1L6             CAP_A_0402V-0.01UF,25V,10%,X7RA 1        SATA6G_P9_TX_C_DP       
                                  2        SATA6G_TX_DP<1>         
C1L7             CAP_A_0402V-0.01UF,25V,10%,X7RA 1        SATA6G_P9_TX_C_DN       
                                  2        SATA6G_TX_DN<1>         
C1L8             CAP_A_0402V-0.1UF,16V,10%,X7R,A 1        XDP_PWRGD_RST_N         
                                  2        GND                     
C1L9             CAP_A_0402V-0.1UF,16V,10%,X7R,A 1        P3V3_STBY               
                                  2        GND                     
C1L10            CAP_A_0402V-1.0UF,6.3V,10%,X6SA 1        FP_RST_BTN_R_N          
                                  2        GND                     
C1L11            CAP_A_0402V-0.1UF,16V,10%,X7R,A 1        P3V3_STBY               
                                  2        GND                     
C1L12            CAP_A_0402V-0.01UF,25V,10%,X7RA 1        SATA6G_P10_TX_C_DP      
                                  2        SATA6G_TX_DP<2>         
C1L13            CAP_A_0402V-0.01UF,25V,10%,X7RA 1        SATA6G_P10_TX_C_DN      
                                  2        SATA6G_TX_DN<2>         
C1L14            CAP_A_0402V-0.01UF,25V,10%,X7RA 1        SATA6G_P11_TX_C_DP      
                                  2        SATA6G_TX_DP<3>         
C1L15            CAP_A_0402V-0.01UF,25V,10%,X7RA 1        SATA6G_P11_TX_C_DN      
                                  2        SATA6G_TX_DN<3>         
C1L16            CAP_A_0402V-0.1UF,16V,10%,X7R,A 1        P3V3                    
                                  2        GND                     
C1L17            CAP_A_0402V-0.1UF,16V,10%,X7R,A 1        P3V3_STBY               
                                  2        GND                     
C1L18            CAP_A_0402V-1.0UF,6.3V,10%,X6SA 1        FP_PWR_BTN_R1_N         
                                  2        GND                     
C1L19            CAP_0402-1.0UF,16V,10%,X6S,D97A 1        P3V3_STBY               
                                  2        GND                     
C1L20            CAP_A_0402V-0.01UF,25V,10%,X7RA 1        P3V3_STBY               
                                  2        GND                     
C1M1             CAP_A_0402V-0.1UF,16V,10%,X7R,A 1        USB3_P01_TXP            
                                  2        USB3_P01_C_TXP          
C1M2             CAP_A_0402V-0.1UF,16V,10%,X7R,A 1        USB3_P01_TXN            
                                  2        USB3_P01_C_TXN          
C1M3             CAP_A_0402V-1.0UF,6.3V,10%,X6SA 1        P3V3                    
                                  2        GND                     
C1M4             CAP_0402LF-47.0PF,50V,5%,EMPTYA 1        ISENSE_TMP421_1_DXP     
                                  2        ISENSE_TMP421_1_DXN     
C1M5             CAPP_3018-68UF,16V,20%,TANT,72A 1        P12V_STBY               
                                  2        GND                     
C1M6             CAP_0402-0.22UF,16V,10%,X7R,A3A 1        P3E_CPU0_PE3_OCP_TXP<15>
                                  2        P3E_OCP_CPU0_PE3_C_TXP<15>
C1M7             CAP_0402-0.22UF,16V,10%,X7R,A3A 1        P3E_CPU0_PE3_OCP_TXN<15>
                                  2        P3E_OCP_CPU0_PE3_C_TXN<15>
C1M8             CAP_0402-0.22UF,16V,10%,X7R,A3A 1        P3E_CPU0_PE3_OCP_TXP<14>
                                  2        P3E_OCP_CPU0_PE3_C_TXP<14>
C1M9             CAP_0402-0.22UF,16V,10%,X7R,A3A 1        P3E_CPU0_PE3_OCP_TXN<14>
                                  2        P3E_OCP_CPU0_PE3_C_TXN<14>
C1M10            CAP_0402-0.22UF,16V,10%,X7R,A3A 1        P3E_CPU0_PE3_OCP_TXP<13>
                                  2        P3E_OCP_CPU0_PE3_C_TXP<13>
C1M11            CAP_0402-0.22UF,16V,10%,X7R,A3A 1        P3E_CPU0_PE3_OCP_TXN<13>
                                  2        P3E_OCP_CPU0_PE3_C_TXN<13>
C1M12            CAP_0402-0.22UF,16V,10%,X7R,A3A 1        P3E_CPU0_PE3_OCP_TXP<12>
                                  2        P3E_OCP_CPU0_PE3_C_TXP<12>
C1M13            CAP_0402-0.22UF,16V,10%,X7R,A3A 1        P3E_CPU0_PE3_OCP_TXN<12>
                                  2        P3E_OCP_CPU0_PE3_C_TXN<12>
C1M14            CAP_0402-0.22UF,16V,10%,X7R,A3A 1        P3E_CPU0_PE3_OCP_TXP<11>
                                  2        P3E_OCP_CPU0_PE3_C_TXP<11>
C1M15            CAP_0402-0.22UF,16V,10%,X7R,A3A 1        P3E_CPU0_PE3_OCP_TXN<11>
                                  2        P3E_OCP_CPU0_PE3_C_TXN<11>
C1M16            CAP_0402-0.22UF,16V,10%,X7R,A3A 1        P3E_CPU0_PE3_OCP_TXP<10>
                                  2        P3E_OCP_CPU0_PE3_C_TXP<10>
C1M17            CAP_0402-0.22UF,16V,10%,X7R,A3A 1        P3E_CPU0_PE3_OCP_TXN<10>
                                  2        P3E_OCP_CPU0_PE3_C_TXN<10>
C1M18            CAP_0402-0.22UF,16V,10%,X7R,A3A 1        P3E_CPU0_PE3_OCP_TXP<9> 
                                  2        P3E_OCP_CPU0_PE3_C_TXP<9>
C1M19            CAP_0402-0.22UF,16V,10%,X7R,A3A 1        P3E_CPU0_PE3_OCP_TXN<9> 
                                  2        P3E_OCP_CPU0_PE3_C_TXN<9>
C1M20            CAP_A_0402V-0.1UF,16V,10%,X7R,A 1        P3V3_STBY               
                                  2        GND                     
C1M21            CAP_A_0402V-1.0UF,6.3V,10%,X6SA 1        P3V3                    
                                  2        GND                     
C1M22            CAP_A_0402V-0.1UF,16V,10%,X7R,A 1        P12V_STBY               
                                  2        GND                     
C1M23            CAP_A_0402V-0.1UF,16V,10%,X7R,A 1        P12V_STBY               
                                  2        GND                     
C1M24            CAP_A_0402V-0.1UF,16V,10%,X7R,A 1        P3V3                    
                                  2        GND                     
C1M25            CAP_A_0402V-1.0UF,6.3V,10%,X6SA 1        P3V3_STBY               
                                  2        GND                     
C1M26            CAP_0805-10UF,16V,10%,X6S,C953A 1        P12V_STBY               
                                  2        GND                     
C1M27            CAP_0805-10UF,16V,10%,X6S,C953A 1        P12V_STBY               
                                  2        GND                     
C1M28            CAP_A_0402V-0.01UF,25V,10%,X7RA 1        P3V3_STBY               
                                  2        GND                     
C1M29            CAP_A_0402V-0.1UF,16V,10%,X7R,A 1        P1V8_MCP_CPU0           
                                  2        GND                     
C1M30            CAP_A_0402V-0.01UF,25V,10%,X7RA 1        P3V3_STBY               
                                  2        GND                     
C1M31            CAP_A_0402V-0.01UF,25V,10%,X7RA 1        P3V3_STBY               
                                  2        GND                     
C1M32            CAP_A_0402V-1.0UF,6.3V,10%,X6SA 1        P3V3_STBY               
                                  2        GND                     
C1M33            CAP_A_0402V-0.1UF,16V,10%,X7R,A 1        JTAG_MCP_TMS_R1         
                                  2        GND                     
C1M34            CAP_A_0402V-0.01UF,25V,10%,X7RA 1        P3V3_STBY               
                                  2        GND                     
C1M35            CAP_A_0402V-0.01UF,25V,10%,X7RA 1        P3V3_STBY               
                                  2        GND                     
C1M36            CAP_A_0402V-0.01UF,25V,10%,X7RA 1        P3V3_STBY               
                                  2        GND                     
C1M37            CAP_A_0402V-1.0UF,6.3V,10%,X6SA 1        P3V3_STBY               
                                  2        GND                     
C1M38            CAP_A_0402V-0.1UF,16V,10%,X7R,A 1        P5V                     
                                  2        GND                     
C1R1             CAP_0402-0.22UF,16V,10%,X7R,A3A 1        P3E_CPU0_PE3_OCP_TXN<0> 
                                  2        P3E_OCP_CPU0_PE3_C_TXN<0>
C1R2             CAP_0402-0.22UF,16V,10%,X7R,A3A 1        P3E_CPU0_PE3_OCP_TXP<0> 
                                  2        P3E_OCP_CPU0_PE3_C_TXP<0>
C1R3             CAP_0402-0.22UF,16V,10%,X7R,A3A 1        P3E_CPU0_PE3_OCP_TXN<1> 
                                  2        P3E_OCP_CPU0_PE3_C_TXN<1>
C1R4             CAP_0402-0.22UF,16V,10%,X7R,A3A 1        P3E_CPU0_PE3_OCP_TXP<1> 
                                  2        P3E_OCP_CPU0_PE3_C_TXP<1>
C1R5             CAP_0402-0.22UF,16V,10%,X7R,A3A 1        P3E_CPU0_PE3_OCP_TXN<2> 
                                  2        P3E_OCP_CPU0_PE3_C_TXN<2>
C1R6             CAP_0402-0.22UF,16V,10%,X7R,A3A 1        P3E_CPU0_PE3_OCP_TXP<2> 
                                  2        P3E_OCP_CPU0_PE3_C_TXP<2>
C1R7             CAP_0402-0.22UF,16V,10%,X7R,A3A 1        P3E_CPU0_PE3_OCP_TXN<3> 
                                  2        P3E_OCP_CPU0_PE3_C_TXN<3>
C1R8             CAP_0402-0.22UF,16V,10%,X7R,A3A 1        P3E_CPU0_PE3_OCP_TXP<3> 
                                  2        P3E_OCP_CPU0_PE3_C_TXP<3>
C1R9             CAP_0402-0.22UF,16V,10%,X7R,A3A 1        P3E_CPU0_PE3_OCP_TXN<4> 
                                  2        P3E_OCP_CPU0_PE3_C_TXN<4>
C1R10            CAP_0402-0.22UF,16V,10%,X7R,A3A 1        P3E_CPU0_PE3_OCP_TXP<4> 
                                  2        P3E_OCP_CPU0_PE3_C_TXP<4>
C1R13            CAP_0603-10UF,6.3V,20%,X6S,E15A 1        P3V3_STBY               
                                  2        GND                     
C1R14            CAP_A_0402V-0.1UF,16V,10%,X7R,A 1        P3V3_STBY               
                                  2        GND                     
C1R15            CAP_A_0402V-0.1UF,16V,10%,X7R,A 1        P0V9_LAN                
                                  2        GND                     
C1R16            CAP_0603-10UF,6.3V,20%,X6S,E15A 1        P0V9_LAN                
                                  2        GND                     
C1R17            CAP_0603-10UF,6.3V,20%,X6S,E15A 1        P1V5_LAN                
                                  2        GND                     
C1R18            CAP_A_0402V-0.1UF,16V,10%,X7R,A 1        P0V9_LAN                
                                  2        GND                     
C1R19            CAP_A_0402V-0.1UF,16V,10%,X7R,A 1        P1V5_LAN                
                                  2        GND                     
C1R20            CAP_A_0402V-0.1UF,16V,10%,X7R,A 1        P3V3_STBY               
                                  2        GND                     
C1R21            CAP_A_0402V-0.1UF,16V,10%,X7R,A 1        P3V3_STBY               
                                  2        GND                     
C1R22            CAP_0603-10UF,6.3V,20%,X6S,E15A 1        P3V3_STBY               
                                  2        GND                     
C1R23            CAPP_3018-68UF,16V,20%,TANT,72A 1        P12V_STBY               
                                  2        GND                     
C1R24            CAP_A_0402V-0.1UF,16V,10%,X7R,A 1        P0V9_LAN                
                                  2        GND                     
C1R25            CAP_A_0402V-0.1UF,16V,10%,X7R,A 1        P3V3_STBY               
                                  2        GND                     
C1R26            CAP_A_0402V-0.1UF,16V,10%,X7R,A 1        P1V5_LAN                
                                  2        GND                     
C1R27            CAP_A_0402V-0.1UF,16V,10%,X7R,A 1        P3V3_STBY               
                                  2        GND                     
C1R28            CAP_A_0402V-0.1UF,16V,10%,X7R,A 1        P3V3_STBY               
                                  2        GND                     
C1R29            CAP_A_0402V-0.1UF,16V,10%,X7R,A 1        P1V5_LAN                
                                  2        GND                     
C1R30            CAP_0603-10UF,6.3V,20%,X6S,E15A 1        P1V5_LAN                
                                  2        GND                     
C1R31            CAP_A_0402V-0.1UF,16V,10%,X7R,A 1        P1V5_LAN                
                                  2        GND                     
C1T3             CAP_A_0402V-0.1UF,16V,10%,X7R,A 1        P3V3_STBY               
                                  2        GND                     
C1T4             CAP_0603-10UF,6.3V,20%,X6S,E15A 1        P0V9_LAN                
                                  2        GND                     
C1T5             CAP_A_0402V-0.1UF,16V,10%,X7R,A 1        P0V9_LAN                
                                  2        GND                     
C1T7             CAP_0603-10UF,6.3V,20%,X6S,E15A 1        P3V3_STBY               
                                  2        GND                     
C1T8             CAP_A_0402V-0.1UF,16V,10%,X7R,A 1        P3V3_STBY               
                                  2        GND                     
C1T9             CAP_0805-22UF,6.3V,20%,X6S,C95A 1        P3V3_STBY               
                                  2        GND                     
C1T10            CAP_A_0402V-0.1UF,16V,10%,X7R,A 1        P3V3_STBY               
                                  2        GND                     
C1T11            CAP_A_0402V-0.1UF,16V,10%,X7R,A 1        P3V3_STBY               
                                  2        GND                     
C1T12            CAP_A_0402V-1.0UF,6.3V,10%,X6SA 1        P3V3_STBY               
                                  2        GND                     
C1T13            CAP_0805-22UF,6.3V,20%,X6S,C95A 1        P3V3_STBY               
                                  2        GND                     
C1T14            CAP_A_0402V-0.1UF,16V,10%,X7R,A 1        P3V3_STBY               
                                  2        GND                     
C1T15            CAP_0603-10UF,6.3V,20%,X6S,E15A 1        P1V538_BMC_STBY         
                                  2        GND                     
C1T16            CAP_0603-10UF,6.3V,20%,EMPTY,EA 1        P1V8_BMC_STBY_PCIE      
                                  2        GND                     
C1T17            CAP_A_0402V-0.1UF,16V,10%,EMPTA 1        P1V8_BMC_STBY_PCIE      
                                  2        GND                     
C1T18            CAP_A_0402V-1.0UF,6.3V,10%,EMPA 1        P1V8_BMC_STBY_PCIE      
                                  2        GND                     
C1T19            CAP_A_0402V-1.0UF,6.3V,10%,X6SA 1        P3V3_STBY_BMC_HPLLAV33  
                                  2        GND                     
C1T20            CAP_0402LF-100.0PF,50V,5%,COG,A 1        P3V3_STBY_BMC_HPLLAV33  
                                  2        GND                     
C1T21            CAP_A_0402V-1.0UF,6.3V,10%,X6SA 1        PVCCIO_CPU0             
                                  2        GND                     
C1T22            CAP_A_0402V-0.1UF,16V,10%,X7R,A 1        P3V3_STBY               
                                  2        GND                     
C1T23            CAP_A_0402V-0.1UF,16V,10%,X7R,A 1        P3V3_STBY_BMC_HPLLAV33  
                                  2        GND                     
C1T24            CAP_A_0402V-0.01UF,25V,10%,X7RA 1        P1V26_BMC_STBY          
                                  2        GND                     
C1T25            CAP_A_0402V-0.1UF,16V,10%,X7R,A 1        P3V3_STBY               
                                  2        GND                     
C1T26            CAP_A_0402V-0.1UF,16V,10%,X7R,A 1        P3V3_STBY               
                                  2        GND                     
C1T27            CAP_A_0402V-0.01UF,25V,10%,X7RA 1        P1V26_BMC_STBY          
                                  2        GND                     
C1T28            CAP_A_0402V-1.0UF,6.3V,10%,X6SA 1        P1V26_BMC_STBY          
                                  2        GND                     
C1T29            CAP_A_0402V-0.1UF,16V,10%,X7R,A 1        P3V3_STBY               
                                  2        GND                     
C1T30            CAP_A_0402V-0.1UF,16V,10%,X7R,A 1        P3V3_STBY               
                                  2        GND                     
C1T31            CAP_A_0402V-1.0UF,6.3V,10%,X6SA 1        P1V538_BMC_STBY         
                                  2        GND                     
C1T32            CAP_A_0402V-1.0UF,6.3V,10%,X6SA 1        P1V538_BMC_STBY         
                                  2        GND                     
C1T33            CAP_A_0402V-0.1UF,16V,10%,X7R,A 1        P1V538_BMC_STBY         
                                  2        GND                     
C1T34            CAP_A_0402V-0.01UF,25V,10%,X7RA 1        P1V26_BMC_STBY          
                                  2        GND                     
C1T35            CAP_A_0402V-1.0UF,6.3V,10%,X6SA 1        P1V538_BMC_STBY         
                                  2        GND                     
C1T36            CAP_A_0402V-0.01UF,25V,10%,X7RA 1        P1V26_BMC_STBY          
                                  2        GND                     
C1T37            CAP_A_0402V-0.1UF,16V,10%,X7R,A 1        M_BMC_DDR3_MVREF        
                                  2        GND                     
C1T38            CAP_A_0402V-0.1UF,16V,10%,X7R,A 1        P3V3_STBY               
                                  2        GND                     
C1T39            CAP_A_0402V-0.01UF,25V,10%,X7RA 1        P1V538_BMC_STBY         
                                  2        M_BMC_DDR3_MVREF        
C1T40            CAP_A_0402V-0.1UF,16V,10%,X7R,A 1        P1V538_BMC_STBY         
                                  2        GND                     
C1T41            CAP_A_0402V-0.01UF,25V,10%,X7RA 1        M_BMC_DDR3_MVREF        
                                  2        GND                     
C1T42            CAP_0603-0.47UF,16V,10%,X7R,20A 1        P1V26_BMC_STBY          
                                  2        GND                     
C1T43            CAP_A_0402V-0.1UF,16V,10%,X7R,A 1        P3V3_STBY               
                                  2        GND                     
C1T44            CAP_0603-4.7UF,6.3V,10%,X6S,E1A 1        P3V3_STBY               
                                  2        GND                     
C1T45            CAP_A_0402V-0.1UF,16V,10%,X7R,A 1        P3V3_STBY               
                                  2        GND                     
C1T46            CAP_A_0402V-1.0UF,6.3V,10%,X6SA 1        P1V538_BMC_STBY         
                                  2        GND                     
C1T47            CAP_A_0402V-0.1UF,16V,10%,X7R,A 1        P3V3_STBY               
                                  2        GND                     
C1T48            CAP_A_0402V-0.1UF,16V,10%,X7R,A 1        M_BMC_DDR3_MVREF        
                                  2        GND                     
C1T49            CAP_A_0402V-1.0UF,6.3V,10%,X6SA 1        P1V538_BMC_STBY         
                                  2        GND                     
C1T50            CAP_A_0402V-0.1UF,16V,10%,X7R,A 1        P3V3_STBY               
                                  2        GND                     
C1T51            CAP_A_0402V-1.0UF,6.3V,10%,X6SA 1        M_BMC_DDR3_MVREF        
                                  2        GND                     
C1T52            CAP_A_0402V-0.1UF,16V,10%,X7R,A 1        P3V3_STBY               
                                  2        GND                     
C1T53            CAP_A_0402V-0.1UF,16V,10%,X7R,A 1        P1V538_BMC_STBY         
                                  2        GND                     
C1T54            CAP_A_0402V-0.1UF,16V,10%,X7R,A 1        P1V538_BMC_STBY         
                                  2        GND                     
C1T55            CAP_A_0402V-1.0UF,6.3V,10%,X6SA 1        P1V538_BMC_STBY         
                                  2        GND                     
C1T56            CAP_A_0402V-0.1UF,16V,10%,X7R,A 1        P3V3_STBY               
                                  2        GND                     
C1U1             CAP_0805-10UF,16V,10%,X6S,C953A 1        P1V26_BMC_STBY          
                                  2        GND                     
C1U2             CAP_0402LF-100.0PF,50V,5%,COG,A 1        P3V3_STBY               
                                  2        GND                     
C1U3             CAP_A_0402V-0.1UF,16V,10%,X7R,A 1        P3V3_STBY               
                                  2        GND                     
C1U4             CAP_A_0402V-0.1UF,16V,10%,X7R,A 1        P3V3_STBY               
                                  2        GND                     
C1U5             CAP_A_0402V-0.1UF,16V,10%,X7R,A 1        P3V3_STBY               
                                  2        GND                     
C1U6             CAP_A_0402V-1.0UF,6.3V,10%,X6SA 1        P1V26_BMC_STBY          
                                  2        GND                     
C1U7             CAP_A_0402V-1.0UF,6.3V,10%,X6SA 1        P1V26_BMC_STBY          
                                  2        GND                     
C1U8             CAP_A_0402V-1.0UF,6.3V,10%,X6SA 1        P3V3_STBY               
                                  2        GND                     
C1U9             CAP_A_0402V-0.1UF,16V,10%,X7R,A 1        P3V3_STBY               
                                  2        GND                     
C1U10            CAP_A_0402V-0.1UF,16V,10%,X7R,A 1        P1V538_BMC_STBY         
                                  2        GND                     
C1U11            CAP_A_0402V-0.1UF,16V,10%,X7R,A 1        P3V3_STBY               
                                  2        GND                     
C1U12            CAP_0805-10UF,16V,10%,X6S,C953A 1        P1V538_BMC_STBY         
                                  2        GND                     
C1U13            CAP_A_0402V-0.1UF,16V,10%,X7R,A 1        P1V538_BMC_STBY         
                                  2        GND                     
C1U14            CAP_A_0402V-0.1UF,16V,10%,X7R,A 1        P1V538_BMC_STBY         
                                  2        GND                     
C1U15            CAP_A_0402V-0.1UF,16V,10%,X7R,A 1        P1V538_BMC_STBY         
                                  2        GND                     
C1U16            CAP_A_0402V-0.1UF,16V,10%,X7R,A 1        P1V538_BMC_STBY         
                                  2        GND                     
C1U17            CAP_0402LF-100.0PF,50V,5%,COG,A 1        P3V3_STBY_BMC_ADCAV33   
                                  2        GND                     
C1U18            CAP_A_0402V-1.0UF,6.3V,10%,X6SA 1        P3V3_STBY_BMC_ADCAV33   
                                  2        GND                     
C1U19            CAP_0402-1.0UF,16V,10%,X6S,D97A 1        P3V3                    
                                  2        GND                     
C1U20            CAP_0805-10UF,16V,10%,X7R,G106A 1        P3V3_FB_ADC128_VCC      
                                  2        GND                     
C1U21            CAP_0402LF-47.0PF,50V,5%,COG,AA 1        A_P1V05_STBY_PCH_SENSOR 
                                  2        GND                     
C1U22            CAP_A_0402V-0.1UF,16V,10%,X7R,A 1        P0V7_GTL2014_2          
                                  2        GND                     
C2A1             CAP_A_0603V-22.0UF,4V,20%,X6S,A 1        PVDDQ_KLM               
                                  2        GND                     
C2A2             CAP_A_0603V-22.0UF,4V,20%,X6S,A 1        PVDDQ_KLM               
                                  2        GND                     
C2A3             CAP_A_0603V-22.0UF,4V,20%,X6S,A 1        PVDDQ_KLM               
                                  2        GND                     
C2A4             CAP_A_0603V-22.0UF,4V,20%,X6S,A 1        PVDDQ_KLM               
                                  2        GND                     
C2A5             CAP_A_0603V-47UF,4V,20%,X5R,60A 1        PVDDQ_KLM               
                                  2        GND                     
C2A6             CAP_A_0603V-22.0UF,4V,20%,X6S,A 1        PVDDQ_KLM               
                                  2        GND                     
C2A7             CAP_A_0603V-22.0UF,4V,20%,X6S,A 1        PVDDQ_KLM               
                                  2        GND                     
C2A8             CAP_0805-100UF,4V,20%,X5R,6024A 1        PVDDQ_KLM               
                                  2        GND                     
C2A9             CAP_A_0603V-22.0UF,4V,20%,X6S,A 1        PVDDQ_KLM               
                                  2        GND                     
C2A10            CAP_A_0603V-22.0UF,4V,20%,X6S,A 1        PVDDQ_KLM               
                                  2        GND                     
C2A11            CAP_A_0603V-22.0UF,4V,20%,X6S,A 1        PVDDQ_KLM               
                                  2        GND                     
C2A12            CAP_A_0603V-22.0UF,4V,20%,X6S,A 1        PVDDQ_KLM               
                                  2        GND                     
C2A13            CAP_A_0603V-22.0UF,4V,20%,X6S,A 1        PVDDQ_KLM               
                                  2        GND                     
C2A14            CAP_A_0603V-22.0UF,4V,20%,X6S,A 1        PVDDQ_KLM               
                                  2        GND                     
C2A15            CAP_A_0603V-22.0UF,4V,20%,X6S,A 1        PVDDQ_KLM               
                                  2        GND                     
C2A16            CAP_0805-100UF,4V,20%,X5R,6024A 1        PVDDQ_KLM               
                                  2        GND                     
C2B1             CAP_A_0603V-47UF,4V,20%,X5R,60A 1        PVDDQ_KLM               
                                  2        GND                     
C2B2             CAP_A_0603V-47UF,4V,20%,X5R,60A 1        PVDDQ_KLM               
                                  2        GND                     
C2D1             CAP_A_0603V-22.0UF,4V,20%,X6S,A 1        PVCCIN_CPU1             
                                  2        GND                     
C2D2             CAP_A_0603V-22.0UF,4V,20%,X6S,A 1        PVCCIN_CPU1             
                                  2        GND                     
C2D3             CAP_A_0603V-22.0UF,4V,20%,X6S,A 1        PVCCIN_CPU1             
                                  2        GND                     
C2D4             CAP_0603LF-10UF,4V,20%,X6S,E15A 1        PVDDQ_KLM               
                                  2        GND                     
C2D5             CAP_0603LF-10UF,4V,20%,X6S,E15A 1        PVDDQ_KLM               
                                  2        GND                     
C2D6             CAP_0603LF-10UF,4V,20%,X6S,E15A 1        PVDDQ_KLM               
                                  2        GND                     
C2D7             CAP_0603LF-10UF,4V,20%,X6S,E15A 1        PVDDQ_KLM               
                                  2        GND                     
C2D8             CAP_0603LF-10UF,4V,20%,X6S,E15A 1        PVSA_CPU1               
                                  2        GND                     
C2D9             CAP_0603LF-10UF,4V,20%,X6S,E15A 1        PVSA_CPU1               
                                  2        GND                     
C2D10            CAP_0603LF-10UF,4V,20%,X6S,E15A 1        PVSA_CPU1               
                                  2        GND                     
C2D11            CAP_0603LF-10UF,4V,20%,X6S,E15A 1        PVSA_CPU1               
                                  2        GND                     
C2D12            CAP_A_0603V-22.0UF,4V,20%,X6S,A 1        PVCCIN_CPU1             
                                  2        GND                     
C2D13            CAP_A_0603V-22.0UF,4V,20%,X6S,A 1        PVCCIN_CPU1             
                                  2        GND                     
C2D14            CAP_A_0603V-22.0UF,4V,20%,X6S,A 1        PVCCIN_CPU1             
                                  2        GND                     
C2D15            CAP_A_0603V-22.0UF,4V,20%,X6S,A 1        PVCCIN_CPU1             
                                  2        GND                     
C2D16            CAP_A_0603V-22.0UF,4V,20%,X6S,A 1        PVCCIN_CPU1             
                                  2        GND                     
C2D17            CAP_A_0603V-22.0UF,4V,20%,X6S,A 1        PVCCIN_CPU1             
                                  2        GND                     
C2D18            CAP_A_0603V-22.0UF,4V,20%,X6S,A 1        PVCCMCP_CPU1            
                                  2        GND                     
C2D19            CAP_A_0603V-22.0UF,4V,20%,X6S,A 1        PVCCIN_CPU1             
                                  2        GND                     
C2D20            CAP_A_0603V-22.0UF,4V,20%,X6S,A 1        PVCCIN_CPU1             
                                  2        GND                     
C2D21            CAP_A_0603V-22.0UF,4V,20%,X6S,A 1        PVCCIN_CPU1             
                                  2        GND                     
C2D22            CAP_A_0603V-22.0UF,4V,20%,X6S,A 1        PVCCIN_CPU1             
                                  2        GND                     
C2D23            CAP_A_0603V-22.0UF,4V,20%,X6S,A 1        PVCCIN_CPU1             
                                  2        GND                     
C2D24            CAP_A_0603V-22.0UF,4V,20%,X6S,A 1        PVCCIN_CPU1             
                                  2        GND                     
C2D25            CAP_A_0603V-22.0UF,4V,20%,X6S,A 1        PVCCIN_CPU1             
                                  2        GND                     
C2D26            CAP_A_0603V-22.0UF,4V,20%,X6S,A 1        PVCCIN_CPU1             
                                  2        GND                     
C2D27            CAP_A_0603V-22.0UF,4V,20%,X6S,A 1        PVCCIN_CPU1             
                                  2        GND                     
C2D28            CAP_A_0603V-22.0UF,4V,20%,X6S,A 1        PVCCMCP_CPU1            
                                  2        GND                     
C2D29            CAP_A_0603V-22.0UF,4V,20%,X6S,A 1        PVCCMCP_CPU1            
                                  2        GND                     
C2D30            CAP_A_0603V-22.0UF,4V,20%,X6S,A 1        PVCCIN_CPU1             
                                  2        GND                     
C2D31            CAP_A_0603V-22.0UF,4V,20%,X6S,A 1        PVCCIN_CPU1             
                                  2        GND                     
C2D32            CAP_A_0603V-22.0UF,4V,20%,X6S,A 1        PVCCIN_CPU1             
                                  2        GND                     
C2D33            CAP_A_0603V-22.0UF,4V,20%,X6S,A 1        PVCCIN_CPU1             
                                  2        GND                     
C2D34            CAP_A_0603V-22.0UF,4V,20%,X6S,A 1        PVCCIN_CPU1             
                                  2        GND                     
C2D35            CAP_A_0603V-22.0UF,4V,20%,X6S,A 1        PVCCIN_CPU1             
                                  2        GND                     
C2D36            CAP_A_0603V-22.0UF,4V,20%,X6S,A 1        PVCCIN_CPU1             
                                  2        GND                     
C2D37            CAP_A_0603V-22.0UF,4V,20%,X6S,A 1        PVCCIN_CPU1             
                                  2        GND                     
C2D38            CAP_A_0603V-22.0UF,4V,20%,X6S,A 1        PVCCIN_CPU1             
                                  2        GND                     
C2D39            CAP_A_0603V-22.0UF,4V,20%,X6S,A 1        PVCCMCP_CPU1            
                                  2        GND                     
C2D40            CAP_A_0603V-22.0UF,4V,20%,X6S,A 1        PVCCMCP_CPU1            
                                  2        GND                     
C2D41            CAP_0603LF-10UF,4V,20%,X6S,E15A 1        PVDDQ_GHJ               
                                  2        GND                     
C2D42            CAP_0603LF-10UF,4V,20%,X6S,E15A 1        PVDDQ_GHJ               
                                  2        GND                     
C2D43            CAP_0603LF-10UF,4V,20%,X6S,E15A 1        PVDDQ_GHJ               
                                  2        GND                     
C2D44            CAP_0603LF-10UF,4V,20%,X6S,E15A 1        PVDDQ_GHJ               
                                  2        GND                     
C2D45            CAP_A_0603V-22.0UF,4V,20%,X6S,A 1        PVCCIN_CPU1             
                                  2        GND                     
C2D46            CAP_A_0603V-22.0UF,4V,20%,X6S,A 1        PVCCIN_CPU1             
                                  2        GND                     
C2D47            CAP_A_0603V-22.0UF,4V,20%,X6S,A 1        PVCCIN_CPU1             
                                  2        GND                     
C2F1             CAP_A_0603V-47UF,4V,20%,X5R,60A 1        PVDDQ_GHJ               
                                  2        GND                     
C2F2             CAP_A_0603V-47UF,4V,20%,X5R,60A 1        PVTT_GHJ                
                                  2        GND                     
C2G1             CAP_A_0603V-22.0UF,4V,20%,X6S,A 1        PVDDQ_GHJ               
                                  2        GND                     
C2G2             CAP_A_0603V-22.0UF,4V,20%,X6S,A 1        PVDDQ_GHJ               
                                  2        GND                     
C2G3             CAP_A_0603V-22.0UF,4V,20%,X6S,A 1        PVDDQ_GHJ               
                                  2        GND                     
C2G4             CAP_A_0603V-22.0UF,4V,20%,X6S,A 1        PVDDQ_GHJ               
                                  2        GND                     
C2G5             CAP_A_0603V-22.0UF,4V,20%,X6S,A 1        PVDDQ_GHJ               
                                  2        GND                     
C2G6             CAP_A_0603V-22.0UF,4V,20%,X6S,A 1        PVDDQ_GHJ               
                                  2        GND                     
C2G7             CAP_0805-100UF,4V,20%,X5R,6024A 1        PVDDQ_GHJ               
                                  2        GND                     
C2G8             CAP_A_0603V-47UF,4V,20%,X5R,60A 1        PVDDQ_GHJ               
                                  2        GND                     
C2G9             CAP_A_0603V-22.0UF,4V,20%,X6S,A 1        PVDDQ_GHJ               
                                  2        GND                     
C2G10            CAP_A_0603V-22.0UF,4V,20%,X6S,A 1        PVDDQ_GHJ               
                                  2        GND                     
C2G11            CAP_A_0603V-22.0UF,4V,20%,X6S,A 1        PVDDQ_GHJ               
                                  2        GND                     
C2G12            CAP_A_0603V-22.0UF,4V,20%,X6S,A 1        PVDDQ_GHJ               
                                  2        GND                     
C2G13            CAP_A_0603V-22.0UF,4V,20%,X6S,A 1        PVDDQ_GHJ               
                                  2        GND                     
C2G14            CAP_A_0603V-22.0UF,4V,20%,X6S,A 1        PVDDQ_GHJ               
                                  2        GND                     
C2G15            CAP_A_0603V-47UF,4V,20%,X5R,60A 1        PVDDQ_GHJ               
                                  2        GND                     
C2G16            CAP_0805-100UF,4V,20%,X5R,6024A 1        PVDDQ_GHJ               
                                  2        GND                     
C2L2             CAP_0402LF-220PF,50V,10%,X7R,AA 1        VR_P1V05_PCH_STBY_AVSP  
                                  2        VSENSE_P1V05_PCH_STBY_AVSN
C2L3             CAP_A_0402V-0.01UF,25V,10%,X7RA 1        SATA6G_PCH_PCIE_UP_SATA_RXN<3>
                                  2        SATA6G_P3_RX_C_DN       
C2L4             CAP_A_0402V-0.01UF,25V,10%,X7RA 1        SATA6G_PCH_PCIE_UP_SATA_RXP<3>
                                  2        SATA6G_P3_RX_C_DP       
C2L5             CAP_A_0402V-0.01UF,25V,10%,X7RA 1        SATA6G_PCH_PCIE_UP_SATA_RXN<7>
                                  2        SATA6G_P7_RX_C_DN       
C2L6             CAP_A_0402V-0.01UF,25V,10%,X7RA 1        SATA6G_PCH_PCIE_UP_SATA_RXN<1>
                                  2        SATA6G_P1_RX_C_DN       
C2L7             CAP_A_0402V-0.01UF,25V,10%,X7RA 1        SATA6G_PCH_PCIE_UP_SATA_RXP<7>
                                  2        SATA6G_P7_RX_C_DP       
C2L8             CAP_A_0402V-1.0UF,6.3V,10%,X6SA 1        VR_PVNN_PCH_VDD         
                                  2        GND                     
C2L9             CAP_A_0402V-0.01UF,25V,10%,X7RA 1        SATA6G_PCH_PCIE_UP_SATA_RXN<5>
                                  2        SATA6G_P5_RX_C_DN       
C2L10            CAP_A_0402V-0.01UF,25V,10%,X7RA 1        SATA6G_PCH_PCIE_UP_SATA_RXP<1>
                                  2        SATA6G_P1_RX_C_DP       
C2L11            CAP_A_0402V-0.1UF,16V,10%,X7R,A 1        VR_PVNN_PCH_VDD         
                                  2        GND                     
C2L12            CAP_A_0402V-0.01UF,25V,10%,X7RA 1        SATA6G_PCH_PCIE_UP_SATA_RXP<5>
                                  2        SATA6G_P5_RX_C_DP       
C2L13            CAP_A_0402V-0.01UF,25V,10%,X7RA 1        SATA6G_PCH_PCIE_UP_SATA_RXN<2>
                                  2        SATA6G_P2_RX_C_DN       
C2L14            CAP_A_0402V-0.01UF,25V,10%,X7RA 1        SATA6G_PCH_PCIE_UP_SATA_RXN<6>
                                  2        SATA6G_P6_RX_C_DN       
C2L15            CAP_A_0402V-0.01UF,25V,10%,X7RA 1        SATA6G_PCH_PCIE_UP_SATA_RXP<2>
                                  2        SATA6G_P2_RX_C_DP       
C2L16            CAP_A_0402V-0.01UF,25V,10%,X7RA 1        SATA6G_PCH_PCIE_UP_SATA_RXP<6>
                                  2        SATA6G_P6_RX_C_DP       
C2L17            CAP_A_0402V-0.01UF,25V,10%,X7RA 1        SATA6G_PCH_PCIE_UP_SATA_RXN<0>
                                  2        SATA6G_P0_RX_C_DN       
C2L18            CAP_A_0402V-0.01UF,25V,10%,X7RA 1        SATA6G_PCH_PCIE_UP_SATA_RXN<4>
                                  2        SATA6G_P4_RX_C_DN       
C2L19            CAP_A_0402V-0.01UF,25V,10%,X7RA 1        SATA6G_PCH_PCIE_UP_SATA_RXP<0>
                                  2        SATA6G_P0_RX_C_DP       
C2L20            CAP_A_0402V-0.01UF,25V,10%,X7RA 1        SATA6G_PCH_PCIE_UP_SATA_RXP<4>
                                  2        SATA6G_P4_RX_C_DP       
C2L21            CAP_A_0402V-0.01UF,25V,10%,X7RA 1        SATA6G_P7_TX_C_DN       
                                  2        SATA6G_PCH_PCIE_UP_SATA_TXN<7>
C2L22            CAP_A_0402V-0.01UF,25V,10%,X7RA 1        SATA6G_P3_TX_C_DN       
                                  2        SATA6G_PCH_PCIE_UP_SATA_TXN<3>
C2L23            CAP_A_0402V-0.01UF,25V,10%,X7RA 1        SATA6G_P3_TX_C_DP       
                                  2        SATA6G_PCH_PCIE_UP_SATA_TXP<3>
C2L24            CAP_A_0402V-0.01UF,25V,10%,X7RA 1        SATA6G_P7_TX_C_DP       
                                  2        SATA6G_PCH_PCIE_UP_SATA_TXP<7>
C2L25            CAPP_SM-470UF,2V,20%,ALUM,6990A 1        P1V05_PCH_STBY          
                                  2        GND                     
C2L26            CAP_A_0402V-0.01UF,25V,10%,X7RA 1        SATA6G_P5_TX_C_DN       
                                  2        SATA6G_PCH_PCIE_UP_SATA_TXN<5>
C2L27            CAP_A_0402V-0.01UF,25V,10%,X7RA 1        SATA6G_P5_TX_C_DP       
                                  2        SATA6G_PCH_PCIE_UP_SATA_TXP<5>
C2L28            CAP_A_0402V-0.01UF,25V,10%,X7RA 1        SATA6G_RX_DP<1>         
                                  2        SATA6G_P9_RX_C_DP       
C2L29            CAP_A_0402V-0.01UF,25V,10%,X7RA 1        SATA6G_RX_DN<1>         
                                  2        SATA6G_P9_RX_C_DN       
C2L30            CAP_A_0402V-0.01UF,25V,10%,X7RA 1        SATA6G_RX_DP<0>         
                                  2        SATA6G_P8_RX_C_DP       
C2L31            CAP_A_0402V-0.01UF,25V,10%,X7RA 1        SATA6G_RX_DN<0>         
                                  2        SATA6G_P8_RX_C_DN       
C2L32            CAP_0805-47UF,4V,20%,X6S,C9533A 1        P1V8_PCH_STBY           
                                  2        GND                     
C2L33            CAP_A_0402V-0.01UF,25V,10%,X7RA 1        SATA6G_RX_DP<3>         
                                  2        SATA6G_P11_RX_C_DP      
C2L34            CAP_A_0402V-0.01UF,25V,10%,X7RA 1        SATA6G_RX_DN<3>         
                                  2        SATA6G_P11_RX_C_DN      
C2L35            CAP_A_0402V-0.01UF,25V,10%,X7RA 1        SATA6G_RX_DP<2>         
                                  2        SATA6G_P10_RX_C_DP      
C2L36            CAP_A_0402V-0.01UF,25V,10%,X7RA 1        SATA6G_RX_DN<2>         
                                  2        SATA6G_P10_RX_C_DN      
C2L37            CAP_A_0402V-0.01UF,25V,10%,X7RA 1        SATA6G_P4_TX_C_DN       
                                  2        SATA6G_PCH_PCIE_UP_SATA_TXN<4>
C2L38            CAP_A_0402V-0.01UF,25V,10%,X7RA 1        SATA6G_P6_TX_C_DN       
                                  2        SATA6G_PCH_PCIE_UP_SATA_TXN<6>
C2L39            CAP_A_0402V-0.01UF,25V,10%,X7RA 1        SATA6G_P0_TX_C_DP       
                                  2        SATA6G_PCH_PCIE_UP_SATA_TXP<0>
C2L40            CAP_A_0402V-0.01UF,25V,10%,X7RA 1        SATA6G_P0_TX_C_DN       
                                  2        SATA6G_PCH_PCIE_UP_SATA_TXN<0>
C2L41            CAP_A_0402V-0.01UF,25V,10%,X7RA 1        SATA6G_P2_TX_C_DP       
                                  2        SATA6G_PCH_PCIE_UP_SATA_TXP<2>
C2L42            CAP_A_0402V-0.01UF,25V,10%,X7RA 1        SATA6G_P2_TX_C_DN       
                                  2        SATA6G_PCH_PCIE_UP_SATA_TXN<2>
C2L43            CAP_A_0402V-0.01UF,25V,10%,X7RA 1        SATA6G_P1_TX_C_DP       
                                  2        SATA6G_PCH_PCIE_UP_SATA_TXP<1>
C2L44            CAP_A_0402V-0.01UF,25V,10%,X7RA 1        SATA6G_P1_TX_C_DN       
                                  2        SATA6G_PCH_PCIE_UP_SATA_TXN<1>
C2L45            CAP_0805-22UF,6.3V,20%,X6S,C95A 1        P1V8_PCH_STBY           
                                  2        GND                     
C2L46            CAPP_SM-470UF,2V,20%,ALUM,6990A 1        P1V05_PCH_STBY          
                                  2        GND                     
C2L47            CAP_A_0402V-0.01UF,25V,10%,X7RA 1        SATA6G_P4_TX_C_DP       
                                  2        SATA6G_PCH_PCIE_UP_SATA_TXP<4>
C2L48            CAP_A_0402V-0.01UF,25V,10%,X7RA 1        SATA6G_P6_TX_C_DP       
                                  2        SATA6G_PCH_PCIE_UP_SATA_TXP<6>
C2L49            CAP_A_0402V-0.01UF,25V,10%,X7RA 1        SATA6G_S1_RX_C_DP       
                                  2        SATA6G_S1_RX_DP         
C2L50            CAP_A_0402V-0.01UF,25V,10%,X7RA 1        SATA6G_S1_RX_C_DN       
                                  2        SATA6G_S1_RX_DN         
C2L51            CAP_A_0402V-0.01UF,25V,10%,X7RA 1        SATA6G_S1_TX_C_DN       
                                  2        SATA6G_S1_TX_DN         
C2L52            CAP_A_0402V-0.01UF,25V,10%,X7RA 1        SATA6G_S1_TX_C_DP       
                                  2        SATA6G_S1_TX_DP         
C2M1             CAP_A_0603V-22.0UF,4V,20%,X6S,A 1        P1V8_PCH_STBY           
                                  2        GND                     
C2M2             CAP_A_0603V-22.0UF,4V,20%,X6S,A 1        P1V8_PCH_STBY           
                                  2        GND                     
C2M3             CAP_A_0402V-0.1UF,16V,10%,EMPTA 1        P2E_SSB_BMC_TX_DN       
                                  2        P2E_SSB_BMC_TX_C_DN     
C2M4             CAP_A_0402V-0.1UF,16V,10%,EMPTA 1        P2E_SSB_BMC_TX_DP       
                                  2        P2E_SSB_BMC_TX_C_DP     
C2M5             CAP_0603LF-10UF,4V,20%,X6S,E15A 1        P1V05_PCH_STBY_WM20_PLL 
                                  2        GND                     
C2M6             CAP_A_0402V-1.0UF,6.3V,10%,X6SA 1        P1V05_PCH_STBY          
                                  2        GND                     
C2M7             CAP_A_0402V-1.0UF,6.3V,10%,X6SA 1        P1V05_PCH_STBY_WM20_PLL 
                                  2        GND                     
C2M8             CAP_A_0402V-1.0UF,6.3V,10%,X6SA 1        P1V05_PCH_STBY          
                                  2        GND                     
C2M9             CAP_A_0402V-1.0UF,6.3V,10%,X6SA 1        P1V05_PCH_STBY_WM26_PLL 
                                  2        GND                     
C2M10            CAP_0603LF-10UF,4V,20%,X6S,E15A 1        P1V05_PCH_STBY_WM26_PLL 
                                  2        GND                     
C2M11            CAP_0805-47UF,4V,20%,X6S,C9533A 1        P1V05_PCH_STBY          
                                  2        GND                     
C2M12            CAP_A_0603V-22.0UF,4V,20%,X6S,A 1        P1V05_PCH_STBY          
                                  2        GND                     
C2M13            CAP_A_0603V-22.0UF,4V,20%,X6S,A 1        P1V05_PCH_STBY          
                                  2        GND                     
C2M14            CAP_0402-0.22UF,16V,10%,X7R,A3A 1        P3E_CPU0_PE3_OCP_TXP<8> 
                                  2        P3E_OCP_CPU0_PE3_C_TXP<8>
C2M15            CAP_0402-0.22UF,16V,10%,X7R,A3A 1        P3E_CPU0_PE3_OCP_TXN<8> 
                                  2        P3E_OCP_CPU0_PE3_C_TXN<8>
C2M16            CAP_A_0402V-1.0UF,6.3V,10%,X6SA 1        P3V3_STBY               
                                  2        GND                     
C2M17            CAP_0805-47UF,4V,20%,X6S,C9533A 1        P1V05_PCH_STBY          
                                  2        GND                     
C2M18            CAP_A_0402V-1.0UF,6.3V,10%,X6SA 1        P1V05_PCH_STBY          
                                  2        GND                     
C2M19            CAP_A_0402V-1.0UF,6.3V,10%,X6SA 1        P1V05_PCH_STBY          
                                  2        GND                     
C2M20            CAP_A_0402V-1.0UF,6.3V,10%,X6SA 1        P1V05_PCH_STBY          
                                  2        GND                     
C2M21            CAP_A_0402V-1.0UF,6.3V,10%,X6SA 1        P1V05_PCH_STBY          
                                  2        GND                     
C2M22            CAP_A_0402V-1.0UF,6.3V,10%,X6SA 1        P1V05_PCH_STBY          
                                  2        GND                     
C2M23            CAP_A_0402V-0.1UF,16V,10%,X7R,A 1        PE_PCH_SPRV_TX_DP       
                                  2        PE_PCH_SPRV_TX_C_DP     
C2M24            CAP_A_0402V-0.1UF,16V,10%,X7R,A 1        PE_PCH_SPRV_TX_DN       
                                  2        PE_PCH_SPRV_TX_C_DN     
C2M25            CAP_A_0402V-1.0UF,6.3V,10%,X6SA 1        P1V05_PCH_STBY          
                                  2        GND                     
C2N2             CAP_A_0402V-1.0UF,6.3V,10%,X6SA 1        P1V05_PCH_STBY          
                                  2        GND                     
C2N3             CAP_A_0402V-1.0UF,6.3V,10%,X6SA 1        PVNN_PCH_STBY           
                                  2        GND                     
C2N4             CAP_A_0402V-1.0UF,6.3V,10%,X6SA 1        PVNN_PCH_STBY           
                                  2        GND                     
C2N5             CAP_A_0402V-1.0UF,6.3V,10%,X6SA 1        P1V05_PCH_STBY_KR_PLL   
                                  2        GND                     
C2N6             CAP_0603LF-10UF,4V,20%,X6S,E15A 1        P1V05_PCH_STBY_KR_PLL   
                                  2        GND                     
C2N7             CAP_A_0402V-1.0UF,6.3V,10%,X6SA 1        P1V05_PCH_STBY          
                                  2        GND                     
C2N8             CAP_A_0402V-1.0UF,6.3V,10%,X6SA 1        P1V05_PCH_STBY          
                                  2        GND                     
C2N9             CAP_A_0402V-1.0UF,6.3V,10%,X6SA 1        PVNN_PCH_STBY           
                                  2        GND                     
C2N10            CAP_A_0603V-22.0UF,4V,20%,X6S,A 1        P1V05_PCH_STBY          
                                  2        GND                     
C2N11            CAP_A_0402V-1.0UF,6.3V,10%,X6SA 1        PVNN_PCH_STBY           
                                  2        GND                     
C2N12            CAP_A_0402V-1.0UF,6.3V,10%,X6SA 1        PVNN_PCH_STBY           
                                  2        GND                     
C2N13            CAP_A_0402V-1.0UF,6.3V,10%,X6SA 1        P1V05_PCH_STBY          
                                  2        GND                     
C2N14            CAP_0603-10UF,6.3V,20%,X6S,E15A 1        P3V3_STBY               
                                  2        GND                     
C2N15            CAP_A_0402V-1.0UF,6.3V,10%,X6SA 1        P1V8_PCH_STBY           
                                  2        GND                     
C2N16            CAP_A_0402V-1.0UF,6.3V,10%,X6SA 1        P1V8_PCH_STBY           
                                  2        GND                     
C2N17            CAP_0603-10UF,6.3V,20%,X6S,E15A 1        P3V3_STBY               
                                  2        GND                     
C2N18            CAP_A_0402V-1.0UF,6.3V,10%,X6SA 1        P3V3_STBY               
                                  2        GND                     
C2N19            CAP_A_0402V-1.0UF,6.3V,10%,X6SA 1        P3V3_STBY               
                                  2        GND                     
C2N20            CAP_A_0402V-1.0UF,6.3V,10%,X6SA 1        P3V3_STBY               
                                  2        GND                     
C2N21            CAP_0603-10UF,6.3V,20%,X6S,E15A 1        P3V3_STBY               
                                  2        GND                     
C2N22            CAP_0603-10UF,6.3V,20%,X6S,E15A 1        P3V3_STBY               
                                  2        GND                     
C2N23            CAP_0603-10UF,6.3V,20%,X6S,E15A 1        P3V3_STBY               
                                  2        GND                     
C2N24            CAP_0603-10UF,6.3V,20%,X6S,E15A 1        P3V3_STBY               
                                  2        GND                     
C2N25            CAP_A_0402V-1.0UF,6.3V,10%,X6SA 1        P3V3_STBY               
                                  2        GND                     
C2N26            CAP_A_0402V-1.0UF,6.3V,10%,X6SA 1        P3V3_STBY               
                                  2        GND                     
C2P1             CAP_A_0402V-0.1UF,16V,10%,X7R,A 1        P3V3_STBY               
                                  2        GND                     
C2P2             CAP_A_0402V-0.1UF,16V,10%,X7R,A 1        P3V3_STBY               
                                  2        GND                     
C2P3             CAP_A_0402V-0.1UF,16V,10%,X7R,A 1        P3V3_STBY               
                                  2        GND                     
C2P4             CAP_A_0402V-0.1UF,16V,10%,X7R,A 1        P3V3_STBY               
                                  2        GND                     
C2P5             CAP_A_0402V-0.1UF,16V,10%,X7R,A 1        P3V3_STBY               
                                  2        GND                     
C2P6             CAP_A_0402V-0.1UF,16V,10%,X7R,A 1        P3V3_STBY               
                                  2        GND                     
C2P7             CAP_A_0402V-0.1UF,16V,10%,X7R,A 1        P3V3_STBY               
                                  2        GND                     
C2P8             CAP_A_0402V-0.01UF,25V,10%,X7RA 1        P3V3_STBY               
                                  2        GND                     
C2P9             CAP_A_0402V-0.1UF,16V,10%,X7R,A 1        P3V3_STBY               
                                  2        GND                     
C2P10            CAP_1206LF-22UF,16V,10%,X6S,D3A 1        P12V_STBY               
                                  2        GND                     
C2P11            CAP_A_0402V-0.1UF,16V,10%,X7R,A 1        P12V_STBY               
                                  2        GND                     
C2P12            CAP_A_0402V-0.1UF,16V,10%,X7R,A 1        P12V_STBY               
                                  2        GND                     
C2P13            CAP_A_0402V-0.1UF,16V,10%,X7R,A 1        P12V_STBY               
                                  2        GND                     
C2P14            CAP_A_0402V-0.1UF,16V,10%,X7R,A 1        P12V_STBY               
                                  2        GND                     
C2P15            CAP_A_0402V-0.1UF,16V,10%,X7R,A 1        P12V_STBY               
                                  2        GND                     
C2P16            CAP_A_0402V-0.1UF,16V,10%,X7R,A 1        P12V_STBY               
                                  2        GND                     
C2R1             CAP_A_0402V-0.1UF,16V,10%,X7R,A 1        P3V3_STBY               
                                  2        GND                     
C2R2             CAP_A_0402V-0.1UF,16V,10%,X7R,A 1        P3V3_STBY               
                                  2        GND                     
C2R3             CAP_A_0402V-0.1UF,16V,10%,X7R,A 1        P3V3_STBY               
                                  2        GND                     
C2R4             CAP_A_0402V-0.1UF,16V,10%,X7R,A 1        P3V3_STBY               
                                  2        GND                     
C2R5             CAP_A_0402V-0.1UF,16V,10%,X7R,A 1        P3V3_STBY               
                                  2        GND                     
C2R6             CAP_0402LF-470PF,50V,10%,EMPTYA 1        FM_PS_EN                
                                  2        GND                     
C2R7             CAP_0402-0.22UF,16V,10%,X7R,A3A 1        P3E_CPU0_PE3_OCP_TXN<6> 
                                  2        P3E_OCP_CPU0_PE3_C_TXN<6>
C2R8             CAP_0402-0.22UF,16V,10%,X7R,A3A 1        P3E_CPU0_PE3_OCP_TXP<6> 
                                  2        P3E_OCP_CPU0_PE3_C_TXP<6>
C2R9             CAP_0402-0.22UF,16V,10%,X7R,A3A 1        P3E_CPU0_PE3_OCP_TXN<7> 
                                  2        P3E_OCP_CPU0_PE3_C_TXN<7>
C2R10            CAP_0402-0.22UF,16V,10%,X7R,A3A 1        P3E_CPU0_PE3_OCP_TXP<7> 
                                  2        P3E_OCP_CPU0_PE3_C_TXP<7>
C2R11            CAP_0603-4.7UF,6.3V,10%,X6S,E1A 1        P5V_STBY                
                                  2        AGND_P3V3_STBY          
C2R12            CAP_A_0402V-1.0UF,6.3V,10%,X6SA 1        FP_NMI_BTN_OUT_N        
                                  2        GND                     
C2R13            CAP_0402-0.22UF,16V,10%,X7R,A3A 1        P3E_CPU0_PE3_OCP_TXN<5> 
                                  2        P3E_OCP_CPU0_PE3_C_TXN<5>
C2R14            CAP_0402-0.22UF,16V,10%,X7R,A3A 1        P3E_CPU0_PE3_OCP_TXP<5> 
                                  2        P3E_OCP_CPU0_PE3_C_TXP<5>
C2R15            CAP_A_0402V-0.1UF,16V,10%,X7R,A 1        P12V_STBY               
                                  2        GND                     
C2R16            CAP_A_0402V-0.1UF,16V,10%,X7R,A 1        P12V_STBY               
                                  2        GND                     
C2R17            CAP_A_0402V-0.1UF,16V,10%,X7R,A 1        P12V_STBY               
                                  2        GND                     
C2R18            CAP_A_0402V-0.1UF,16V,10%,X7R,A 1        P12V_STBY               
                                  2        GND                     
C2T1             CAP_A_0402V-0.1UF,16V,10%,X7R,A 1        P3V3_STBY               
                                  2        GND                     
C2T2             CAP_A_0402V-0.1UF,16V,10%,X7R,A 1        P3V3                    
                                  2        GND                     
C2T3             CAP_A_0402V-0.1UF,16V,10%,X7R,A 1        P3V3_STBY               
                                  2        GND                     
C2T4             CAP_A_0402V-0.1UF,16V,10%,X7R,A 1        P3V3                    
                                  2        GND                     
C2T5             CAP_A_0402V-0.1UF,16V,10%,X7R,A 1        P3V3                    
                                  2        GND                     
C2T6             CAP_0805-22UF,6.3V,20%,X6S,C95A 1        P3V3_STBY               
                                  2        GND                     
C2T7             CAP_0805-22UF,6.3V,20%,X6S,C95A 1        P3V3_STBY               
                                  2        GND                     
C2T8             CAP_A_0402V-0.1UF,16V,10%,X7R,A 1        P3V3_STBY               
                                  2        GND                     
C2T9             CAP_0805-22UF,6.3V,20%,X6S,C95A 1        P3V3_STBY               
                                  2        GND                     
C2T10            CAP_0402-0.22UF,16V,10%,X7R,A3A 1        P3E_PCH_M2_TX_C_DP<1>   
                                  2        P3E_PCH_M2_TX_DP<1>     
C2T11            CAP_0402-0.22UF,16V,10%,X7R,A3A 1        P3E_PCH_M2_TX_C_DN<1>   
                                  2        P3E_PCH_M2_TX_DN<1>     
C2T12            CAP_A_0402V-0.1UF,16V,10%,X7R,A 1        P3V3_STBY               
                                  2        GND                     
C2T13            CAP_0402-0.22UF,16V,10%,X7R,A3A 1        P3E_PCH_M2_TX_C_DP<2>   
                                  2        P3E_PCH_M2_TX_DP<2>     
C2T14            CAP_0402-0.22UF,16V,10%,X7R,A3A 1        P3E_PCH_M2_TX_C_DN<2>   
                                  2        P3E_PCH_M2_TX_DN<2>     
C2T15            CAP_A_0402V-0.1UF,16V,10%,X7R,A 1        P3V3                    
                                  2        GND                     
C2T16            CAP_A_0402V-0.1UF,16V,10%,X7R,A 1        P3V3                    
                                  2        GND                     
C2T17            CAP_A_0402V-0.1UF,16V,10%,X7R,A 1        P3V3_STBY_MNG           
                                  2        GND                     
C2T18            CAP_A_0402V-0.01UF,25V,10%,X7RA 1        P3V3_STBY_MNG_CPU       
                                  2        GND                     
C2T19            CAP_A_0402V-1.0UF,6.3V,10%,X6SA 1        P3V3_STBY_MNG_CPU       
                                  2        GND                     
C2T20            CAP_0402-0.22UF,16V,10%,X7R,A3A 1        P3E_PCH_M2_TX_C_DP<3>   
                                  2        P3E_PCH_M2_TX_DP<3>     
C2T21            CAP_A_0402V-0.1UF,16V,10%,X7R,A 1        P3V3                    
                                  2        GND                     
C2T22            CAP_0805-10UF,16V,10%,X6S,C953A 1        P3V3_STBY_MNG           
                                  2        GND                     
C2T23            CAP_0402-0.22UF,16V,10%,X7R,A3A 1        P3E_PCH_M2_TX_C_DN<3>   
                                  2        P3E_PCH_M2_TX_DN<3>     
C2T24            CAP_A_0402V-0.1UF,16V,10%,X7R,A 1        P3V3                    
                                  2        GND                     
C2T25            CAP_A_0402V-0.1UF,16V,10%,X7R,A 1        P3V3_STBY_MNG           
                                  2        GND                     
C2T26            CAP_A_0402V-0.1UF,16V,10%,X7R,A 1        P3V3                    
                                  2        GND                     
C2T27            CAP_A_0402V-0.01UF,25V,10%,X7RA 1        P3V3_STBY_MNG_RGMII     
                                  2        GND                     
C2T28            CAP_A_0402V-1.0UF,6.3V,10%,X6SA 1        P3V3_STBY               
                                  2        GND                     
C2T29            CAP_A_0402V-0.1UF,16V,10%,X7R,A 1        P3V3                    
                                  2        GND                     
C2T30            CAP_A_0402V-0.1UF,16V,10%,X7R,A 1        P3V3_STBY_MNG           
                                  2        GND                     
C2T31            CAP_A_0402V-1.0UF,6.3V,10%,X6SA 1        P3V3_STBY_MNG_RGMII     
                                  2        GND                     
C2T32            CAP_A_0402V-0.1UF,16V,10%,X7R,A 1        P0V7_GTL2104_5_VREF     
                                  2        GND                     
C2T33            CAP_A_0402V-1.0UF,6.3V,10%,X6SA 1        P3V3                    
                                  2        GND                     
C2T34            CAP_A_0402V-0.1UF,16V,10%,X7R,A 1        P3V3_STBY_MNG           
                                  2        GND                     
C2T35            CAP_A_0402V-0.1UF,16V,10%,X7R,A 1        P3V3_STBY               
                                  2        GND                     
C2T36            CAP_A_0402V-0.1UF,16V,10%,X7R,A 1        P3V3_STBY               
                                  2        GND                     
C2T37            CAP_A_0402V-0.01UF,25V,10%,X7RA 1        P3V3_STBY_MNG_RMII      
                                  2        GND                     
C2T38            CAP_A_0402V-1.0UF,6.3V,10%,X6SA 1        P3V3_STBY_MNG_RMII      
                                  2        GND                     
C2U1             CAP_0805-10UF,16V,10%,X6S,C953A 1        P3V3_STBY               
                                  2        GND                     
C2U2             CAP_0805-10UF,16V,10%,X6S,C953A 1        P3V3                    
                                  2        GND                     
C2U3             CAP_0402-0.22UF,16V,10%,X7R,A3A 1        P3E_CPU0_PE1_PCH_RXP<0> 
                                  2        P3E_CPU0_PE1_SS_RXP<0>  
C2U4             CAP_0402-0.22UF,16V,10%,X7R,A3A 1        P3E_CPU0_PE1_PCH_RXN<0> 
                                  2        P3E_CPU0_PE1_SS_RXN<0>  
C2U5             CAP_0402-0.22UF,16V,10%,X7R,A3A 1        P3E_CPU0_PE1_PCH_RXP<1> 
                                  2        P3E_CPU0_PE1_SS_RXP<1>  
C2U6             CAP_0402-0.22UF,16V,10%,X7R,A3A 1        P3E_CPU0_PE1_PCH_RXN<1> 
                                  2        P3E_CPU0_PE1_SS_RXN<1>  
C2U7             CAP_0402-0.22UF,16V,10%,X7R,A3A 1        P3E_CPU0_PE1_PCH_RXP<2> 
                                  2        P3E_CPU0_PE1_SS_RXP<2>  
C2U8             CAP_0402-0.22UF,16V,10%,X7R,A3A 1        P3E_CPU0_PE1_PCH_RXN<2> 
                                  2        P3E_CPU0_PE1_SS_RXN<2>  
C2U9             CAP_0402-0.22UF,16V,10%,X7R,A3A 1        P3E_CPU0_PE1_PCH_RXP<3> 
                                  2        P3E_CPU0_PE1_SS_RXP<3>  
C2U10            CAP_0402-0.22UF,16V,10%,X7R,A3A 1        P3E_CPU0_PE1_PCH_RXN<3> 
                                  2        P3E_CPU0_PE1_SS_RXN<3>  
C2U11            CAP_0402-0.22UF,16V,10%,X7R,A3A 1        P3E_CPU0_PE1_PCH_RXP<4> 
                                  2        P3E_CPU0_PE1_SS_RXP<4>  
C2U12            CAP_0402-0.22UF,16V,10%,X7R,A3A 1        P3E_CPU0_PE1_PCH_RXN<4> 
                                  2        P3E_CPU0_PE1_SS_RXN<4>  
C2U13            CAP_0402-0.22UF,16V,10%,X7R,A3A 1        P3E_CPU0_PE1_PCH_RXP<5> 
                                  2        P3E_CPU0_PE1_SS_RXP<5>  
C2U14            CAP_0402-0.22UF,16V,10%,X7R,A3A 1        P3E_CPU0_PE1_PCH_RXN<5> 
                                  2        P3E_CPU0_PE1_SS_RXN<5>  
C2U15            CAP_0402-0.22UF,16V,10%,X7R,A3A 1        P3E_CPU0_PE1_PCH_RXP<6> 
                                  2        P3E_CPU0_PE1_SS_RXP<6>  
C2U16            CAP_0402-0.22UF,16V,10%,X7R,A3A 1        P3E_CPU0_PE1_PCH_RXN<6> 
                                  2        P3E_CPU0_PE1_SS_RXN<6>  
C2U17            CAP_0402-0.22UF,16V,10%,X7R,A3A 1        P3E_CPU0_PE1_PCH_RXP<7> 
                                  2        P3E_CPU0_PE1_SS_RXP<7>  
C2U18            CAP_0402-0.22UF,16V,10%,X7R,A3A 1        P3E_CPU0_PE1_PCH_RXN<7> 
                                  2        P3E_CPU0_PE1_SS_RXN<7>  
C2U19            CAP_A_0402V-0.1UF,16V,10%,X7R,A 1        P3V3                    
                                  2        GND                     
C2U20            CAP_A_0402V-0.1UF,16V,10%,X7R,A 1        P12V                    
                                  2        GND                     
C2U21            CAP_A_0402V-0.1UF,16V,10%,X7R,A 1        P3V3                    
                                  2        GND                     
C2U22            CAP_A_0402V-0.1UF,16V,10%,X7R,A 1        P3V3_STBY               
                                  2        GND                     
C2U23            CAP_A_0402V-0.1UF,16V,10%,X7R,A 1        P3V3_STBY               
                                  2        GND                     
C2U24            CAP_A_0402V-0.1UF,16V,10%,X7R,A 1        P12V                    
                                  2        GND                     
C2U25            CAP_A_0402V-0.1UF,16V,10%,X7R,A 1        P3V3                    
                                  2        GND                     
C2U26            CAP_A_0402V-1.0UF,6.3V,10%,X6SA 1        P3V3_RTC_STBY           
                                  2        GND                     
C2U27            CAP_A_0402V-0.1UF,16V,10%,X7R,A 1        P3V3_STBY               
                                  2        GND                     
C2U28            CAP_A_0402V-0.1UF,16V,10%,X7R,A 1        P3V3_STBY               
                                  2        GND                     
C3A1             CAP_A_0603V-22.0UF,4V,20%,X6S,A 1        PVDDQ_KLM               
                                  2        GND                     
C3A2             CAP_A_0603V-22.0UF,4V,20%,X6S,A 1        PVDDQ_KLM               
                                  2        GND                     
C3A3             CAP_0603LF-10UF,4V,20%,X6S,E15A 1        PVPP_KLM                
                                  2        GND                     
C3A4             CAP_0603LF-10UF,4V,20%,X6S,E15A 1        PVPP_KLM                
                                  2        GND                     
C3A5             CAP_A_0603V-22.0UF,4V,20%,X6S,A 1        PVDDQ_KLM               
                                  2        GND                     
C3A6             CAP_A_0603V-22.0UF,4V,20%,X6S,A 1        PVDDQ_KLM               
                                  2        GND                     
C3A7             CAP_0603LF-10UF,4V,20%,X6S,E15A 1        PVPP_KLM                
                                  2        GND                     
C3A8             CAP_0603LF-10UF,4V,20%,X6S,E15A 1        PVPP_KLM                
                                  2        GND                     
C3B1             CAP_0603LF-10UF,4V,20%,X6S,E15A 1        PVPP_KLM                
                                  2        GND                     
C3B2             CAP_0603LF-10UF,4V,20%,X6S,E15A 1        PVPP_KLM                
                                  2        GND                     
C3B3             CAPP_7343LF-330UF,6.3V,20%,POSA 1        PVPP_KLM                
                                  2        GND                     
C3B4             CAP_A_0402V-0.1UF,16V,10%,X7R,A 1        PVCCIO_CPU1             
                                  2        GND                     
C3B5             CAP_A_0402V-0.1UF,16V,10%,X7R,A 1        PVPP_KLM                
                                  2        GND                     
C3B6             CAPP_3018-68UF,16V,20%,TANT,72A 1        P12V_STBY               
                                  2        GND                     
C3C1             CAP_A_0402V-1.0UF,6.3V,10%,X6SA 1        PVCCIOMCP_CPU1          
                                  2        GND                     
C3C2             CAP_A_0402V-1.0UF,6.3V,10%,X6SA 1        PVCCIOMCP_CPU1          
                                  2        GND                     
C3D1             CAP_A_0603V-22.0UF,4V,20%,X6S,A 1        PVCCIN_CPU1             
                                  2        GND                     
C3D2             CAP_A_0603V-22.0UF,4V,20%,X6S,A 1        PVCCIN_CPU1             
                                  2        GND                     
C3D3             CAP_0603LF-10UF,4V,20%,X6S,E15A 1        P1V8_MCP_CPU1           
                                  2        GND                     
C3D4             CAP_A_0603V-22.0UF,4V,20%,X6S,A 1        PVCCMCP_CPU1            
                                  2        GND                     
C3D5             CAP_A_0603V-22.0UF,4V,20%,X6S,A 1        PVCCMCP_CPU1            
                                  2        GND                     
C3D6             CAP_A_0603V-22.0UF,4V,20%,X6S,A 1        PVCCMCP_CPU1            
                                  2        GND                     
C3D7             CAP_A_0603V-22.0UF,4V,20%,X6S,A 1        PVCCMCP_CPU1            
                                  2        GND                     
C3D8             CAP_A_0603V-22.0UF,4V,20%,X6S,A 1        PVCCIO_CPU1             
                                  2        GND                     
C3D9             CAP_A_0603V-22.0UF,4V,20%,X6S,A 1        PVCCIO_CPU1             
                                  2        GND                     
C3D10            CAP_A_0603V-22.0UF,4V,20%,X6S,A 1        PVCCMCP_CPU1            
                                  2        GND                     
C3D11            CAP_A_0603V-22.0UF,4V,20%,X6S,A 1        PVCCMCP_CPU1            
                                  2        GND                     
C3D12            CAP_A_0603V-22.0UF,4V,20%,X6S,A 1        PVCCMCP_CPU1            
                                  2        GND                     
C3D13            CAP_A_0603V-22.0UF,4V,20%,X6S,A 1        PVCCMCP_CPU1            
                                  2        GND                     
C3D14            CAP_A_0603V-22.0UF,4V,20%,X6S,A 1        PVCCMCP_CPU1            
                                  2        GND                     
C3D15            CAP_A_0603V-22.0UF,4V,20%,X6S,A 1        PVCCIO_CPU1             
                                  2        GND                     
C3D16            CAP_A_0603V-22.0UF,4V,20%,X6S,A 1        PVCCIO_CPU1             
                                  2        GND                     
C3D17            CAP_A_0603V-22.0UF,4V,20%,X6S,A 1        PVCCMCP_CPU1            
                                  2        GND                     
C3D18            CAP_A_0603V-22.0UF,4V,20%,X6S,A 1        PVCCMCP_CPU1            
                                  2        GND                     
C3D19            CAP_A_0603V-22.0UF,4V,20%,X6S,A 1        PVCCMCP_CPU1            
                                  2        GND                     
C3D20            CAP_A_0603V-22.0UF,4V,20%,X6S,A 1        PVCCMCP_CPU1            
                                  2        GND                     
C3D21            CAP_A_0603V-22.0UF,4V,20%,X6S,A 1        PVCCMCP_CPU1            
                                  2        GND                     
C3D22            CAP_0805-10UF,16V,10%,X7R,G106A 1        P3V3_DB1200             
                                  2        GND                     
C3D23            CAP_A_0603V-22.0UF,4V,20%,X6S,A 1        PVCCIO_CPU1             
                                  2        GND                     
C3D24            CAP_A_0603V-22.0UF,4V,20%,X6S,A 1        PVCCIO_CPU1             
                                  2        GND                     
C3D25            CAP_A_0603V-22.0UF,4V,20%,X6S,A 1        PVCCIN_CPU1             
                                  2        GND                     
C3D27            CAP_A_0402V-0.1UF,16V,10%,EMPTA 1        VSENSE_PVCCIO_CPU1_SKT_VSEN
                                  2        VSENSE_PVCCIO_CPU1_SKT_VRTN
C3E1             CAP_A_0603V-22.0UF,4V,20%,X6S,A 1        PVCCIO_CPU1             
                                  2        GND                     
C3F1             CAP_A_0603V-47UF,4V,20%,X5R,60A 1        P1V8_MCP_CPU1           
                                  2        GND                     
C3F2             CAP_A_0402V-0.1UF,16V,10%,X7R,A 1        P3V3                    
                                  2        GND                     
C3F3             CAP_0603LF-10UF,4V,20%,X6S,E15A 1        PVPP_GHJ                
                                  2        GND                     
C3F4             CAP_0603LF-10UF,4V,20%,X6S,E15A 1        PVPP_GHJ                
                                  2        GND                     
C3G1             CAP_A_0603V-22.0UF,4V,20%,X6S,A 1        PVDDQ_GHJ               
                                  2        GND                     
C3G2             CAP_A_0603V-22.0UF,4V,20%,X6S,A 1        PVDDQ_GHJ               
                                  2        GND                     
C3G3             CAP_0603LF-10UF,4V,20%,X6S,E15A 1        PVPP_GHJ                
                                  2        GND                     
C3G4             CAP_0603LF-10UF,4V,20%,X6S,E15A 1        PVPP_GHJ                
                                  2        GND                     
C3G5             CAP_A_0603V-22.0UF,4V,20%,X6S,A 1        PVDDQ_GHJ               
                                  2        GND                     
C3G6             CAP_A_0603V-22.0UF,4V,20%,X6S,A 1        PVDDQ_GHJ               
                                  2        GND                     
C3G7             CAP_0603LF-10UF,4V,20%,X6S,E15A 1        PVPP_GHJ                
                                  2        GND                     
C3G8             CAP_0603LF-10UF,4V,20%,X6S,E15A 1        PVPP_GHJ                
                                  2        GND                     
C3L1             CAP_A_0402V-1.0UF,6.3V,10%,X6SA 1        P5V_STBY                
                                  2        GND                     
C3L2             CAP_0805-10UF,16V,10%,X6S,C953A 1        VR_FET_SW_P12V_STBY_PVDDQ_DEF
                                  2        GND                     
C3L4             CAP_0805-10UF,16V,10%,X6S,C953A 1        VR_FET_SW_P12V_STBY_PVDDQ_DEF
                                  2        GND                     
C3L6             CAPP_3018-470UF,2.5V,20%,ALUM,A 1        PVDDQ_DEF               
                                  2        GND                     
C3L7             CAP_0805-10UF,16V,10%,X6S,C953A 1        VR_FET_SW_P12V_STBY_PVDDQ_DEF
                                  2        GND                     
C3L8             CAP_0805-10UF,16V,10%,X6S,C953A 1        VR_FET_SW_P12V_STBY_PVDDQ_DEF
                                  2        GND                     
C3L9             CAP_0805-10UF,16V,10%,X6S,C953A 1        VR_FET_SW_P12V_STBY_PVDDQ_DEF
                                  2        GND                     
C3L10            CAP_0805-10UF,16V,10%,X6S,C953A 1        VR_FET_SW_P12V_STBY_PVDDQ_DEF
                                  2        GND                     
C3L11            CAP_0805-10UF,16V,10%,X6S,C953A 1        VR_FET_SW_P12V_STBY_PVDDQ_DEF
                                  2        GND                     
C3L12            CAP_0805-10UF,16V,10%,X6S,C953A 1        VR_FET_SW_P12V_STBY_PVDDQ_DEF
                                  2        GND                     
C3L13            CAP_0805-10UF,16V,10%,X6S,C953A 1        VR_FET_SW_P12V_STBY_PVDDQ_DEF
                                  2        GND                     
C3L14            CAPP_3018-470UF,2.5V,20%,ALUM,A 1        PVDDQ_DEF               
                                  2        GND                     
C3L15            CAP_0805-10UF,16V,10%,X6S,C953A 1        VR_FET_SW_P12V_STBY_PVDDQ_DEF
                                  2        GND                     
C3L16            CAP_0805-10UF,16V,10%,X6S,C953A 1        VR_FET_SW_P12V_STBY_PVDDQ_DEF
                                  2        GND                     
C3L17            CAP_0805-10UF,16V,10%,X6S,C953A 1        VR_FET_SW_P12V_STBY_PVDDQ_DEF
                                  2        GND                     
C3L18            CAPP_SM-470UF,2V,20%,ALUM,6990A 1        PVNN_PCH_STBY           
                                  2        GND                     
C3L19            CAPP_SM-470UF,2V,20%,ALUM,6990A 1        P1V05_PCH_STBY          
                                  2        GND                     
C3L20            CAPP_SM-470UF,2V,20%,ALUM,6990A 1        PVNN_PCH_STBY           
                                  2        GND                     
C3L21            CAPP_SM-470UF,2V,20%,ALUM,6990A 1        PVNN_PCH_STBY           
                                  2        GND                     
C3L22            CAP_A_0603V-22.0UF,4V,20%,X6S,A 1        PVNN_PCH_STBY           
                                  2        GND                     
C3L23            CAP_A_0603V-22.0UF,4V,20%,X6S,A 1        PVNN_PCH_STBY           
                                  2        GND                     
C3L24            CAP_A_0603V-22.0UF,4V,20%,X6S,A 1        PVNN_PCH_STBY           
                                  2        GND                     
C3L25            CAP_A_0603V-22.0UF,4V,20%,X6S,A 1        PVNN_PCH_STBY           
                                  2        GND                     
C3L26            CAP_A_0603V-22.0UF,4V,20%,X6S,A 1        PVNN_PCH_STBY           
                                  2        GND                     
C3L27            CAP_A_0603V-22.0UF,4V,20%,X6S,A 1        PVNN_PCH_STBY           
                                  2        GND                     
C3L29            CAP_A_0402V-1.0UF,6.3V,10%,X6SA 1        P5V_STBY                
                                  2        GND                     
C3L31            CAP_A_0402V-0.1UF,16V,10%,X7R,A 1        VR_PVDDQ_DEF_AIINSEN    
                                  2        GND                     
C3M1             CAP_0402-0.22UF,16V,10%,X7R,A3A 1        P3E_CPU0_PE1_PCH_R_RXN<15>
                                  2        P3E_CPU0_PE1_PCH_RXN<15>
C3M2             CAP_0402-0.22UF,16V,10%,X7R,A3A 1        P3E_CPU0_PE1_PCH_R_RXP<15>
                                  2        P3E_CPU0_PE1_PCH_RXP<15>
C3M3             CAP_0402-0.22UF,16V,10%,X7R,A3A 1        P3E_CPU0_PE1_PCH_R_RXP<12>
                                  2        P3E_CPU0_PE1_PCH_RXP<12>
C3M4             CAP_0402-0.22UF,16V,10%,X7R,A3A 1        P3E_CPU0_PE1_PCH_R_RXN<12>
                                  2        P3E_CPU0_PE1_PCH_RXN<12>
C3M6             CAP_A_0603V-22.0UF,4V,20%,X6S,A 1        PVNN_PCH_STBY           
                                  2        GND                     
C3M7             CAP_A_0603V-22.0UF,4V,20%,X6S,A 1        PVNN_PCH_STBY           
                                  2        GND                     
C3M8             CAP_0805-10UF,16V,10%,X6S,C953A 1        VR_FET_SW_P12V_STBY_PVPP_DEF
                                  2        GND                     
C3M9             CAP_0402-1.0UF,16V,10%,X6S,D97A 1        VR_FET_SW_P12V_STBY_PVPP_DEF
                                  2        GND                     
C3M10            CAP_0603-4.7UF,6.3V,10%,X6S,E1A 1        VR_VB_PVPP_DEF          
                                  2        AGND_PVPP_DEF           
C3M11            CAP_0402-0.22UF,16V,10%,X7R,A3A 1        P3E_CPU0_PE1_PCH_R_RXP<14>
                                  2        P3E_CPU0_PE1_PCH_RXP<14>
C3M12            CAP_0402-0.22UF,16V,10%,X7R,A3A 1        P3E_CPU0_PE1_PCH_R_RXN<14>
                                  2        P3E_CPU0_PE1_PCH_RXN<14>
C3M13            CAP_0402-0.22UF,16V,10%,X7R,A3A 1        P3E_CPU0_PE1_PCH_R_RXP<13>
                                  2        P3E_CPU0_PE1_PCH_RXP<13>
C3M14            CAP_0402-0.22UF,16V,10%,X7R,A3A 1        P3E_CPU0_PE1_PCH_R_RXN<13>
                                  2        P3E_CPU0_PE1_PCH_RXN<13>
C3M15            CAP_0805-10UF,16V,10%,X6S,C953A 1        VR_FET_SW_P12V_STBY_PVPP_DEF
                                  2        GND                     
C3M16            CAP_0805-10UF,16V,10%,X6S,C953A 1        VR_FET_SW_P12V_STBY_PVPP_DEF
                                  2        GND                     
C3M17            CAP_0603LF-10UF,4V,20%,X6S,E15A 1        P1V05_PCH_STBY_VCCA_PLL1
                                  2        GND                     
C3M18            CAP_0603LF-10UF,4V,20%,X6S,E15A 1        P1V05_PCH_STBY_VCCA_PLL0
                                  2        GND                     
C3M19            CAP_A_0402V-1.0UF,6.3V,10%,X6SA 1        P1V05_PCH_STBY_VCCA_PLL1
                                  2        GND                     
C3M20            CAP_A_0402V-1.0UF,6.3V,10%,X6SA 1        P1V05_PCH_STBY_VCCA_PLL0
                                  2        GND                     
C3M21            CAP_A_0402V-1.0UF,6.3V,10%,X6SA 1        P1V05_PCH_STBY          
                                  2        GND                     
C3M22            CAP_A_0402V-1.0UF,6.3V,10%,X6SA 1        P1V05_PCH_STBY          
                                  2        GND                     
C3M23            CAP_0603LF-10UF,4V,20%,X6S,E15A 1        P1V05_PCH_STBY_VCCA_XTAL
                                  2        GND                     
C3M24            CAP_0603LF-10UF,4V,20%,X6S,E15A 1        P1V05_PCH_STBY_ISCLK_PLL
                                  2        GND                     
C3M25            CAP_0402-0.22UF,16V,10%,X7R,A3A 1        P3E_CPU0_PE1_PCH_R_RXP<11>
                                  2        P3E_CPU0_PE1_PCH_RXP<11>
C3M26            CAP_0402-0.22UF,16V,10%,X7R,A3A 1        P3E_CPU0_PE1_PCH_R_RXN<11>
                                  2        P3E_CPU0_PE1_PCH_RXN<11>
C3M27            CAP_A_0402V-1.0UF,6.3V,10%,X6SA 1        P1V05_PCH_STBY_VCCA_XTAL
                                  2        GND                     
C3M28            CAP_0402-0.22UF,16V,10%,X7R,A3A 1        P3E_CPU0_PE1_PCH_R_RXP<10>
                                  2        P3E_CPU0_PE1_PCH_RXP<10>
C3M29            CAP_A_0402V-1.0UF,6.3V,10%,X6SA 1        P1V05_PCH_STBY_ISCLK_PLL
                                  2        GND                     
C3M30            CAP_A_0402V-1.0UF,6.3V,10%,X6SA 1        P1V05_PCH_STBY          
                                  2        GND                     
C3M31            CAP_A_0402V-1.0UF,6.3V,10%,X6SA 1        P1V05_PCH_STBY          
                                  2        GND                     
C3M32            CAP_0402-0.22UF,16V,10%,X7R,A3A 1        P3E_CPU0_PE1_PCH_R_RXN<10>
                                  2        P3E_CPU0_PE1_PCH_RXN<10>
C3M33            CAP_0402-0.22UF,16V,10%,X7R,A3A 1        P3E_CPU0_PE1_PCH_R_RXN<8>
                                  2        P3E_CPU0_PE1_PCH_RXN<8> 
C3M34            CAP_0402-0.22UF,16V,10%,X7R,A3A 1        P3E_CPU0_PE1_PCH_R_RXP<8>
                                  2        P3E_CPU0_PE1_PCH_RXP<8> 
C3M35            CAP_0402-0.22UF,16V,10%,X7R,A3A 1        P3E_CPU0_PE1_PCH_R_RXN<9>
                                  2        P3E_CPU0_PE1_PCH_RXN<9> 
C3M36            CAP_0402-0.22UF,16V,10%,X7R,A3A 1        P3E_CPU0_PE1_PCH_R_RXP<9>
                                  2        P3E_CPU0_PE1_PCH_RXP<9> 
C3M37            CAP_0402-0.22UF,16V,10%,X7R,A3A 1        DMI_CPU0_PCH_RX_DP<1>   
                                  2        DMI_CPU0_PCH_RX_C_DP<1> 
C3M38            CAP_A_0402V-1.0UF,6.3V,10%,X6SA 1        P1V05_PCH_STBY          
                                  2        GND                     
C3M39            CAP_A_0402V-1.0UF,6.3V,10%,X6SA 1        P1V05_PCH_STBY          
                                  2        GND                     
C3M40            CAP_0402-0.22UF,16V,10%,X7R,A3A 1        DMI_CPU0_PCH_RX_DP<0>   
                                  2        DMI_CPU0_PCH_RX_C_DP<0> 
C3M41            CAP_0402-0.22UF,16V,10%,X7R,A3A 1        DMI_CPU0_PCH_RX_DN<1>   
                                  2        DMI_CPU0_PCH_RX_C_DN<1> 
C3M42            CAP_A_0402V-1.0UF,6.3V,10%,X6SA 1        P1V05_PCH_STBY          
                                  2        GND                     
C3M43            CAP_A_0402V-1.0UF,6.3V,10%,X6SA 1        P1V05_PCH_STBY          
                                  2        GND                     
C3M44            CAP_0402-0.22UF,16V,10%,X7R,A3A 1        DMI_CPU0_PCH_RX_DN<0>   
                                  2        DMI_CPU0_PCH_RX_C_DN<0> 
C3M45            CAP_0402-0.22UF,16V,10%,X7R,A3A 1        DMI_CPU0_PCH_RX_DN<2>   
                                  2        DMI_CPU0_PCH_RX_C_DN<2> 
C3M46            CAP_A_0402V-1.0UF,6.3V,10%,X6SA 1        PVCCIOMCP_CPU0          
                                  2        GND                     
C3N1             CAP_A_0402V-1.0UF,6.3V,10%,X6SA 1        PVNN_PCH_STBY           
                                  2        GND                     
C3N2             CAP_A_0402V-1.0UF,6.3V,10%,X6SA 1        PVNN_PCH_STBY           
                                  2        GND                     
C3N3             CAP_A_0402V-1.0UF,6.3V,10%,X6SA 1        PVNN_PCH_STBY           
                                  2        GND                     
C3N4             CAP_A_0402V-1.0UF,6.3V,10%,X6SA 1        PVNN_PCH_STBY           
                                  2        GND                     
C3N5             CAP_A_0402V-1.0UF,6.3V,10%,X6SA 1        PVNN_PCH_STBY           
                                  2        GND                     
C3N6             CAP_A_0402V-1.0UF,6.3V,10%,X6SA 1        PVNN_PCH_STBY           
                                  2        GND                     
C3N7             CAP_A_0402V-1.0UF,6.3V,10%,X6SA 1        PVNN_PCH_STBY           
                                  2        GND                     
C3N8             CAP_0402-0.22UF,16V,10%,X7R,A3A 1        DMI_CPU0_PCH_RX_DP<3>   
                                  2        DMI_CPU0_PCH_RX_C_DP<3> 
C3N9             CAP_0402-0.22UF,16V,10%,X7R,A3A 1        DMI_CPU0_PCH_RX_DP<2>   
                                  2        DMI_CPU0_PCH_RX_C_DP<2> 
C3N10            CAP_A_0603V-22.0UF,4V,20%,X6S,A 1        PVNN_PCH_STBY           
                                  2        GND                     
C3N11            CAP_A_0603V-22.0UF,4V,20%,X6S,A 1        PVNN_PCH_STBY           
                                  2        GND                     
C3N12            CAP_A_0603V-22.0UF,4V,20%,X6S,A 1        PVNN_PCH_STBY           
                                  2        GND                     
C3N13            CAP_0402-0.22UF,16V,10%,X7R,A3A 1        DMI_CPU0_PCH_RX_DN<3>   
                                  2        DMI_CPU0_PCH_RX_C_DN<3> 
C3N14            CAPP_3018-470UF,2.5V,20%,ALUM,A 1        PVCCIOMCP_CPU0          
                                  2        GND                     
C3N15            CAP_A_0402V-1.0UF,6.3V,10%,X6SA 1        PVNN_PCH_STBY           
                                  2        GND                     
C3N16            CAP_A_0402V-1.0UF,6.3V,10%,X6SA 1        PVNN_PCH_STBY           
                                  2        GND                     
C3N17            CAP_A_0402V-1.0UF,6.3V,10%,X6SA 1        PVNN_PCH_STBY           
                                  2        GND                     
C3N18            CAP_A_0402V-1.0UF,6.3V,10%,X6SA 1        PVNN_PCH_STBY           
                                  2        GND                     
C3N19            CAP_A_0402V-1.0UF,6.3V,10%,X6SA 1        PVNN_PCH_STBY           
                                  2        GND                     
C3N20            CAP_A_0402V-1.0UF,6.3V,10%,X6SA 1        PVNN_PCH_STBY           
                                  2        GND                     
C3N21            CAP_A_0402V-1.0UF,6.3V,10%,X6SA 1        P1V8_PCH_STBY           
                                  2        GND                     
C3N22            CAP_A_0402V-1.0UF,6.3V,10%,X6SA 1        P1V8_PCH_STBY           
                                  2        GND                     
C3N23            CAP_A_0402V-1.0UF,6.3V,10%,X6SA 1        P3V3_STBY               
                                  2        GND                     
C3N24            CAP_A_0603V-22.0UF,4V,20%,X6S,A 1        PVNN_PCH_STBY           
                                  2        GND                     
C3N25            CAP_A_0402V-1.0UF,6.3V,10%,X6SA 1        P1V8_PCH_STBY           
                                  2        GND                     
C3N26            CAPP_3018-470UF,2.5V,20%,ALUM,A 1        PVCCIO_CPU0             
                                  2        GND                     
C3N27            CAP_A_0603V-22.0UF,4V,20%,X6S,A 1        PVNN_PCH_STBY           
                                  2        GND                     
C3N28            CAP_A_0603V-22.0UF,4V,20%,X6S,A 1        PVNN_PCH_STBY           
                                  2        GND                     
C3N29            CAP_A_0402V-0.1UF,16V,10%,X7R,A 1        A_PVCCRTC_EXT_CAP       
                                  2        GND                     
C3N30            CAP_A_0603V-22.0UF,4V,20%,X6S,A 1        PVNN_PCH_STBY           
                                  2        GND                     
C3N31            CAP_A_0603V-22.0UF,4V,20%,X6S,A 1        PVNN_PCH_STBY           
                                  2        GND                     
C3N32            CAP_A_0402V-1.0UF,6.3V,10%,X6SA 1        RST_SRTCRST_N           
                                  2        GND                     
C3N33            CAP_0805-10UF,16V,10%,X6S,C953A 1        VR_FET_SW_P12V_STBY_PVCCIO_CPU0
                                  2        GND                     
C3N34            CAP_0805-10UF,16V,10%,X6S,C953A 1        VR_FET_SW_P12V_STBY_PVCCIO_CPU0
                                  2        GND                     
C3N35            CAPP_3018-470UF,2.5V,20%,ALUM,A 1        PVCCIO_CPU0             
                                  2        GND                     
C3N36            CAP_0805-10UF,16V,10%,X6S,C953A 1        VR_FET_SW_P12V_STBY_PVCCIO_CPU0
                                  2        GND                     
C3N38            CAPP_3018-470UF,2.5V,20%,ALUM,A 1        PVCCIO_CPU0             
                                  2        GND                     
C3N39            CAP_0402LF-220PF,50V,10%,X7R,AA 1        VR_PVCCIO_CPU0_AVSP     
                                  2        VSENSE_PVCCIO_CPU0_AVSN 
C3N40            CAP_A_0402V-1.0UF,6.3V,10%,X6SA 1        PVCCIOMCP_CPU0          
                                  2        GND                     
C3P1             CAP_A_0402V-0.1UF,16V,10%,EMPTA 1        VSENSE_PVCCIO_CPU0_SKT_VSEN
                                  2        VSENSE_PVCCIO_CPU0_SKT_VRTN
C3P2             CAP_0402LF-1000PF,50V,10%,X7R,A 1        VR_PVCCIO_CPU0_VINSEN   
                                  2        GND                     
C3P3             CAP_A_0402V-1.0UF,6.3V,10%,X6SA 1        VR_PVCCIO_CPU0_VDD      
                                  2        GND                     
C3P4             CAP_A_0402V-1.0UF,6.3V,10%,X6SA 1        VR_PVCCIO_CPU0_VD12     
                                  2        GND                     
C3P5             CAP_A_0402V-0.1UF,16V,10%,X7R,A 1        VR_PVCCIO_CPU0_VD12     
                                  2        GND                     
C3P6             CAP_0402LF-1000PF,50V,10%,X7R,A 1        PWRGD_PVCCIO_CPU0_R     
                                  2        GND                     
C3P7             CAP_A_0402V-0.1UF,16V,10%,X7R,A 1        VR_PVCCIO_CPU0_VDD      
                                  2        GND                     
C3P10            CAP_0402-0.22UF,16V,10%,EMPTY,A 1        P3E_CPU0_PE1_SS_TXP<0>  
                                  2        P3E_CPU0_PE1_SS_C_TXP<0>
C3P11            CAP_0402-0.22UF,16V,10%,X7R,A3A 1        P3E_CPU0_PE1_SS_TXP<0>  
                                  2        P3E_CPU0_PE1_PCH_TXP<0> 
C3P12            CAP_0402-0.22UF,16V,10%,EMPTY,A 1        P3E_CPU0_PE1_SS_TXN<0>  
                                  2        P3E_CPU0_PE1_SS_C_TXN<0>
C3P13            CAP_0402-0.22UF,16V,10%,X7R,A3A 1        P3E_CPU0_PE1_SS_TXN<0>  
                                  2        P3E_CPU0_PE1_PCH_TXN<0> 
C3P14            CAP_0402-0.22UF,16V,10%,EMPTY,A 1        P3E_CPU0_PE1_SS_TXP<1>  
                                  2        P3E_CPU0_PE1_SS_C_TXP<1>
C3P15            CAP_0402-0.22UF,16V,10%,X7R,A3A 1        P3E_CPU0_PE1_SS_TXP<1>  
                                  2        P3E_CPU0_PE1_PCH_TXP<1> 
C3P16            CAP_0402-0.22UF,16V,10%,EMPTY,A 1        P3E_CPU0_PE1_SS_TXN<1>  
                                  2        P3E_CPU0_PE1_SS_C_TXN<1>
C3P17            CAP_0402-0.22UF,16V,10%,X7R,A3A 1        P3E_CPU0_PE1_SS_TXN<1>  
                                  2        P3E_CPU0_PE1_PCH_TXN<1> 
C3P18            CAP_0402-0.22UF,16V,10%,X7R,A3A 1        P3E_CPU0_PE1_SS_TXP<2>  
                                  2        P3E_CPU0_PE1_PCH_TXP<2> 
C3P19            CAP_0402-0.22UF,16V,10%,EMPTY,A 1        P3E_CPU0_PE1_SS_TXP<2>  
                                  2        P3E_CPU0_PE1_SS_C_TXP<2>
C3P20            CAP_0402-0.22UF,16V,10%,X7R,A3A 1        P3E_CPU0_PE1_SS_TXN<2>  
                                  2        P3E_CPU0_PE1_PCH_TXN<2> 
C3P21            CAP_0402-0.22UF,16V,10%,EMPTY,A 1        P3E_CPU0_PE1_SS_TXN<2>  
                                  2        P3E_CPU0_PE1_SS_C_TXN<2>
C3P22            CAP_0402-0.22UF,16V,10%,EMPTY,A 1        P3E_CPU0_PE1_SS_TXP<3>  
                                  2        P3E_CPU0_PE1_SS_C_TXP<3>
C3P23            CAP_0402-0.22UF,16V,10%,X7R,A3A 1        P3E_CPU0_PE1_SS_TXP<3>  
                                  2        P3E_CPU0_PE1_PCH_TXP<3> 
C3P24            CAP_0402-0.22UF,16V,10%,EMPTY,A 1        P3E_CPU0_PE1_SS_TXN<3>  
                                  2        P3E_CPU0_PE1_SS_C_TXN<3>
C3P25            CAP_0402-0.22UF,16V,10%,X7R,A3A 1        P3E_CPU0_PE1_SS_TXN<3>  
                                  2        P3E_CPU0_PE1_PCH_TXN<3> 
C3P26            CAP_0402-0.22UF,16V,10%,EMPTY,A 1        P3E_CPU0_PE1_SS_TXP<4>  
                                  2        P3E_CPU0_PE1_SS_C_TXP<4>
C3P27            CAP_0402-0.22UF,16V,10%,X7R,A3A 1        P3E_CPU0_PE1_SS_TXP<4>  
                                  2        P3E_CPU0_PE1_PCH_TXP<4> 
C3P28            CAP_0402-0.22UF,16V,10%,X7R,A3A 1        P3E_CPU0_PE1_SS_TXN<4>  
                                  2        P3E_CPU0_PE1_PCH_TXN<4> 
C3P29            CAP_0402-0.22UF,16V,10%,EMPTY,A 1        P3E_CPU0_PE1_SS_TXN<4>  
                                  2        P3E_CPU0_PE1_SS_C_TXN<4>
C3P30            CAP_0402-0.22UF,16V,10%,X7R,A3A 1        P3E_CPU0_PE1_SS_TXP<5>  
                                  2        P3E_CPU0_PE1_PCH_TXP<5> 
C3P31            CAP_0402-0.22UF,16V,10%,EMPTY,A 1        P3E_CPU0_PE1_SS_TXP<5>  
                                  2        P3E_CPU0_PE1_SS_C_TXP<5>
C3P32            CAP_0402-0.22UF,16V,10%,X7R,A3A 1        P3E_CPU0_PE1_SS_TXN<5>  
                                  2        P3E_CPU0_PE1_PCH_TXN<5> 
C3P33            CAP_0402-0.22UF,16V,10%,EMPTY,A 1        P3E_CPU0_PE1_SS_TXN<5>  
                                  2        P3E_CPU0_PE1_SS_C_TXN<5>
C3P34            CAP_0402-0.22UF,16V,10%,EMPTY,A 1        P3E_CPU0_PE1_SS_TXP<6>  
                                  2        P3E_CPU0_PE1_SS_C_TXP<6>
C3P35            CAP_0402-0.22UF,16V,10%,X7R,A3A 1        P3E_CPU0_PE1_SS_TXP<6>  
                                  2        P3E_CPU0_PE1_PCH_TXP<6> 
C3P36            CAP_0402-0.22UF,16V,10%,EMPTY,A 1        P3E_CPU0_PE1_SS_TXN<6>  
                                  2        P3E_CPU0_PE1_SS_C_TXN<6>
C3P37            CAP_0402-0.22UF,16V,10%,X7R,A3A 1        P3E_CPU0_PE1_SS_TXN<6>  
                                  2        P3E_CPU0_PE1_PCH_TXN<6> 
C3P38            CAP_0402-0.22UF,16V,10%,EMPTY,A 1        P3E_CPU0_PE1_SS_TXP<7>  
                                  2        P3E_CPU0_PE1_SS_C_TXP<7>
C3P39            CAP_0402-0.22UF,16V,10%,X7R,A3A 1        P3E_CPU0_PE1_SS_TXP<7>  
                                  2        P3E_CPU0_PE1_PCH_TXP<7> 
C3P40            CAP_0402-0.22UF,16V,10%,X7R,A3A 1        P3E_CPU0_PE1_SS_TXN<7>  
                                  2        P3E_CPU0_PE1_PCH_TXN<7> 
C3P41            CAP_0402-0.22UF,16V,10%,EMPTY,A 1        P3E_CPU0_PE1_SS_TXN<7>  
                                  2        P3E_CPU0_PE1_SS_C_TXN<7>
C3P42            CAP_A_0402V-1.0UF,6.3V,10%,X6SA 1        P3V3_STBY               
                                  2        GND                     
C3P43            CAP_A_0402V-0.1UF,16V,10%,X7R,A 1        P3V3_STBY               
                                  2        GND                     
C3P44            CAP_A_0402V-0.1UF,16V,10%,X7R,A 1        P3V3_STBY               
                                  2        GND                     
C3P45            CAP_0402-0.047UF,25V,10%,X7R,AA 1        A_ADM1085_CEXT          
                                  2        GND                     
C3P46            CAP_A_0402V-0.1UF,16V,10%,X7R,A 1        P3V3_STBY               
                                  2        GND                     
C3P47            CAP_A_0402V-0.1UF,16V,10%,X7R,A 1        P3V3_STBY               
                                  2        GND                     
C3P48            CAP_A_0402V-0.1UF,16V,10%,X7R,A 1        P3V3_STBY               
                                  2        GND                     
C3P49            CAP_A_0402V-0.1UF,16V,10%,X7R,A 1        P0V7_GTL2104_VREF_1     
                                  2        GND                     
C3P50            CAP_0402-1.0UF,16V,10%,X6S,D97A 1        P3V3                    
                                  2        GND                     
C3P51            CAP_A_0402V-0.1UF,16V,10%,X7R,A 1        P3V3_STBY               
                                  2        GND                     
C3P52            CAP_A_0402V-0.1UF,16V,10%,X7R,A 1        P3V3_STBY               
                                  2        GND                     
C3R1             CAP_A_0402V-0.1UF,16V,10%,X7R,A 1        P3V3_STBY               
                                  2        GND                     
C3R2             CAP_A_0402V-0.1UF,16V,10%,X7R,A 1        P3V3_STBY               
                                  2        GND                     
C3R3             CAP_A_0402V-0.1UF,16V,10%,X7R,A 1        P3V3_STBY               
                                  2        GND                     
C3R4             CAPP_3018-470UF,2.5V,20%,ALUM,A 1        PVCCMCP_CPU0            
                                  2        GND                     
C3T1             CAP_A_0603V-47UF,4V,20%,X5R,60A 1        P1V8_MCP_CPU0           
                                  2        GND                     
C3T2             CAP_A_0603V-47UF,4V,20%,X5R,60A 1        P1V8_MCP_CPU0           
                                  2        GND                     
C3T3             CAPP_3018-68UF,16V,20%,TANT,72A 1        P12V_STBY               
                                  2        GND                     
C3T4             CAP_A_0402V-1.0UF,6.3V,10%,X6SA 1        P3V3_STBY               
                                  2        GND                     
C3T5             CAP_A_0402V-0.01UF,25V,10%,X7RA 1        P3V3_STBY               
                                  2        GND                     
C3T6             CAPP_3018-68UF,16V,20%,TANT,72A 1        P12V_STBY               
                                  2        GND                     
C3T7             CAP_0805-47UF,4V,20%,X6S,C9533A 1        PVPP_ABC                
                                  2        GND                     
C3T8             CAP_0805-10UF,16V,10%,X6S,C953A 1        VR_FET_SW_P12V_STBY_PVPP_ABC
                                  2        GND                     
C3T9             CAP_0805-47UF,4V,20%,X6S,C9533A 1        PVPP_ABC                
                                  2        GND                     
C3T10            CAP_0402-1.0UF,16V,10%,X6S,D97A 1        VR_FET_SW_P12V_STBY_PVPP_ABC
                                  2        GND                     
C3T11            CAP_0603-4.7UF,6.3V,10%,X6S,E1A 1        VR_VB_PVPP_ABC          
                                  2        AGND_PVPP_ABC           
C3T12            CAP_0805-10UF,16V,10%,X6S,C953A 1        VR_FET_SW_P12V_STBY_PVPP_ABC
                                  2        GND                     
C3T13            CAPP_3018-68UF,16V,20%,TANT,72A 1        P12V_STBY               
                                  2        GND                     
C3T14            CAP_0805-10UF,16V,10%,X6S,C953A 1        VR_FET_SW_P12V_STBY_PVPP_ABC
                                  2        GND                     
C3T15            CAPP_3018-68UF,16V,20%,TANT,72A 1        P12V_STBY               
                                  2        GND                     
C3U1             CAPP_3018-470UF,2.5V,20%,ALUM,A 1        PVDDQ_ABC               
                                  2        GND                     
C3U2             CAP_0805-10UF,16V,10%,X6S,C953A 1        VR_FET_SW_P12V_STBY_PVDDQ_ABC
                                  2        GND                     
C3U3             CAP_0805-10UF,16V,10%,X6S,C953A 1        VR_FET_SW_P12V_STBY_PVDDQ_ABC
                                  2        GND                     
C3U4             CAP_0805-10UF,16V,10%,X6S,C953A 1        VR_FET_SW_P12V_STBY_PVDDQ_ABC
                                  2        GND                     
C3U5             CAPP_3018-470UF,2.5V,20%,ALUM,A 1        PVDDQ_ABC               
                                  2        GND                     
C3U6             CAP_0805-10UF,16V,10%,X6S,C953A 1        VR_FET_SW_P12V_STBY_PVDDQ_ABC
                                  2        GND                     
C3U7             CAP_0805-10UF,16V,10%,X6S,C953A 1        VR_FET_SW_P12V_STBY_PVDDQ_ABC
                                  2        GND                     
C3U8             CAPP_3018-470UF,2.5V,20%,ALUM,A 1        PVDDQ_ABC               
                                  2        GND                     
C3U9             CAP_0805-10UF,16V,10%,X6S,C953A 1        VR_FET_SW_P12V_STBY_PVDDQ_ABC
                                  2        GND                     
C3U10            CAP_A_0402V-0.1UF,16V,10%,X7R,A 1        VR_PVDDQ_ABC_AIINSEN    
                                  2        GND                     
C4A1             CAP_0805LF-22UF,4V,20%,X6S,C95A 1        PVTT_DEF                
                                  2        GND                     
C4A2             CAP_0402LF-1000PF,50V,10%,EMPTA 1        FM_PVTT_DEF_EN_R        
                                  2        GND                     
C4A3             CAP_0402LF-1000PF,50V,10%,X7R,A 1        PWRGD_PVTT_KLM_CPU1_R   
                                  2        GND                     
C4A4             CAP_0805-10UF,16V,10%,X7R,G106A 1        P12V_NVDIMM_DEF         
                                  2        GND                     
C4A5             CAP_A_0402V-0.01UF,25V,10%,X7RA 1        M_F_VREF                
                                  2        GND                     
C4A6             CAP_0402LF-1000PF,50V,10%,EMPTA 1        FM_PVTT_KLM_EN_R        
                                  2        GND                     
C4A7             CAP_0603-4.7UF,6.3V,10%,X6S,E1A 1        VSENSE_PVDDQ_KLM_VTT    
                                  2        GND                     
C4A8             CAP_0402-1.0UF,16V,10%,X6S,D97A 1        VR_PVTT_KLM_BIAS        
                                  2        GND                     
C4A9             CAP_0402-1.0UF,16V,10%,X6S,D97A 1        VR_PVTT_DEF_VREF        
                                  2        GND                     
C4A10            CAP_0402-1.0UF,16V,10%,X6S,D97A 1        VR_PVTT_DEF_BIAS        
                                  2        GND                     
C4A11            CAP_0603-4.7UF,6.3V,10%,X6S,E1A 1        VSENSE_PVDDQ_DEF_VTT    
                                  2        GND                     
C4A12            CAP_0402LF-1000PF,50V,10%,X7R,A 1        PWRGD_PVTT_DEF_CPU0_R   
                                  2        GND                     
C4A13            CAP_0805LF-22UF,4V,20%,X6S,C95A 1        PVTT_KLM                
                                  2        GND                     
C4A14            CAP_0402-1.0UF,16V,10%,X6S,D97A 1        VR_PVTT_KLM_VREF        
                                  2        GND                     
C4A15            CAP_0603LF-10UF,4V,20%,X6S,E15A 1        PVDDQ_KLM               
                                  2        GND                     
C4A16            CAP_0402LF-3300PF,50V,10%,EMPTA 1        VR_PVPP_KLM_PHASE       
                                  2        VR_PVPP_KLM_SNUB        
C4A17            CAP_0805-10UF,16V,10%,X7R,G106A 1        P12V_NVDIMM_DEF         
                                  2        GND                     
C4A18            CAP_A_0402V-0.01UF,25V,10%,X7RA 1        M_E_VREF                
                                  2        GND                     
C4A19            CAP_0805-10UF,16V,10%,X6S,C953A 1        VR_FET_SW_P12V_STBY_PVPP_KLM
                                  2        GND                     
C4A20            CAP_A_0402V-0.1UF,16V,10%,X7R,A 1        VR_FET_SW_P12V_STBY_PVPP_KLM
                                  2        GND                     
C4B1             CAP_1210-47UF,16V,20%,X6S,D384A 1        VR_FET_SW_P12V_STBY_PVPP_KLM
                                  2        GND                     
C4B2             CAP_0805-47UF,4V,20%,X6S,C9533A 1        PVPP_KLM                
                                  2        GND                     
C4B3             CAP_0805-47UF,4V,20%,X6S,C9533A 1        PVPP_KLM                
                                  2        GND                     
C4B4             CAP_0402LF-100.0PF,50V,5%,COG,A 1        VR_FB_PVPP_KLM          
                                  2        VR_COMP_PVPP_KLM_3      
C4B5             CAP_0402LF-1000PF,50V,10%,EMPTA 1        FM_PVPP_CPU1_EN         
                                  2        AGND_PVPP_KLM           
C4B6             CAP_0402-0.027UF,16V,10%,X7R,AA 1        VR_PVPP_KLM_SS          
                                  2        AGND_PVPP_KLM           
C4B7             CAP_0402LF-2200PF,50V,10%,X7R,A 1        VR_COMP_PVPP_KLM        
                                  2        VR_FB_PVPP_KLM          
C4B8             CAP_0402LF-1000PF,50V,10%,X7R,A 1        PWRGD_PVPP_KLM_R        
                                  2        GND                     
C4B9             CAP_0402LF-2200PF,50V,10%,X7R,A 1        VR_COMP_RC_PVPP_KLM     
                                  2        VR_COMP_PVPP_KLM_3      
C4B11            CAP_0805-10UF,16V,10%,X7R,G106A 1        P12V_NVDIMM_DEF         
                                  2        GND                     
C4B12            CAP_A_0402V-0.01UF,25V,10%,X7RA 1        M_D_VREF                
                                  2        GND                     
C4B13            CAPP_4040LF-470UF,16V,20%,ALUMA 1        P12V_STBY               
                                  2        GND                     
C4B14            CAPP_3018-68UF,16V,20%,TANT,72A 1        P12V_STBY               
                                  2        GND                     
C4B15            CAP_0603LF-0.1UF,25V,10%,X7R,6A 1        VR_PVPP_KLM_PHASE       
                                  2        VR_PVPP_KLM_BOOT_R      
C4C1             CAPP_3018-470UF,2.5V,20%,ALUM,A 1        PVCCIOMCP_CPU1          
                                  2        GND                     
C4C2             CAP_A_0402V-0.1UF,16V,10%,EMPTA 1        VR_FET_SW_P12V_PVCCIN_CPU0_R
                                  2        GND                     
C4C3             CAP_A_0402V-1.0UF,6.3V,10%,X6SA 1        P3V3_STBY               
                                  2        GND                     
C4C4             CAP_A_0402V-1.0UF,6.3V,10%,X6SA 1        P5V_STBY                
                                  2        GND                     
C4C5             CAP_0402-0.22UF,16V,10%,X7R,A3A 1        P5V_STBY                
                                  2        GND                     
C4C6             CAP_0402-1.0UF,16V,10%,X6S,D97A 1        VR_PVSA_CPU0_VCIN       
                                  2        GND                     
C4C8             CAP_0402-0.220UF,16V,10%,X7R,AA 1        VR_PVSA_CPU0_BOOT       
                                  2        VR_PVSA_CPU0_PHASE      
C4C9             CAP_0402-1.0UF,16V,10%,X6S,D97A 1        VR_FET_SW_P12V_STBY_PVCCIN_CPU0
                                  2        GND                     
C4C10            CAP_A_0402V-0.1UF,16V,10%,X7R,A 1        VR_FET_SW_P12V_STBY_PVCCIN_CPU0
                                  2        GND                     
C4C11            CAP_A_0603V-22.0UF,4V,20%,X6S,A 1        PVSA_CPU0               
                                  2        GND                     
C4C12            CAPP_2626-270UF,16V,20%,OSCON,A 1        VR_FET_SW_P12V_STBY_PVCCIN_CPU0
                                  2        GND                     
C4C14            CAP_A_0402V-1.0UF,6.3V,10%,X6SA 1        P5V_STBY                
                                  2        GND                     
C4C17            CAP_0402-0.220UF,16V,10%,X7R,AA 1        VR_PVCCIN_CPU0_PH5_BOOT 
                                  2        VR_PVCCIN_CPU0_PH5_PHASE
C4C18            CAP_0402-1.0UF,16V,10%,X6S,D97A 1        VR_FET_SW_P12V_STBY_PVCCIN_CPU0
                                  2        GND                     
C4C19            CAP_A_0402V-0.1UF,16V,10%,X7R,A 1        VR_FET_SW_P12V_STBY_PVCCIN_CPU0
                                  2        GND                     
C4D2             CAPP_2626-270UF,16V,20%,OSCON,A 1        VR_FET_SW_P12V_STBY_PVCCIN_CPU0
                                  2        GND                     
C4D4             CAP_A_0603V-22.0UF,4V,20%,X6S,A 1        PVCCIN_CPU0             
                                  2        GND                     
C4D5             CAP_0402-0.22UF,16V,10%,X7R,A3A 1        P5V_STBY                
                                  2        GND                     
C4D6             CAP_A_0402V-1.0UF,6.3V,10%,X6SA 1        P5V_STBY                
                                  2        GND                     
C4D7             CAP_0402-1.0UF,16V,10%,X6S,D97A 1        VR_PVCCIN_CPU0_PH4_VCIN 
                                  2        GND                     
C4D9             CAP_0402-0.220UF,16V,10%,X7R,AA 1        VR_PVCCIN_CPU0_PH4_BOOT 
                                  2        VR_PVCCIN_CPU0_PH4_PHASE
C4D10            CAP_0402-1.0UF,16V,10%,X6S,D97A 1        VR_FET_SW_P12V_STBY_PVCCIN_CPU0
                                  2        GND                     
C4D11            CAP_A_0402V-0.1UF,16V,10%,X7R,A 1        VR_FET_SW_P12V_STBY_PVCCIN_CPU0
                                  2        GND                     
C4D12            CAP_A_0603V-22.0UF,4V,20%,X6S,A 1        PVCCIN_CPU0             
                                  2        GND                     
C4D13            CAP_0402-0.22UF,16V,10%,X7R,A3A 1        P5V_STBY                
                                  2        GND                     
C4D14            CAP_A_0402V-1.0UF,6.3V,10%,X6SA 1        P5V_STBY                
                                  2        GND                     
C4D15            CAP_A_0402V-1.0UF,6.3V,10%,X6SA 1        VR_PVCCIN_CPU0_VDD      
                                  2        GND                     
C4D16            CAP_0402-1.0UF,16V,10%,X6S,D97A 1        VR_PVCCIN_CPU0_PH3_VCIN 
                                  2        GND                     
C4D17            CAP_0402LF-220PF,50V,10%,X7R,AA 1        A_TSENSE_PVCCIN_CPU0    
                                  2        GND                     
C4D18            CAP_0402LF-220PF,50V,10%,X7R,AA 1        A_TSENSE_PVSA_CPU0      
                                  2        GND                     
C4D19            CAP_A_0402V-0.1UF,16V,10%,X7R,A 1        VR_PVCCIN_CPU0_VDD      
                                  2        GND                     
C4D20            CAP_0402LF-1000PF,50V,10%,X7R,A 1        VR_PVCCIN_CPU0_AVINSEN  
                                  2        GND                     
C4D22            CAP_A_0402V-0.1UF,16V,10%,X7R,A 1        P3V3_DB1200_R           
                                  2        GND                     
C4D23            CAP_A_0402V-1.0UF,6.3V,10%,X6SA 1        P3V3_DB1200_A           
                                  2        GND                     
C4D24            CAP_A_0402V-0.1UF,16V,10%,X7R,A 1        P3V3_DB1200_A           
                                  2        GND                     
C4D25            CAP_A_0402V-1.0UF,6.3V,10%,X6SA 1        VR_PVCCIN_CPU0_VD12     
                                  2        GND                     
C4D26            CAP_A_0402V-0.1UF,16V,10%,X7R,A 1        VR_PVCCIN_CPU0_VD12     
                                  2        GND                     
C4D27            CAP_A_0402V-1.0UF,6.3V,10%,X6SA 1        P3V3_DB1200_R           
                                  2        GND                     
C4D28            CAP_0402-0.220UF,16V,10%,X7R,AA 1        VR_PVCCIN_CPU0_PH3_BOOT 
                                  2        VR_PVCCIN_CPU0_PH3_PHASE
C4D29            CAP_0402LF-220PF,50V,10%,X7R,AA 1        VSENSE_PVSA_CPU0_BVSP   
                                  2        VSENSE_PVSA_CPU0_N      
C4D30            CAP_0402-1.0UF,16V,10%,X6S,D97A 1        VR_FET_SW_P12V_STBY_PVCCIN_CPU0
                                  2        GND                     
C4D31            CAP_A_0402V-1.0UF,6.3V,10%,X6SA 1        VR_PVCCIO_CPU1_VD12     
                                  2        GND                     
C4D32            CAP_A_0402V-0.1UF,16V,10%,X7R,A 1        VR_PVCCIO_CPU1_VD12     
                                  2        GND                     
C4D33            CAP_0402LF-1000PF,50V,10%,X7R,A 1        PWRGD_PVCCIO_CPU1_R     
                                  2        GND                     
C4D34            CAP_A_0603V-22.0UF,4V,20%,X6S,A 1        PVCCIN_CPU0             
                                  2        GND                     
C4D35            CAP_A_0402V-0.1UF,16V,10%,X7R,A 1        VR_FET_SW_P12V_STBY_PVCCIN_CPU0
                                  2        GND                     
C4D36            CAP_A_0402V-1.0UF,6.3V,10%,X6SA 1        VR_PVCCIO_CPU1_VDD      
                                  2        GND                     
C4D38            CAP_A_0402V-0.1UF,16V,10%,X7R,A 1        VR_PVCCIO_CPU1_VDD      
                                  2        GND                     
C4D40            CAP_0402LF-1000PF,50V,10%,X7R,A 1        VR_PVCCIO_CPU1_VINSEN   
                                  2        GND                     
C4D42            CAP_0402LF-1000PF,50V,10%,X7R,A 1        VR_VRRDY_PVCCIN_CPU0    
                                  2        GND                     
C4D44            CAP_0402LF-220PF,50V,10%,X7R,AA 1        VR_PVCCIO_CPU1_AVSP     
                                  2        VSENSE_PVCCIO_CPU1_AVSN 
C4D45            CAP_0402LF-220PF,50V,10%,X7R,AA 1        VSENSE_PVCCIN_CPU0_AVSP 
                                  2        VSENSE_PVCCIN_CPU0_N    
C4D46            CAP_0402-1.0UF,16V,10%,X6S,D97A 1        VR_PVCCIN_CPU0_PH5_VCIN 
                                  2        GND                     
C4D47            CAP_0402-0.22UF,16V,10%,X7R,A3A 1        P5V_STBY                
                                  2        GND                     
C4D48            CAP_0402-1.0UF,16V,10%,X6S,D97A 1        VR_FET_SW_P12V_STBY_PVCCIN_CPU0
                                  2        GND                     
C4D49            CAP_A_0402V-0.1UF,16V,10%,X7R,A 1        VR_FET_SW_P12V_STBY_PVCCIN_CPU0
                                  2        GND                     
C4D50            CAP_0402-0.220UF,16V,10%,X7R,AA 1        VR_PVCCIN_CPU0_PH2_BOOT 
                                  2        VR_PVCCIN_CPU0_PH2_PHASE
C4E3             CAP_A_0603V-22.0UF,4V,20%,X6S,A 1        PVCCIN_CPU0             
                                  2        GND                     
C4E5             CAP_0402-0.22UF,16V,10%,X7R,A3A 1        P5V_STBY                
                                  2        GND                     
C4E6             CAP_A_0402V-1.0UF,6.3V,10%,X6SA 1        P5V_STBY                
                                  2        GND                     
C4E7             CAPP_3018-470UF,2.5V,20%,ALUM,A 1        PVCCIO_CPU1             
                                  2        GND                     
C4E8             CAP_1210-100UF,16V,20%,X5R,644A 1        VR_FET_SW_P12V_STBY_PVCCIN_CPU0
                                  2        GND                     
C4E9             CAP_1210-100UF,16V,20%,X5R,644A 1        VR_FET_SW_P12V_STBY_PVCCIN_CPU0
                                  2        GND                     
C4E10            CAP_0402-1.0UF,16V,10%,X6S,D97A 1        VR_PVCCIN_CPU0_PH1_VCIN 
                                  2        GND                     
C4E11            CAP_A_0603V-22.0UF,4V,20%,X6S,A 1        PVCCIN_CPU0             
                                  2        GND                     
C4E13            CAP_A_0402V-0.1UF,16V,10%,X7R,A 1        VR_FET_SW_P12V_STBY_PVCCIN_CPU0
                                  2        GND                     
C4E14            CAP_1210-100UF,16V,20%,X5R,644A 1        VR_FET_SW_P12V_STBY_PVCCIN_CPU0
                                  2        GND                     
C4E15            CAP_0402-1.0UF,16V,10%,X6S,D97A 1        VR_FET_SW_P12V_STBY_PVCCIN_CPU0
                                  2        GND                     
C4E16            CAPP_2626-270UF,16V,20%,OSCON,A 1        VR_FET_SW_P12V_STBY_PVCCIN_CPU0
                                  2        GND                     
C4E17            CAP_0402-0.220UF,16V,10%,X7R,AA 1        VR_PVCCIN_CPU0_PH1_BOOT 
                                  2        VR_PVCCIN_CPU0_PH1_PHASE
C4E18            CAP_0402-0.220UF,16V,10%,X7R,AA 1        VR_PVCCIO_CPU1_PH1_BOOT 
                                  2        VR_PVCCIO_CPU1_PH1_PHASE
C4E19            CAP_0402-1.0UF,16V,10%,X6S,D97A 1        VR_FET_SW_P12V_STBY_PVCCIN_CPU0
                                  2        GND                     
C4E20            CAP_A_0402V-0.1UF,16V,10%,X7R,A 1        VR_FET_SW_P12V_STBY_PVCCIN_CPU0
                                  2        GND                     
C4E22            CAP_0402-1.0UF,16V,10%,X6S,D97A 1        VR_PVCCIO_CPU1_PH1_VCIN 
                                  2        GND                     
C4E23            CAP_0402-0.22UF,16V,10%,X7R,A3A 1        P5V_STBY                
                                  2        GND                     
C4E24            CAPP_3018-470UF,2.5V,20%,ALUM,A 1        PVCCMCP_CPU1            
                                  2        GND                     
C4E25            CAP_A_0402V-1.0UF,6.3V,10%,X6SA 1        P5V_STBY                
                                  2        GND                     
C4E26            CAP_0402-1.0UF,16V,10%,X6S,D97A 1        VR_PVCCIN_CPU0_PH2_VCIN 
                                  2        GND                     
C4E27            CAP_0402-0.22UF,16V,10%,X7R,A3A 1        P5V_STBY                
                                  2        GND                     
C4E28            CAP_A_0402V-1.0UF,6.3V,10%,X6SA 1        P5V_STBY                
                                  2        GND                     
C4F1             CAP_A_0402V-1.0UF,6.3V,10%,X6SA 1        P1V8_MCP_CPU1           
                                  2        GND                     
C4F2             CAP_A_0603V-47UF,4V,20%,X5R,60A 1        P1V8_MCP_CPU1           
                                  2        GND                     
C4F3             CAP_A_0402V-1.0UF,6.3V,10%,X6SA 1        P1V8_MCP_CPU1           
                                  2        GND                     
C4F4             CAPP_3018-68UF,16V,20%,TANT,72A 1        P12V_STBY               
                                  2        GND                     
C4F5             CAPP_3018-68UF,16V,20%,TANT,72A 1        P12V_STBY               
                                  2        GND                     
C4F6             CAPP_4040LF-470UF,16V,20%,ALUMA 1        P12V_STBY               
                                  2        GND                     
C4F7             CAPP_7343LF-330UF,6.3V,20%,POSA 1        PVPP_GHJ                
                                  2        GND                     
C4F9             CAP_A_0402V-0.01UF,25V,10%,X7RA 1        M_A_CPU_VREF            
                                  2        GND                     
C4F10            CAP_A_0402V-0.01UF,25V,10%,X7RA 1        M_A_VREF                
                                  2        GND                     
C4F11            CAPP_7343-220UF,4V,20%,POSCAP,A 1        PVPP_GHJ                
                                  2        GND                     
C4F12            CAP_0402LF-3300PF,50V,10%,EMPTA 1        VR_PVPP_GHJ_PHASE       
                                  2        VR_PVPP_GHJ_SNUB        
C4G1             CAP_A_0402V-0.01UF,25V,10%,X7RA 1        M_B_CPU_VREF            
                                  2        GND                     
C4G2             CAP_0805-10UF,16V,10%,X6S,C953A 1        VR_FET_SW_P12V_STBY_PVPP_GHJ
                                  2        GND                     
C4G3             CAP_A_0402V-0.01UF,25V,10%,X7RA 1        M_B_VREF                
                                  2        GND                     
C4G4             CAP_0402-1.0UF,16V,10%,X6S,D97A 1        VR_FET_SW_P12V_STBY_PVPP_GHJ
                                  2        GND                     
C4G5             CAP_1210-47UF,16V,20%,X6S,D384A 1        VR_FET_SW_P12V_STBY_PVPP_GHJ
                                  2        GND                     
C4G6             CAP_0402LF-100.0PF,50V,5%,COG,A 1        VR_FB_PVPP_GHJ          
                                  2        VR_COMP_PVPP_GHJ_3      
C4G7             CAP_0402LF-1000PF,50V,10%,EMPTA 1        FM_PVPP_CPU1_EN         
                                  2        AGND_PVPP_GHJ           
C4G8             CAP_0402-0.027UF,16V,10%,X7R,AA 1        VR_PVPP_GHJ_SS          
                                  2        AGND_PVPP_GHJ           
C4G9             CAP_0402LF-1000PF,50V,10%,X7R,A 1        PWRGD_PVPP_GHJ_R        
                                  2        GND                     
C4G10            CAP_0402LF-2200PF,50V,10%,X7R,A 1        VR_COMP_RC_PVPP_GHJ     
                                  2        VR_COMP_PVPP_GHJ_3      
C4G11            CAP_0402LF-2200PF,50V,10%,X7R,A 1        VR_COMP_PVPP_GHJ        
                                  2        VR_FB_PVPP_GHJ          
C4G12            CAP_0402LF-1000PF,50V,10%,EMPTA 1        FM_PVTT_GHJ_EN_R        
                                  2        GND                     
C4G13            CAP_0402LF-1000PF,50V,10%,X7R,A 1        PWRGD_PVTT_GHJ_CPU1_R   
                                  2        GND                     
C4G14            CAP_0402LF-1000PF,50V,10%,X7R,A 1        PWRGD_PVTT_ABC_CPU0_R   
                                  2        GND                     
C4G15            CAP_0402-1.0UF,16V,10%,X6S,D97A 1        VR_PVTT_ABC_BIAS        
                                  2        GND                     
C4G16            CAP_0402-1.0UF,16V,10%,X6S,D97A 1        VR_PVTT_ABC_VREF        
                                  2        GND                     
C4G17            CAP_A_0402V-0.01UF,25V,10%,X7RA 1        M_C_CPU_VREF            
                                  2        GND                     
C4G18            CAP_0402-1.0UF,16V,10%,X6S,D97A 1        VR_PVTT_GHJ_BIAS        
                                  2        GND                     
C4G19            CAP_A_0402V-0.01UF,25V,10%,X7RA 1        M_C_VREF                
                                  2        GND                     
C4G20            CAP_0805LF-22UF,4V,20%,X6S,C95A 1        PVTT_GHJ                
                                  2        GND                     
C4G21            CAP_0402-1.0UF,16V,10%,X6S,D97A 1        VR_PVTT_GHJ_VREF        
                                  2        GND                     
C4G22            CAP_A_0402V-0.1UF,16V,10%,X7R,A 1        PVCCIO_CPU1             
                                  2        GND                     
C4G23            CAP_0402LF-1000PF,50V,10%,EMPTA 1        FM_PVTT_ABC_EN_R        
                                  2        GND                     
C4G24            CAP_0805LF-22UF,4V,20%,X6S,C95A 1        PVTT_ABC                
                                  2        GND                     
C4G25            CAP_A_0402V-0.1UF,16V,10%,X7R,A 1        PVPP_GHJ                
                                  2        GND                     
C4G26            CAP_0603LF-0.1UF,25V,10%,X7R,6A 1        VR_PVPP_GHJ_PHASE       
                                  2        VR_PVPP_GHJ_BOOT_R      
C4L1             CAP_0603LF-10UF,4V,20%,X6S,E15A 1        PVPP_DEF                
                                  2        GND                     
C4L2             CAP_0603LF-10UF,4V,20%,X6S,E15A 1        PVPP_DEF                
                                  2        GND                     
C4L3             CAP_0603LF-10UF,4V,20%,X6S,E15A 1        PVPP_DEF                
                                  2        GND                     
C4L4             CAP_0603LF-10UF,4V,20%,X6S,E15A 1        PVPP_DEF                
                                  2        GND                     
C4L5             CAPP_3018-470UF,2.5V,20%,ALUM,A 1        PVDDQ_DEF               
                                  2        GND                     
C4M1             CAPP_7343-220UF,4V,20%,POSCAP,A 1        PVPP_DEF                
                                  2        GND                     
C4M2             CAP_A_0603V-22.0UF,4V,20%,X6S,A 1        PVDDQ_DEF               
                                  2        GND                     
C4M3             CAP_0603LF-10UF,4V,20%,X6S,E15A 1        PVPP_DEF                
                                  2        GND                     
C4M4             CAP_0603LF-10UF,4V,20%,X6S,E15A 1        PVPP_DEF                
                                  2        GND                     
C4M5             CAP_A_0603V-47UF,4V,20%,X5R,60A 1        PVDDQ_DEF               
                                  2        GND                     
C4M6             CAPP_3018-68UF,16V,20%,TANT,72A 1        P12V_STBY               
                                  2        GND                     
C4M7             CAPP_3018-68UF,16V,20%,TANT,72A 1        P12V_STBY               
                                  2        GND                     
C4P1             CAP_0805-47UF,4V,20%,X6S,C9533A 1        PVCCIO_CPU0             
                                  2        GND                     
C4P2             CAP_0805-47UF,4V,20%,X6S,C9533A 1        PVCCMCP_CPU0            
                                  2        GND                     
C4P3             CAP_0805-47UF,4V,20%,X6S,C9533A 1        PVCCMCP_CPU0            
                                  2        GND                     
C4P4             CAP_0805-47UF,4V,20%,X6S,C9533A 1        PVCCMCP_CPU0            
                                  2        GND                     
C4P5             CAP_0805-47UF,4V,20%,X6S,C9533A 1        PVCCMCP_CPU0            
                                  2        GND                     
C4P6             CAP_A_0603V-22.0UF,4V,20%,X6S,A 1        PVCCIO_CPU0             
                                  2        GND                     
C4P7             CAP_0805-47UF,4V,20%,X6S,C9533A 1        PVCCMCP_CPU0            
                                  2        GND                     
C4P8             CAP_A_0603V-22.0UF,4V,20%,X6S,A 1        PVCCIO_CPU0             
                                  2        GND                     
C4P9             CAP_0805-47UF,4V,20%,X6S,C9533A 1        PVCCIO_CPU0             
                                  2        GND                     
C4P10            CAP_0805-47UF,4V,20%,X6S,C9533A 1        PVCCIO_CPU0             
                                  2        GND                     
C4R1             CAPP_3018-470UF,2.5V,20%,ALUM,A 1        PVCCMCP_CPU0            
                                  2        GND                     
C4R2             CAP_A_0402V-0.1UF,16V,10%,X7R,A 1        JTAG_MCP_CPU0_TDI_R     
                                  2        GND                     
C4T1             CAP_A_0402V-1.0UF,6.3V,10%,X6SA 1        P1V8_MCP_CPU0           
                                  2        GND                     
C4T2             CAP_A_0402V-1.0UF,6.3V,10%,X6SA 1        P1V8_MCP_CPU0           
                                  2        GND                     
C4T3             CAPP_7343-220UF,4V,20%,POSCAP,A 1        PVPP_ABC                
                                  2        GND                     
C4T4             CAP_0805-100UF,4V,20%,X5R,6024A 1        PVDDQ_ABC               
                                  2        GND                     
C4T5             CAP_0603LF-10UF,4V,20%,X6S,E15A 1        PVPP_ABC                
                                  2        GND                     
C4T6             CAP_0603LF-10UF,4V,20%,X6S,E15A 1        PVPP_ABC                
                                  2        GND                     
C4U1             CAP_0603LF-10UF,4V,20%,X6S,E15A 1        PVPP_ABC                
                                  2        GND                     
C4U2             CAP_0603LF-10UF,4V,20%,X6S,E15A 1        PVPP_ABC                
                                  2        GND                     
C4U3             CAP_0603LF-10UF,4V,20%,X6S,E15A 1        PVPP_ABC                
                                  2        GND                     
C4U4             CAP_0603LF-10UF,4V,20%,X6S,E15A 1        PVPP_ABC                
                                  2        GND                     
C5A1             CAP_A_0603V-22.0UF,4V,20%,X6S,A 1        PVDDQ_DEF               
                                  2        GND                     
C5A2             CAP_A_0603V-22.0UF,4V,20%,X6S,A 1        PVDDQ_DEF               
                                  2        GND                     
C5A3             CAP_A_0603V-22.0UF,4V,20%,X6S,A 1        PVDDQ_DEF               
                                  2        GND                     
C5A4             CAP_A_0603V-22.0UF,4V,20%,X6S,A 1        PVDDQ_DEF               
                                  2        GND                     
C5A5             CAP_A_0603V-47UF,4V,20%,X5R,60A 1        PVDDQ_DEF               
                                  2        GND                     
C5A6             CAP_A_0603V-22.0UF,4V,20%,X6S,A 1        PVDDQ_DEF               
                                  2        GND                     
C5A7             CAP_A_0603V-22.0UF,4V,20%,X6S,A 1        PVDDQ_DEF               
                                  2        GND                     
C5A8             CAP_A_0603V-22.0UF,4V,20%,X6S,A 1        PVDDQ_DEF               
                                  2        GND                     
C5A9             CAP_A_0603V-22.0UF,4V,20%,X6S,A 1        PVDDQ_DEF               
                                  2        GND                     
C5A10            CAP_0805-100UF,4V,20%,X5R,6024A 1        PVDDQ_DEF               
                                  2        GND                     
C5A11            CAP_A_0603V-22.0UF,4V,20%,X6S,A 1        PVDDQ_DEF               
                                  2        GND                     
C5A12            CAP_A_0603V-22.0UF,4V,20%,X6S,A 1        PVDDQ_DEF               
                                  2        GND                     
C5A13            CAP_A_0603V-22.0UF,4V,20%,X6S,A 1        PVDDQ_DEF               
                                  2        GND                     
C5A14            CAP_A_0603V-22.0UF,4V,20%,X6S,A 1        PVDDQ_DEF               
                                  2        GND                     
C5A15            CAP_A_0603V-22.0UF,4V,20%,X6S,A 1        PVDDQ_DEF               
                                  2        GND                     
C5A16            CAP_A_0603V-22.0UF,4V,20%,X6S,A 1        PVDDQ_DEF               
                                  2        GND                     
C5A17            CAP_A_0603V-22.0UF,4V,20%,X6S,A 1        PVDDQ_DEF               
                                  2        GND                     
C5A18            CAP_A_0603V-22.0UF,4V,20%,X6S,A 1        PVDDQ_DEF               
                                  2        GND                     
C5A19            CAP_A_0603V-22.0UF,4V,20%,X6S,A 1        PVDDQ_DEF               
                                  2        GND                     
C5A20            CAP_0805-100UF,4V,20%,X5R,6024A 1        PVDDQ_DEF               
                                  2        GND                     
C5B1             CAP_A_0603V-47UF,4V,20%,X5R,60A 1        PVDDQ_DEF               
                                  2        GND                     
C5B2             CAP_A_0603V-47UF,4V,20%,X5R,60A 1        PVDDQ_DEF               
                                  2        GND                     
C5D1             CAP_A_0603V-22.0UF,4V,20%,X6S,A 1        PVCCIN_CPU0             
                                  2        GND                     
C5D2             CAP_A_0603V-22.0UF,4V,20%,X6S,A 1        PVCCIN_CPU0             
                                  2        GND                     
C5D3             CAP_A_0603V-22.0UF,4V,20%,X6S,A 1        PVCCIN_CPU0             
                                  2        GND                     
C5D4             CAP_A_0603V-22.0UF,4V,20%,X6S,A 1        PVCCIN_CPU0             
                                  2        GND                     
C5D5             CAP_A_0603V-22.0UF,4V,20%,X6S,A 1        PVCCIN_CPU0             
                                  2        GND                     
C5D6             CAP_0603LF-10UF,4V,20%,X6S,E15A 1        PVDDQ_DEF               
                                  2        GND                     
C5D7             CAP_0603LF-10UF,4V,20%,X6S,E15A 1        PVDDQ_DEF               
                                  2        GND                     
C5D8             CAP_0603LF-10UF,4V,20%,X6S,E15A 1        PVDDQ_DEF               
                                  2        GND                     
C5D9             CAP_0603LF-10UF,4V,20%,X6S,E15A 1        PVDDQ_DEF               
                                  2        GND                     
C5D10            CAP_0603LF-10UF,4V,20%,X6S,E15A 1        PVSA_CPU0               
                                  2        GND                     
C5D11            CAP_0603LF-10UF,4V,20%,X6S,E15A 1        PVSA_CPU0               
                                  2        GND                     
C5D12            CAP_0603LF-10UF,4V,20%,X6S,E15A 1        PVSA_CPU0               
                                  2        GND                     
C5D13            CAP_0603LF-10UF,4V,20%,X6S,E15A 1        PVSA_CPU0               
                                  2        GND                     
C5D14            CAP_A_0603V-22.0UF,4V,20%,X6S,A 1        PVCCIN_CPU0             
                                  2        GND                     
C5D15            CAP_A_0603V-22.0UF,4V,20%,X6S,A 1        PVCCIN_CPU0             
                                  2        GND                     
C5D16            CAP_A_0603V-22.0UF,4V,20%,X6S,A 1        PVCCIN_CPU0             
                                  2        GND                     
C5D17            CAP_A_0603V-22.0UF,4V,20%,X6S,A 1        PVCCIN_CPU0             
                                  2        GND                     
C5D18            CAP_A_0603V-22.0UF,4V,20%,X6S,A 1        PVCCIN_CPU0             
                                  2        GND                     
C5D19            CAP_A_0603V-22.0UF,4V,20%,X6S,A 1        PVCCIN_CPU0             
                                  2        GND                     
C5D20            CAP_A_0603V-22.0UF,4V,20%,X6S,A 1        PVCCMCP_CPU0            
                                  2        GND                     
C5D21            CAP_A_0603V-22.0UF,4V,20%,X6S,A 1        PVCCMCP_CPU0            
                                  2        GND                     
C5D22            CAP_A_0603V-22.0UF,4V,20%,X6S,A 1        PVCCMCP_CPU0            
                                  2        GND                     
C5D23            CAP_A_0603V-22.0UF,4V,20%,X6S,A 1        PVCCMCP_CPU0            
                                  2        GND                     
C5D24            CAP_A_0603V-22.0UF,4V,20%,X6S,A 1        PVCCIN_CPU0             
                                  2        GND                     
C5D25            CAP_A_0603V-22.0UF,4V,20%,X6S,A 1        PVCCIN_CPU0             
                                  2        GND                     
C5D26            CAP_A_0603V-22.0UF,4V,20%,X6S,A 1        PVCCIN_CPU0             
                                  2        GND                     
C5D27            CAP_A_0603V-22.0UF,4V,20%,X6S,A 1        PVCCIN_CPU0             
                                  2        GND                     
C5D28            CAP_A_0603V-22.0UF,4V,20%,X6S,A 1        PVCCIN_CPU0             
                                  2        GND                     
C5D29            CAP_A_0603V-22.0UF,4V,20%,X6S,A 1        PVCCIN_CPU0             
                                  2        GND                     
C5D30            CAP_A_0603V-22.0UF,4V,20%,X6S,A 1        PVCCIN_CPU0             
                                  2        GND                     
C5D31            CAP_A_0603V-22.0UF,4V,20%,X6S,A 1        PVCCIN_CPU0             
                                  2        GND                     
C5D32            CAP_A_0603V-22.0UF,4V,20%,X6S,A 1        PVCCIN_CPU0             
                                  2        GND                     
C5D33            CAP_A_0603V-22.0UF,4V,20%,X6S,A 1        PVCCMCP_CPU0            
                                  2        GND                     
C5D34            CAP_A_0603V-22.0UF,4V,20%,X6S,A 1        PVCCMCP_CPU0            
                                  2        GND                     
C5D35            CAP_A_0603V-22.0UF,4V,20%,X6S,A 1        PVCCMCP_CPU0            
                                  2        GND                     
C5D36            CAP_A_0603V-22.0UF,4V,20%,X6S,A 1        PVCCMCP_CPU0            
                                  2        GND                     
C5D37            CAP_A_0603V-22.0UF,4V,20%,X6S,A 1        PVCCMCP_CPU0            
                                  2        GND                     
C5D38            CAP_A_0603V-22.0UF,4V,20%,X6S,A 1        PVCCMCP_CPU0            
                                  2        GND                     
C5D39            CAP_A_0603V-22.0UF,4V,20%,X6S,A 1        PVCCIN_CPU0             
                                  2        GND                     
C5D40            CAP_A_0603V-22.0UF,4V,20%,X6S,A 1        PVCCIN_CPU0             
                                  2        GND                     
C5D41            CAP_A_0603V-22.0UF,4V,20%,X6S,A 1        PVCCIN_CPU0             
                                  2        GND                     
C5D42            CAP_A_0603V-22.0UF,4V,20%,X6S,A 1        PVCCIN_CPU0             
                                  2        GND                     
C5D43            CAP_A_0603V-22.0UF,4V,20%,X6S,A 1        PVCCIN_CPU0             
                                  2        GND                     
C5D44            CAP_A_0603V-22.0UF,4V,20%,X6S,A 1        PVCCIN_CPU0             
                                  2        GND                     
C5D45            CAP_A_0603V-22.0UF,4V,20%,X6S,A 1        PVCCIN_CPU0             
                                  2        GND                     
C5D46            CAP_A_0603V-22.0UF,4V,20%,X6S,A 1        PVCCIN_CPU0             
                                  2        GND                     
C5D47            CAP_A_0603V-22.0UF,4V,20%,X6S,A 1        PVCCIN_CPU0             
                                  2        GND                     
C5D48            CAP_A_0603V-22.0UF,4V,20%,X6S,A 1        PVCCMCP_CPU0            
                                  2        GND                     
C5D49            CAP_A_0603V-22.0UF,4V,20%,X6S,A 1        PVCCMCP_CPU0            
                                  2        GND                     
C5D50            CAP_A_0603V-22.0UF,4V,20%,X6S,A 1        PVCCMCP_CPU0            
                                  2        GND                     
C5D51            CAP_A_0603V-22.0UF,4V,20%,X6S,A 1        PVCCMCP_CPU0            
                                  2        GND                     
C5D52            CAP_A_0603V-22.0UF,4V,20%,X6S,A 1        PVCCMCP_CPU0            
                                  2        GND                     
C5D53            CAP_A_0603V-22.0UF,4V,20%,X6S,A 1        PVCCMCP_CPU0            
                                  2        GND                     
C5D54            CAP_0603LF-10UF,4V,20%,X6S,E15A 1        PVDDQ_ABC               
                                  2        GND                     
C5D55            CAP_0603LF-10UF,4V,20%,X6S,E15A 1        PVDDQ_ABC               
                                  2        GND                     
C5D56            CAP_0603LF-10UF,4V,20%,X6S,E15A 1        PVDDQ_ABC               
                                  2        GND                     
C5D57            CAP_0603LF-10UF,4V,20%,X6S,E15A 1        PVDDQ_ABC               
                                  2        GND                     
C5D58            CAP_A_0603V-22.0UF,4V,20%,X6S,A 1        PVCCIN_CPU0             
                                  2        GND                     
C5D59            CAP_A_0603V-22.0UF,4V,20%,X6S,A 1        PVCCIN_CPU0             
                                  2        GND                     
C5D60            CAP_A_0603V-22.0UF,4V,20%,X6S,A 1        PVCCIN_CPU0             
                                  2        GND                     
C5D61            CAP_A_0603V-22.0UF,4V,20%,X6S,A 1        PVCCIN_CPU0             
                                  2        GND                     
C5F1             CAP_A_0603V-47UF,4V,20%,X5R,60A 1        PVDDQ_ABC               
                                  2        GND                     
C5F2             CAP_A_0603V-47UF,4V,20%,X5R,60A 1        PVDDQ_ABC               
                                  2        GND                     
C5G1             CAP_A_0603V-22.0UF,4V,20%,X6S,A 1        PVDDQ_ABC               
                                  2        GND                     
C5G2             CAP_A_0603V-22.0UF,4V,20%,X6S,A 1        PVDDQ_ABC               
                                  2        GND                     
C5G3             CAP_A_0603V-22.0UF,4V,20%,X6S,A 1        PVDDQ_ABC               
                                  2        GND                     
C5G4             CAP_A_0603V-22.0UF,4V,20%,X6S,A 1        PVDDQ_ABC               
                                  2        GND                     
C5G5             CAP_A_0603V-22.0UF,4V,20%,X6S,A 1        PVDDQ_ABC               
                                  2        GND                     
C5G6             CAP_A_0603V-22.0UF,4V,20%,X6S,A 1        PVDDQ_ABC               
                                  2        GND                     
C5G7             CAP_A_0603V-22.0UF,4V,20%,X6S,A 1        PVDDQ_ABC               
                                  2        GND                     
C5G8             CAP_A_0603V-22.0UF,4V,20%,X6S,A 1        PVDDQ_ABC               
                                  2        GND                     
C5G9             CAP_0805-100UF,4V,20%,X5R,6024A 1        PVDDQ_ABC               
                                  2        GND                     
C5G10            CAP_A_0603V-47UF,4V,20%,X5R,60A 1        PVDDQ_ABC               
                                  2        GND                     
C5G11            CAP_A_0603V-22.0UF,4V,20%,X6S,A 1        PVDDQ_ABC               
                                  2        GND                     
C5G12            CAP_A_0603V-22.0UF,4V,20%,X6S,A 1        PVDDQ_ABC               
                                  2        GND                     
C5G13            CAP_A_0603V-22.0UF,4V,20%,X6S,A 1        PVDDQ_ABC               
                                  2        GND                     
C5G14            CAP_A_0603V-22.0UF,4V,20%,X6S,A 1        PVDDQ_ABC               
                                  2        GND                     
C5G15            CAP_A_0603V-22.0UF,4V,20%,X6S,A 1        PVDDQ_ABC               
                                  2        GND                     
C5G16            CAP_A_0603V-22.0UF,4V,20%,X6S,A 1        PVDDQ_ABC               
                                  2        GND                     
C5G17            CAP_A_0603V-22.0UF,4V,20%,X6S,A 1        PVDDQ_ABC               
                                  2        GND                     
C5G18            CAP_A_0603V-22.0UF,4V,20%,X6S,A 1        PVDDQ_ABC               
                                  2        GND                     
C5G19            CAP_A_0603V-47UF,4V,20%,X5R,60A 1        PVDDQ_ABC               
                                  2        GND                     
C5G20            CAP_0805-100UF,4V,20%,X5R,6024A 1        PVDDQ_ABC               
                                  2        GND                     
C5G21            CAP_0805-100UF,4V,20%,X5R,6024A 1        PVDDQ_ABC               
                                  2        GND                     
C5G22            CAP_0805-100UF,4V,20%,X5R,6024A 1        PVDDQ_ABC               
                                  2        GND                     
C5G41            CAP_A_0603V-22.0UF,4V,20%,X6S,A 1        PVDDQ_ABC               
                                  2        GND                     
C5G42            CAP_A_0603V-22.0UF,4V,20%,X6S,A 1        PVDDQ_ABC               
                                  2        GND                     
C5G43            CAP_A_0603V-22.0UF,4V,20%,X6S,A 1        PVDDQ_ABC               
                                  2        GND                     
C5G44            CAP_A_0603V-22.0UF,4V,20%,X6S,A 1        PVDDQ_ABC               
                                  2        GND                     
C5G45            CAP_A_0603V-22.0UF,4V,20%,X6S,A 1        PVDDQ_ABC               
                                  2        GND                     
C5G46            CAP_A_0603V-22.0UF,4V,20%,X6S,A 1        PVDDQ_ABC               
                                  2        GND                     
C5G47            CAP_A_0603V-22.0UF,4V,20%,X6S,A 1        PVDDQ_ABC               
                                  2        GND                     
C5G48            CAP_A_0603V-22.0UF,4V,20%,X6S,A 1        PVDDQ_ABC               
                                  2        GND                     
C5G49            CAP_A_0603V-22.0UF,4V,20%,X6S,A 1        PVDDQ_ABC               
                                  2        GND                     
C5G50            CAP_A_0603V-22.0UF,4V,20%,X6S,A 1        PVDDQ_ABC               
                                  2        GND                     
C5G51            CAP_A_0603V-22.0UF,4V,20%,X6S,A 1        PVDDQ_ABC               
                                  2        GND                     
C5G52            CAP_A_0603V-22.0UF,4V,20%,X6S,A 1        PVDDQ_ABC               
                                  2        GND                     
C5G53            CAP_A_0603V-22.0UF,4V,20%,X6S,A 1        PVDDQ_ABC               
                                  2        GND                     
C5G54            CAP_A_0603V-22.0UF,4V,20%,X6S,A 1        PVDDQ_ABC               
                                  2        GND                     
C5G55            CAP_A_0603V-22.0UF,4V,20%,X6S,A 1        PVDDQ_ABC               
                                  2        GND                     
C5G56            CAP_A_0603V-22.0UF,4V,20%,X6S,A 1        PVDDQ_ABC               
                                  2        GND                     
C5G57            CAP_A_0603V-22.0UF,4V,20%,X6S,A 1        PVDDQ_ABC               
                                  2        GND                     
C5G58            CAP_A_0603V-22.0UF,4V,20%,X6S,A 1        PVDDQ_ABC               
                                  2        GND                     
C5G59            CAP_A_0603V-22.0UF,4V,20%,X6S,A 1        PVDDQ_DEF               
                                  2        GND                     
C5G60            CAP_A_0603V-22.0UF,4V,20%,X6S,A 1        PVDDQ_DEF               
                                  2        GND                     
C5G61            CAP_A_0603V-22.0UF,4V,20%,X6S,A 1        PVDDQ_DEF               
                                  2        GND                     
C5G62            CAP_A_0603V-22.0UF,4V,20%,X6S,A 1        PVDDQ_DEF               
                                  2        GND                     
C5G63            CAP_A_0603V-22.0UF,4V,20%,X6S,A 1        PVDDQ_DEF               
                                  2        GND                     
C5G64            CAP_A_0603V-22.0UF,4V,20%,X6S,A 1        PVDDQ_DEF               
                                  2        GND                     
C5G65            CAP_A_0603V-22.0UF,4V,20%,X6S,A 1        PVDDQ_DEF               
                                  2        GND                     
C5G66            CAP_A_0603V-22.0UF,4V,20%,X6S,A 1        PVDDQ_DEF               
                                  2        GND                     
C5G67            CAP_A_0603V-22.0UF,4V,20%,X6S,A 1        PVDDQ_DEF               
                                  2        GND                     
C5G68            CAP_A_0603V-22.0UF,4V,20%,X6S,A 1        PVDDQ_DEF               
                                  2        GND                     
C5G69            CAP_A_0603V-22.0UF,4V,20%,X6S,A 1        PVDDQ_DEF               
                                  2        GND                     
C5G70            CAP_A_0603V-22.0UF,4V,20%,X6S,A 1        PVDDQ_DEF               
                                  2        GND                     
C5G71            CAP_A_0603V-22.0UF,4V,20%,X6S,A 1        PVDDQ_DEF               
                                  2        GND                     
C5G72            CAP_A_0603V-22.0UF,4V,20%,X6S,A 1        PVDDQ_DEF               
                                  2        GND                     
C5G73            CAP_A_0603V-22.0UF,4V,20%,X6S,A 1        PVDDQ_DEF               
                                  2        GND                     
C5G74            CAP_A_0603V-22.0UF,4V,20%,X6S,A 1        PVDDQ_DEF               
                                  2        GND                     
C5G75            CAP_A_0603V-22.0UF,4V,20%,X6S,A 1        PVDDQ_DEF               
                                  2        GND                     
C5G76            CAP_A_0603V-22.0UF,4V,20%,X6S,A 1        PVDDQ_DEF               
                                  2        GND                     
C5G77            CAP_0805-100UF,4V,20%,X5R,6024A 1        PVDDQ_DEF               
                                  2        GND                     
C5G78            CAP_0805-100UF,4V,20%,X5R,6024A 1        PVDDQ_DEF               
                                  2        GND                     
C5G79            CAP_A_0603V-22.0UF,4V,20%,X6S,A 1        PVDDQ_GHJ               
                                  2        GND                     
C5G80            CAP_A_0603V-22.0UF,4V,20%,X6S,A 1        PVDDQ_GHJ               
                                  2        GND                     
C5G81            CAP_A_0603V-22.0UF,4V,20%,X6S,A 1        PVDDQ_GHJ               
                                  2        GND                     
C5G82            CAP_A_0603V-22.0UF,4V,20%,X6S,A 1        PVDDQ_GHJ               
                                  2        GND                     
C5G83            CAP_A_0603V-22.0UF,4V,20%,X6S,A 1        PVDDQ_GHJ               
                                  2        GND                     
C5G84            CAP_A_0603V-22.0UF,4V,20%,X6S,A 1        PVDDQ_GHJ               
                                  2        GND                     
C5G85            CAP_A_0603V-22.0UF,4V,20%,X6S,A 1        PVDDQ_GHJ               
                                  2        GND                     
C5G86            CAP_A_0603V-22.0UF,4V,20%,X6S,A 1        PVDDQ_GHJ               
                                  2        GND                     
C5G87            CAP_A_0603V-22.0UF,4V,20%,X6S,A 1        PVDDQ_GHJ               
                                  2        GND                     
C5G88            CAP_A_0603V-22.0UF,4V,20%,X6S,A 1        PVDDQ_GHJ               
                                  2        GND                     
C5G89            CAP_A_0603V-22.0UF,4V,20%,X6S,A 1        PVDDQ_GHJ               
                                  2        GND                     
C5G90            CAP_A_0603V-22.0UF,4V,20%,X6S,A 1        PVDDQ_GHJ               
                                  2        GND                     
C5G91            CAP_A_0603V-22.0UF,4V,20%,X6S,A 1        PVDDQ_GHJ               
                                  2        GND                     
C5G92            CAP_A_0603V-22.0UF,4V,20%,X6S,A 1        PVDDQ_GHJ               
                                  2        GND                     
C5G93            CAP_A_0603V-22.0UF,4V,20%,X6S,A 1        PVDDQ_GHJ               
                                  2        GND                     
C5G94            CAP_A_0603V-22.0UF,4V,20%,X6S,A 1        PVDDQ_GHJ               
                                  2        GND                     
C5G95            CAP_A_0603V-22.0UF,4V,20%,X6S,A 1        PVDDQ_GHJ               
                                  2        GND                     
C5G96            CAP_A_0603V-22.0UF,4V,20%,X6S,A 1        PVDDQ_GHJ               
                                  2        GND                     
C5G97            CAP_A_0603V-22.0UF,4V,20%,X6S,A 1        PVDDQ_KLM               
                                  2        GND                     
C5G98            CAP_A_0603V-22.0UF,4V,20%,X6S,A 1        PVDDQ_KLM               
                                  2        GND                     
C5G99            CAP_A_0603V-22.0UF,4V,20%,X6S,A 1        PVDDQ_KLM               
                                  2        GND                     
C5G100           CAP_A_0603V-22.0UF,4V,20%,X6S,A 1        PVDDQ_KLM               
                                  2        GND                     
C5G101           CAP_A_0603V-22.0UF,4V,20%,X6S,A 1        PVDDQ_KLM               
                                  2        GND                     
C5G102           CAP_A_0603V-22.0UF,4V,20%,X6S,A 1        PVDDQ_KLM               
                                  2        GND                     
C5G103           CAP_A_0603V-22.0UF,4V,20%,X6S,A 1        PVDDQ_KLM               
                                  2        GND                     
C5G104           CAP_A_0603V-22.0UF,4V,20%,X6S,A 1        PVDDQ_KLM               
                                  2        GND                     
C5G105           CAP_A_0603V-22.0UF,4V,20%,X6S,A 1        PVDDQ_KLM               
                                  2        GND                     
C5G106           CAP_A_0603V-22.0UF,4V,20%,X6S,A 1        PVDDQ_KLM               
                                  2        GND                     
C5G107           CAP_A_0603V-22.0UF,4V,20%,X6S,A 1        PVDDQ_KLM               
                                  2        GND                     
C5G108           CAP_A_0603V-22.0UF,4V,20%,X6S,A 1        PVDDQ_KLM               
                                  2        GND                     
C5G109           CAP_A_0603V-22.0UF,4V,20%,X6S,A 1        PVDDQ_KLM               
                                  2        GND                     
C5G110           CAP_A_0603V-22.0UF,4V,20%,X6S,A 1        PVDDQ_KLM               
                                  2        GND                     
C5G111           CAP_A_0603V-22.0UF,4V,20%,X6S,A 1        PVDDQ_KLM               
                                  2        GND                     
C5G112           CAP_A_0603V-22.0UF,4V,20%,X6S,A 1        PVDDQ_KLM               
                                  2        GND                     
C5G113           CAP_A_0603V-22.0UF,4V,20%,X6S,A 1        PVDDQ_KLM               
                                  2        GND                     
C5G114           CAP_A_0603V-22.0UF,4V,20%,X6S,A 1        PVDDQ_KLM               
                                  2        GND                     
C5G115           CAP_0805-100UF,4V,20%,X5R,6024A 1        PVDDQ_KLM               
                                  2        GND                     
C5G116           CAP_0805-100UF,4V,20%,X5R,6024A 1        PVDDQ_KLM               
                                  2        GND                     
C5G117           CAP_0805-100UF,4V,20%,X5R,6024A 1        PVDDQ_GHJ               
                                  2        GND                     
C5G118           CAP_0805-100UF,4V,20%,X5R,6024A 1        PVDDQ_GHJ               
                                  2        GND                     
C5L1             CAP_0805-100UF,4V,20%,X5R,6024A 1        PVDDQ_DEF               
                                  2        GND                     
C5L2             CAP_0805-100UF,4V,20%,X5R,6024A 1        PVDDQ_DEF               
                                  2        GND                     
C5L3             CAP_0805-100UF,4V,20%,X5R,6024A 1        PVDDQ_DEF               
                                  2        GND                     
C5L4             CAP_A_0603V-47UF,4V,20%,X5R,60A 1        PVTT_DEF                
                                  2        GND                     
C5L5             CAP_A_0603V-47UF,4V,20%,X5R,60A 1        PVTT_DEF                
                                  2        GND                     
C5L6             CAP_A_0603V-22.0UF,4V,20%,X6S,A 1        PVDDQ_DEF               
                                  2        GND                     
C5L7             CAP_A_0603V-22.0UF,4V,20%,X6S,A 1        PVDDQ_DEF               
                                  2        GND                     
C5L8             CAP_A_0603V-22.0UF,4V,20%,X6S,A 1        PVDDQ_DEF               
                                  2        GND                     
C5L9             CAP_A_0603V-22.0UF,4V,20%,X6S,A 1        PVDDQ_DEF               
                                  2        GND                     
C5L10            CAP_A_0603V-22.0UF,4V,20%,X6S,A 1        PVDDQ_DEF               
                                  2        GND                     
C5L11            CAP_A_0603V-22.0UF,4V,20%,X6S,A 1        PVDDQ_DEF               
                                  2        GND                     
C5L12            CAP_A_0603V-22.0UF,4V,20%,X6S,A 1        PVDDQ_DEF               
                                  2        GND                     
C5L13            CAP_A_0603V-22.0UF,4V,20%,X6S,A 1        PVDDQ_DEF               
                                  2        GND                     
C5L14            CAP_0805-100UF,4V,20%,X5R,6024A 1        PVDDQ_DEF               
                                  2        GND                     
C5L15            CAP_A_0603V-47UF,4V,20%,X5R,60A 1        PVDDQ_DEF               
                                  2        GND                     
C5M1             CAP_A_0603V-22.0UF,4V,20%,X6S,A 1        PVDDQ_DEF               
                                  2        GND                     
C5M2             CAP_A_0603V-22.0UF,4V,20%,X6S,A 1        PVDDQ_DEF               
                                  2        GND                     
C5M3             CAP_A_0603V-47UF,4V,20%,X5R,60A 1        PVDDQ_DEF               
                                  2        GND                     
C5M4             CAP_A_0603V-22.0UF,4V,20%,X6S,A 1        PVDDQ_DEF               
                                  2        GND                     
C5M5             CAP_A_0603V-22.0UF,4V,20%,X6S,A 1        PVDDQ_DEF               
                                  2        GND                     
C5M6             CAP_A_0603V-22.0UF,4V,20%,X6S,A 1        PVDDQ_DEF               
                                  2        GND                     
C5M7             CAP_A_0603V-22.0UF,4V,20%,X6S,A 1        PVDDQ_DEF               
                                  2        GND                     
C5M8             CAP_0805-100UF,4V,20%,X5R,6024A 1        PVDDQ_DEF               
                                  2        GND                     
C5M9             CAP_A_0603V-47UF,4V,20%,X5R,60A 1        PVDDQ_DEF               
                                  2        GND                     
C5M10            CAP_A_0603V-47UF,4V,20%,X5R,60A 1        PVDDQ_DEF               
                                  2        GND                     
C5M11            CAP_A_0603V-47UF,4V,20%,X5R,60A 1        PVDDQ_DEF               
                                  2        GND                     
C5M12            CAP_0805-100UF,4V,20%,X5R,6024A 1        PVDDQ_DEF               
                                  2        GND                     
C5M13            CAP_A_0603V-47UF,4V,20%,X5R,60A 1        PVTT_DEF                
                                  2        GND                     
C5P1             CAP_0805LF-22UF,4V,20%,X6S,C95A 1        PVDDQ_DEF               
                                  2        GND                     
C5P2             CAP_0805LF-22UF,4V,20%,X6S,C95A 1        PVDDQ_DEF               
                                  2        GND                     
C5P3             CAP_0805-47UF,4V,20%,X6S,C9533A 1        PVCCIN_CPU0             
                                  2        GND                     
C5P4             CAP_0805-47UF,4V,20%,X6S,C9533A 1        PVCCIN_CPU0             
                                  2        GND                     
C5P5             CAP_0805-47UF,4V,20%,X6S,C9533A 1        PVCCIN_CPU0             
                                  2        GND                     
C5P6             CAP_0805-47UF,4V,20%,X6S,C9533A 1        PVCCIN_CPU0             
                                  2        GND                     
C5P7             CAP_0805LF-22UF,4V,20%,X6S,C95A 1        PVSA_CPU0               
                                  2        GND                     
C5P8             CAP_0805LF-22UF,4V,20%,X6S,C95A 1        PVSA_CPU0               
                                  2        GND                     
C5P9             CAP_0805LF-22UF,4V,20%,X6S,C95A 1        PVSA_CPU0               
                                  2        GND                     
C5P10            CAP_0805-47UF,4V,20%,X6S,C9533A 1        PVCCMCP_CPU0            
                                  2        GND                     
C5P11            CAP_0805-47UF,4V,20%,X6S,C9533A 1        PVCCMCP_CPU0            
                                  2        GND                     
C5P12            CAP_0805-47UF,4V,20%,X6S,C9533A 1        PVCCMCP_CPU0            
                                  2        GND                     
C5P13            CAP_0805-47UF,4V,20%,X6S,C9533A 1        PVCCMCP_CPU0            
                                  2        GND                     
C5P14            CAP_0805-47UF,4V,20%,X6S,C9533A 1        PVCCIN_CPU0             
                                  2        GND                     
C5P15            CAP_0805-47UF,4V,20%,X6S,C9533A 1        PVCCIN_CPU0             
                                  2        GND                     
C5P16            CAP_0805-47UF,4V,20%,X6S,C9533A 1        PVCCIN_CPU0             
                                  2        GND                     
C5P17            CAP_0805-47UF,4V,20%,X6S,C9533A 1        PVCCIN_CPU0             
                                  2        GND                     
C5P18            CAP_0805-47UF,4V,20%,X6S,C9533A 1        PVCCMCP_CPU0            
                                  2        GND                     
C5P19            CAP_0805-47UF,4V,20%,X6S,C9533A 1        PVCCMCP_CPU0            
                                  2        GND                     
C5P20            CAP_0805-47UF,4V,20%,X6S,C9533A 1        PVCCMCP_CPU0            
                                  2        GND                     
C5P21            CAP_0805-47UF,4V,20%,X6S,C9533A 1        PVCCMCP_CPU0            
                                  2        GND                     
C5P22            CAP_0805-47UF,4V,20%,X6S,C9533A 1        PVCCIN_CPU0             
                                  2        GND                     
C5P23            CAP_0805-47UF,4V,20%,X6S,C9533A 1        PVCCIN_CPU0             
                                  2        GND                     
C5P24            CAP_0805-47UF,4V,20%,X6S,C9533A 1        PVCCIN_CPU0             
                                  2        GND                     
C5P25            CAP_0805-47UF,4V,20%,X6S,C9533A 1        PVCCIN_CPU0             
                                  2        GND                     
C5P26            CAP_0805-47UF,4V,20%,X6S,C9533A 1        PVCCIN_CPU0             
                                  2        GND                     
C5P27            CAP_0805-47UF,4V,20%,X6S,C9533A 1        PVCCIN_CPU0             
                                  2        GND                     
C5P28            CAP_0805-47UF,4V,20%,X6S,C9533A 1        PVCCMCP_CPU0            
                                  2        GND                     
C5P29            CAP_0805-47UF,4V,20%,X6S,C9533A 1        PVCCMCP_CPU0            
                                  2        GND                     
C5P30            CAP_0805-47UF,4V,20%,X6S,C9533A 1        PVCCMCP_CPU0            
                                  2        GND                     
C5P31            CAP_0805-47UF,4V,20%,X6S,C9533A 1        PVCCMCP_CPU0            
                                  2        GND                     
C5P32            CAP_0805-47UF,4V,20%,X6S,C9533A 1        PVCCIN_CPU0             
                                  2        GND                     
C5P33            CAP_0805-47UF,4V,20%,X6S,C9533A 1        PVCCIN_CPU0             
                                  2        GND                     
C5P34            CAP_0805-47UF,4V,20%,X6S,C9533A 1        PVCCIN_CPU0             
                                  2        GND                     
C5P35            CAP_0805-47UF,4V,20%,X6S,C9533A 1        PVCCIN_CPU0             
                                  2        GND                     
C5P36            CAP_0805-47UF,4V,20%,X6S,C9533A 1        PVCCIN_CPU0             
                                  2        GND                     
C5P37            CAP_0805-47UF,4V,20%,X6S,C9533A 1        PVCCIN_CPU0             
                                  2        GND                     
C5P38            CAP_0805LF-22UF,4V,20%,X6S,C95A 1        PVDDQ_ABC               
                                  2        GND                     
C5P39            CAP_0805LF-22UF,4V,20%,X6S,C95A 1        PVDDQ_ABC               
                                  2        GND                     
C5P40            CAP_0805-47UF,4V,20%,X6S,C9533A 1        PVCCIN_CPU0             
                                  2        GND                     
C5P41            CAP_0805-47UF,4V,20%,X6S,C9533A 1        PVCCIN_CPU0             
                                  2        GND                     
C5P42            CAP_0805-47UF,4V,20%,X6S,C9533A 1        PVCCIN_CPU0             
                                  2        GND                     
C5P43            CAP_0805-47UF,4V,20%,X6S,C9533A 1        PVCCIN_CPU0             
                                  2        GND                     
C5P44            CAP_0805-47UF,4V,20%,X6S,C9533A 1        PVCCIN_CPU0             
                                  2        GND                     
C5T1             CAP_A_0603V-47UF,4V,20%,X5R,60A 1        PVDDQ_ABC               
                                  2        GND                     
C5T2             CAP_A_0603V-47UF,4V,20%,X5R,60A 1        PVDDQ_ABC               
                                  2        GND                     
C5T3             CAP_A_0603V-47UF,4V,20%,X5R,60A 1        PVTT_ABC                
                                  2        GND                     
C5T4             CAP_A_0603V-47UF,4V,20%,X5R,60A 1        PVDDQ_ABC               
                                  2        GND                     
C5T5             CAP_A_0603V-22.0UF,4V,20%,X6S,A 1        PVDDQ_ABC               
                                  2        GND                     
C5T6             CAP_A_0603V-22.0UF,4V,20%,X6S,A 1        PVDDQ_ABC               
                                  2        GND                     
C5T7             CAP_A_0603V-22.0UF,4V,20%,X6S,A 1        PVDDQ_ABC               
                                  2        GND                     
C5T8             CAP_A_0603V-22.0UF,4V,20%,X6S,A 1        PVDDQ_ABC               
                                  2        GND                     
C5T9             CAP_A_0603V-22.0UF,4V,20%,X6S,A 1        PVDDQ_ABC               
                                  2        GND                     
C5T10            CAP_A_0603V-22.0UF,4V,20%,X6S,A 1        PVDDQ_ABC               
                                  2        GND                     
C5T11            CAP_A_0603V-22.0UF,4V,20%,X6S,A 1        PVDDQ_ABC               
                                  2        GND                     
C5T12            CAP_A_0603V-22.0UF,4V,20%,X6S,A 1        PVDDQ_ABC               
                                  2        GND                     
C5T13            CAP_A_0603V-47UF,4V,20%,X5R,60A 1        PVDDQ_ABC               
                                  2        GND                     
C5U1             CAP_0805-100UF,4V,20%,X5R,6024A 1        PVDDQ_ABC               
                                  2        GND                     
C5U2             CAP_A_0603V-22.0UF,4V,20%,X6S,A 1        PVDDQ_ABC               
                                  2        GND                     
C5U3             CAP_A_0603V-22.0UF,4V,20%,X6S,A 1        PVDDQ_ABC               
                                  2        GND                     
C5U4             CAP_A_0603V-22.0UF,4V,20%,X6S,A 1        PVDDQ_ABC               
                                  2        GND                     
C5U5             CAP_A_0603V-22.0UF,4V,20%,X6S,A 1        PVDDQ_ABC               
                                  2        GND                     
C5U6             CAP_A_0603V-22.0UF,4V,20%,X6S,A 1        PVDDQ_ABC               
                                  2        GND                     
C5U7             CAP_A_0603V-22.0UF,4V,20%,X6S,A 1        PVDDQ_ABC               
                                  2        GND                     
C5U8             CAP_A_0603V-22.0UF,4V,20%,X6S,A 1        PVDDQ_ABC               
                                  2        GND                     
C5U9             CAP_A_0603V-22.0UF,4V,20%,X6S,A 1        PVDDQ_ABC               
                                  2        GND                     
C5U10            CAP_0805-100UF,4V,20%,X5R,6024A 1        PVDDQ_ABC               
                                  2        GND                     
C5U11            CAP_A_0603V-47UF,4V,20%,X5R,60A 1        PVDDQ_ABC               
                                  2        GND                     
C5U12            CAP_A_0603V-47UF,4V,20%,X5R,60A 1        PVTT_ABC                
                                  2        GND                     
C5U13            CAP_0805-100UF,4V,20%,X5R,6024A 1        PVDDQ_ABC               
                                  2        GND                     
C5U14            CAP_0805-100UF,4V,20%,X5R,6024A 1        PVDDQ_ABC               
                                  2        GND                     
C5U15            CAP_0805-100UF,4V,20%,X5R,6024A 1        PVDDQ_ABC               
                                  2        GND                     
C5U16            CAP_A_0603V-47UF,4V,20%,X5R,60A 1        PVTT_ABC                
                                  2        GND                     
C6A1             CAP_0805LF-22UF,4V,20%,X6S,C95A 1        PVDDQ_DEF               
                                  2        GND                     
C6A2             CAP_0603LF-10UF,4V,20%,X6S,E15A 1        PVPP_DEF                
                                  2        GND                     
C6A3             CAP_0603LF-10UF,4V,20%,X6S,E15A 1        PVPP_DEF                
                                  2        GND                     
C6A4             CAP_0805LF-22UF,4V,20%,X6S,C95A 1        PVDDQ_DEF               
                                  2        GND                     
C6A5             CAPP_3018-470UF,2.5V,20%,ALUM,A 1        PVDDQ_DEF               
                                  2        GND                     
C6A6             CAP_0603LF-10UF,4V,20%,X6S,E15A 1        PVPP_DEF                
                                  2        GND                     
C6A7             CAP_0603LF-10UF,4V,20%,X6S,E15A 1        PVPP_DEF                
                                  2        GND                     
C6B1             CAP_0603LF-10UF,4V,20%,X6S,E15A 1        PVPP_DEF                
                                  2        GND                     
C6B2             CAP_0603LF-10UF,4V,20%,X6S,E15A 1        PVPP_DEF                
                                  2        GND                     
C6B3             CAP_0805-47UF,4V,20%,X6S,C9533A 1        PVPP_DEF                
                                  2        GND                     
C6B4             CAP_0402-0.22UF,16V,10%,X7R,A3A 1        P3E_CPU0_PE1_PCH_TXN<15>
                                  2        P3E_CPU0_PE1_PCH_C_TXN<15>
C6B5             CAP_0402-0.22UF,16V,10%,X7R,A3A 1        P3E_CPU0_PE1_PCH_TXP<15>
                                  2        P3E_CPU0_PE1_PCH_C_TXP<15>
C6B6             CAP_0402-0.22UF,16V,10%,X7R,A3A 1        P3E_CPU0_PE1_PCH_TXN<14>
                                  2        P3E_CPU0_PE1_PCH_C_TXN<14>
C6B7             CAPP_7343LF-330UF,6.3V,20%,POSA 1        PVPP_DEF                
                                  2        GND                     
C6B8             CAP_0402-0.22UF,16V,10%,X7R,A3A 1        P3E_CPU0_PE1_PCH_TXP<14>
                                  2        P3E_CPU0_PE1_PCH_C_TXP<14>
C6B9             CAP_0402-0.22UF,16V,10%,X7R,A3A 1        P3E_CPU0_PE1_PCH_TXN<13>
                                  2        P3E_CPU0_PE1_PCH_C_TXN<13>
C6B10            CAP_0402-0.22UF,16V,10%,X7R,A3A 1        P3E_CPU0_PE1_PCH_TXP<13>
                                  2        P3E_CPU0_PE1_PCH_C_TXP<13>
C6B11            CAP_0402-0.22UF,16V,10%,X7R,A3A 1        P3E_CPU0_PE1_PCH_TXN<12>
                                  2        P3E_CPU0_PE1_PCH_C_TXN<12>
C6B12            CAP_0402-0.22UF,16V,10%,X7R,A3A 1        P3E_CPU0_PE1_PCH_TXP<12>
                                  2        P3E_CPU0_PE1_PCH_C_TXP<12>
C6B13            CAP_0402-0.22UF,16V,10%,X7R,A3A 1        P3E_CPU0_PE1_PCH_TXP<11>
                                  2        P3E_CPU0_PE1_PCH_C_TXP<11>
C6B14            CAP_0402-0.22UF,16V,10%,X7R,A3A 1        P3E_CPU0_PE1_PCH_TXN<11>
                                  2        P3E_CPU0_PE1_PCH_C_TXN<11>
C6B15            CAP_0402-0.22UF,16V,10%,X7R,A3A 1        P3E_CPU0_PE1_PCH_TXN<10>
                                  2        P3E_CPU0_PE1_PCH_C_TXN<10>
C6B16            CAP_0402-0.22UF,16V,10%,X7R,A3A 1        P3E_CPU0_PE1_PCH_TXP<10>
                                  2        P3E_CPU0_PE1_PCH_C_TXP<10>
C6B17            CAP_0402-0.22UF,16V,10%,X7R,A3A 1        P3E_CPU0_PE1_PCH_TXN<9> 
                                  2        P3E_CPU0_PE1_PCH_C_TXN<9>
C6B18            CAP_0402-0.22UF,16V,10%,X7R,A3A 1        P3E_CPU0_PE1_PCH_TXP<9> 
                                  2        P3E_CPU0_PE1_PCH_C_TXP<9>
C6B19            CAP_0402-0.22UF,16V,10%,X7R,A3A 1        P3E_CPU0_PE1_PCH_TXN<8> 
                                  2        P3E_CPU0_PE1_PCH_C_TXN<8>
C6B20            CAP_0402-0.22UF,16V,10%,X7R,A3A 1        P3E_CPU0_PE1_PCH_TXP<8> 
                                  2        P3E_CPU0_PE1_PCH_C_TXP<8>
C6D1             CAP_0603LF-10UF,4V,20%,X6S,E15A 1        P1V8_MCP_CPU0           
                                  2        GND                     
C6D2             CAP_A_0603V-22.0UF,4V,20%,X6S,A 1        PVCCMCP_CPU0            
                                  2        GND                     
C6D3             CAP_A_0603V-22.0UF,4V,20%,X6S,A 1        PVCCIO_CPU0             
                                  2        GND                     
C6D4             CAP_A_0603V-22.0UF,4V,20%,X6S,A 1        PVCCIO_CPU0             
                                  2        GND                     
C6D5             CAP_A_0603V-22.0UF,4V,20%,X6S,A 1        PVCCMCP_CPU0            
                                  2        GND                     
C6D6             CAP_A_0603V-22.0UF,4V,20%,X6S,A 1        PVCCIO_CPU0             
                                  2        GND                     
C6D7             CAP_A_0603V-22.0UF,4V,20%,X6S,A 1        PVCCIO_CPU0             
                                  2        GND                     
C6D8             CAP_A_0603V-22.0UF,4V,20%,X6S,A 1        PVCCMCP_CPU0            
                                  2        GND                     
C6D9             CAP_A_0603V-22.0UF,4V,20%,X6S,A 1        PVCCIO_CPU0             
                                  2        GND                     
C6D10            CAP_A_0603V-22.0UF,4V,20%,X6S,A 1        PVCCIO_CPU0             
                                  2        GND                     
C6F1             CAP_A_0402V-0.1UF,16V,10%,X7R,A 1        P3V3                    
                                  2        GND                     
C6F2             CAP_A_0402V-0.1UF,16V,10%,X7R,A 1        PVCCIO_CPU0             
                                  2        GND                     
C6F3             CAP_A_0402V-0.1UF,16V,10%,X7R,A 1        PVPP_ABC                
                                  2        GND                     
C6F4             CAPP_7343LF-330UF,6.3V,20%,POSA 1        PVPP_ABC                
                                  2        GND                     
C6F5             CAP_0603LF-10UF,4V,20%,X6S,E15A 1        PVPP_ABC                
                                  2        GND                     
C6F6             CAP_0603LF-10UF,4V,20%,X6S,E15A 1        PVPP_ABC                
                                  2        GND                     
C6G1             CAP_0603LF-10UF,4V,20%,X6S,E15A 1        PVPP_ABC                
                                  2        GND                     
C6G2             CAP_0603LF-10UF,4V,20%,X6S,E15A 1        PVPP_ABC                
                                  2        GND                     
C6G3             CAP_0805LF-22UF,4V,20%,X6S,C95A 1        PVDDQ_ABC               
                                  2        GND                     
C6G4             CAP_0603LF-10UF,4V,20%,X6S,E15A 1        PVPP_ABC                
                                  2        GND                     
C6G5             CAP_0603LF-10UF,4V,20%,X6S,E15A 1        PVPP_ABC                
                                  2        GND                     
C6L1             CAP_A_0402V-0.01UF,25V,10%,X7RA 1        M_F_VREF                
                                  2        GND                     
C6L2             CAP_A_0402V-0.01UF,25V,10%,X7RA 1        M_F_CPU_VREF            
                                  2        GND                     
C6L3             CAP_0603LF-10UF,4V,20%,X6S,E15A 1        PVDDQ_DEF               
                                  2        GND                     
C6L4             CAP_0603LF-10UF,4V,20%,X6S,E15A 1        PVDDQ_DEF               
                                  2        GND                     
C6L5             CAP_0603LF-10UF,4V,20%,X6S,E15A 1        PVDDQ_KLM               
                                  2        GND                     
C6L6             CAP_A_0402V-0.01UF,25V,10%,X7RA 1        M_E_VREF                
                                  2        GND                     
C6L7             CAP_A_0402V-0.01UF,25V,10%,X7RA 1        M_E_CPU_VREF            
                                  2        GND                     
C6L8             CAPP_7343-220UF,4V,20%,POSCAP,A 1        PVPP_KLM                
                                  2        GND                     
C6L10            CAP_0805-10UF,16V,10%,X6S,C953A 1        VR_FET_SW_P12V_STBY_PVPP_KLM
                                  2        GND                     
C6L11            CAP_0402-1.0UF,16V,10%,X6S,D97A 1        VR_FET_SW_P12V_STBY_PVPP_KLM
                                  2        GND                     
C6L12            CAP_0603-4.7UF,6.3V,10%,X6S,E1A 1        VR_VB_PVPP_KLM          
                                  2        AGND_PVPP_KLM           
C6M1             CAP_A_0402V-0.01UF,25V,10%,X7RA 1        M_D_VREF                
                                  2        GND                     
C6M2             CAP_A_0402V-0.01UF,25V,10%,X7RA 1        M_D_CPU_VREF            
                                  2        GND                     
C6M3             CAP_0805-10UF,16V,10%,X6S,C953A 1        VR_FET_SW_P12V_STBY_PVPP_KLM
                                  2        GND                     
C6M5             CAP_0805-10UF,16V,10%,X6S,C953A 1        VR_FET_SW_P12V_STBY_PVPP_KLM
                                  2        GND                     
C6M6             CAP_A_0402V-0.1UF,16V,10%,X7R,A 1        JTAG_MCP_CPU1_TDI_R     
                                  2        GND                     
C6N1             CAPP_3018-470UF,2.5V,20%,ALUM,A 1        PVSA_CPU0               
                                  2        GND                     
C6N2             CAP_0805-10UF,16V,10%,X6S,C953A 1        VR_FET_SW_P12V_STBY_PVCCIN_CPU0
                                  2        GND                     
C6N3             CAP_0805-10UF,16V,10%,X6S,C953A 1        VR_FET_SW_P12V_STBY_PVCCIN_CPU0
                                  2        GND                     
C6N4             CAPP_3018-470UF,2.5V,20%,ALUM,A 1        PVSA_CPU0               
                                  2        GND                     
C6N5             CAPP_3018-68UF,16V,20%,TANT,72A 1        P12V_STBY               
                                  2        GND                     
C6N6             CAP_0805-10UF,16V,10%,X6S,C953A 1        VR_FET_SW_P12V_STBY_PVCCIN_CPU0
                                  2        GND                     
C6N7             CAP_A_0603V-22.0UF,4V,20%,X6S,A 1        PVSA_CPU0               
                                  2        GND                     
C6N8             CAP_0805-10UF,16V,10%,X6S,C953A 1        VR_FET_SW_P12V_STBY_PVCCIN_CPU0
                                  2        GND                     
C6N9             CAPP_3018-470UF,2.5V,20%,ALUM,A 1        PVCCIN_CPU0             
                                  2        GND                     
C6N10            CAP_0805-10UF,16V,10%,X6S,C953A 1        VR_FET_SW_P12V_STBY_PVCCIN_CPU0
                                  2        GND                     
C6N11            CAP_0805-10UF,16V,10%,X6S,C953A 1        VR_FET_SW_P12V_STBY_PVCCIN_CPU0
                                  2        GND                     
C6P3             CAP_A_0603V-22.0UF,4V,20%,X6S,A 1        PVCCIN_CPU0             
                                  2        GND                     
C6P4             CAP_A_0402V-0.1UF,16V,10%,X7R,A 1        P3V3_DB1200             
                                  2        GND                     
C6P5             CAP_A_0402V-0.1UF,16V,10%,X7R,A 1        P3V3_DB1200             
                                  2        GND                     
C6P6             CAP_A_0402V-0.1UF,16V,10%,X7R,A 1        P3V3_DB1200             
                                  2        GND                     
C6P7             CAP_0805-10UF,16V,10%,X6S,C953A 1        VR_FET_SW_P12V_STBY_PVCCIN_CPU0
                                  2        GND                     
C6P8             CAPP_3018-470UF,2.5V,20%,ALUM,A 1        PVCCIN_CPU0             
                                  2        GND                     
C6P9             CAP_A_0402V-0.1UF,16V,10%,X7R,A 1        P3V3_DB1200             
                                  2        GND                     
C6P10            CAP_A_0402V-0.1UF,16V,10%,X7R,A 1        P3V3_DB1200             
                                  2        GND                     
C6P11            CAP_A_0402V-0.1UF,16V,10%,X7R,A 1        P3V3_DB1200             
                                  2        GND                     
C6P12            CAP_A_0402V-0.1UF,16V,10%,X7R,A 1        P3V3_DB1200             
                                  2        GND                     
C6P13            CAP_0805-10UF,16V,10%,X6S,C953A 1        VR_FET_SW_P12V_STBY_PVCCIN_CPU0
                                  2        GND                     
C6P14            CAPP_3018-470UF,2.5V,20%,ALUM,A 1        PVCCIN_CPU0             
                                  2        GND                     
C6P15            CAP_0805-10UF,16V,10%,X6S,C953A 1        VR_FET_SW_P12V_STBY_PVCCIN_CPU0
                                  2        GND                     
C6P16            CAP_A_0603V-22.0UF,4V,20%,X6S,A 1        PVCCIN_CPU0             
                                  2        GND                     
C6P17            CAP_0805-10UF,16V,10%,X6S,C953A 1        VR_FET_SW_P12V_STBY_PVCCIN_CPU0
                                  2        GND                     
C6P18            CAPP_3018-470UF,2.5V,20%,ALUM,A 1        PVCCIN_CPU0             
                                  2        GND                     
C6P19            CAP_0805-10UF,16V,10%,X6S,C953A 1        VR_FET_SW_P12V_STBY_PVCCIN_CPU0
                                  2        GND                     
C6P20            CAP_0805-10UF,16V,10%,X6S,C953A 1        VR_FET_SW_P12V_STBY_PVCCIN_CPU0
                                  2        GND                     
C6P21            CAP_A_0603V-22.0UF,4V,20%,X6S,A 1        PVCCIN_CPU0             
                                  2        GND                     
C6P22            CAP_0805-10UF,16V,10%,X6S,C953A 1        VR_FET_SW_P12V_STBY_PVCCIN_CPU0
                                  2        GND                     
C6P23            CAPP_3018-470UF,2.5V,20%,ALUM,A 1        PVCCIN_CPU0             
                                  2        GND                     
C6P24            CAP_0805-10UF,16V,10%,X6S,C953A 1        VR_FET_SW_P12V_STBY_PVCCIN_CPU0
                                  2        GND                     
C6R2             CAP_A_0603V-22.0UF,4V,20%,X6S,A 1        PVCCIN_CPU0             
                                  2        GND                     
C6R3             CAPP_3018-470UF,2.5V,20%,ALUM,A 1        PVCCIN_CPU0             
                                  2        GND                     
C6R4             CAP_0805-10UF,16V,10%,X6S,C953A 1        VR_FET_SW_P12V_STBY_PVCCIN_CPU0
                                  2        GND                     
C6R5             CAPP_3018-470UF,2.5V,20%,ALUM,A 1        PVCCIO_CPU1             
                                  2        GND                     
C6R6             CAP_0805-10UF,16V,10%,X6S,C953A 1        VR_FET_SW_P12V_STBY_PVCCIN_CPU0
                                  2        GND                     
C6R7             CAP_A_0603V-22.0UF,4V,20%,X6S,A 1        PVCCIN_CPU0             
                                  2        GND                     
C6R8             CAP_0805-10UF,16V,10%,X6S,C953A 1        VR_FET_SW_P12V_STBY_PVCCIN_CPU0
                                  2        GND                     
C6R9             CAPP_3018-470UF,2.5V,20%,ALUM,A 1        PVCCIN_CPU0             
                                  2        GND                     
C6R10            CAP_0805-10UF,16V,10%,X6S,C953A 1        VR_FET_SW_P12V_STBY_PVCCIN_CPU0
                                  2        GND                     
C6R11            CAP_0805-10UF,16V,10%,X6S,C953A 1        VR_FET_SW_P12V_STBY_PVCCIN_CPU0
                                  2        GND                     
C6R12            CAPP_3018-470UF,2.5V,20%,ALUM,A 1        PVCCIO_CPU1             
                                  2        GND                     
C6R13            CAP_0805-10UF,16V,10%,X6S,C953A 1        VR_FET_SW_P12V_STBY_PVCCIN_CPU0
                                  2        GND                     
C6R14            CAP_0805-10UF,16V,10%,X6S,C953A 1        VR_FET_SW_P12V_STBY_PVCCIN_CPU0
                                  2        GND                     
C6R16            CAPP_3018-470UF,2.5V,20%,ALUM,A 1        PVCCMCP_CPU1            
                                  2        GND                     
C6T1             CAP_A_0402V-0.01UF,25V,10%,X7RA 1        M_A_VREF                
                                  2        GND                     
C6T2             CAP_0805-10UF,16V,10%,X7R,G106A 1        P12V_NVDIMM_ABC         
                                  2        GND                     
C6U2             CAP_0805-47UF,4V,20%,X6S,C9533A 1        PVPP_GHJ                
                                  2        GND                     
C6U3             CAP_0805-47UF,4V,20%,X6S,C9533A 1        PVPP_GHJ                
                                  2        GND                     
C6U4             CAP_0805-10UF,16V,10%,X6S,C953A 1        VR_FET_SW_P12V_STBY_PVPP_GHJ
                                  2        GND                     
C6U5             CAP_A_0402V-0.1UF,16V,10%,X7R,A 1        VR_FET_SW_P12V_STBY_PVPP_GHJ
                                  2        GND                     
C6U6             CAP_0603-4.7UF,6.3V,10%,X6S,E1A 1        VR_VB_PVPP_GHJ          
                                  2        AGND_PVPP_GHJ           
C6U7             CAP_0805-10UF,16V,10%,X6S,C953A 1        VR_FET_SW_P12V_STBY_PVPP_GHJ
                                  2        GND                     
C6U8             CAP_0805-10UF,16V,10%,X6S,C953A 1        VR_FET_SW_P12V_STBY_PVPP_GHJ
                                  2        GND                     
C6U9             CAP_A_0402V-0.01UF,25V,10%,X7RA 1        M_B_VREF                
                                  2        GND                     
C6U10            CAP_0805-10UF,16V,10%,X7R,G106A 1        P12V_NVDIMM_ABC         
                                  2        GND                     
C6U11            CAP_0603-4.7UF,6.3V,10%,X6S,E1A 1        VSENSE_PVDDQ_GHJ_VTT    
                                  2        GND                     
C6U12            CAP_0603-4.7UF,6.3V,10%,X6S,E1A 1        VSENSE_PVDDQ_ABC_VTT    
                                  2        GND                     
C6U13            CAP_0603LF-10UF,4V,20%,X6S,E15A 1        PVDDQ_GHJ               
                                  2        GND                     
C6U14            CAP_0603LF-10UF,4V,20%,X6S,E15A 1        PVDDQ_GHJ               
                                  2        GND                     
C6U15            CAP_0603LF-10UF,4V,20%,X6S,E15A 1        PVDDQ_ABC               
                                  2        GND                     
C6U16            CAP_0603LF-10UF,4V,20%,X6S,E15A 1        PVDDQ_ABC               
                                  2        GND                     
C6U17            CAP_A_0402V-0.01UF,25V,10%,X7RA 1        M_C_VREF                
                                  2        GND                     
C6U18            CAP_0805-10UF,16V,10%,X7R,G106A 1        P12V_NVDIMM_ABC         
                                  2        GND                     
C7A5             CAP_A_0402V-0.1UF,16V,10%,X7R,A 1        VR_FET_SW_P12V_STBY_PVDDQ_DEF
                                  2        GND                     
C7A6             CAP_0402-1.0UF,16V,10%,X6S,D97A 1        VR_PVNN_PCH_PH1_VCIN    
                                  2        GND                     
C7A7             CAP_0402-1.0UF,16V,10%,X6S,D97A 1        VR_FET_SW_P12V_STBY_PVDDQ_DEF
                                  2        GND                     
C7A8             CAP_0402-0.22UF,16V,10%,X7R,A3A 1        P5V_STBY                
                                  2        GND                     
C7A9             CAP_0402-1.0UF,16V,10%,X6S,D97A 1        VR_FET_SW_P12V_STBY_PVDDQ_DEF
                                  2        GND                     
C7A10            CAP_0402-1.0UF,16V,10%,X6S,D97A 1        VR_P1V05_PCH_STBY_PH1_VCIN
                                  2        GND                     
C7A11            CAP_0402-1.0UF,16V,10%,X6S,D97A 1        VR_FET_SW_P12V_STBY_PVDDQ_DEF
                                  2        GND                     
C7A12            CAP_0402-0.220UF,16V,10%,X7R,AA 1        VR_PVDDQ_DEF_PH1_BOOT   
                                  2        VR_PVDDQ_DEF_PH1_PHASE  
C7A13            CAP_1210-100UF,16V,20%,X5R,644A 1        VR_FET_SW_P12V_STBY_PVDDQ_DEF
                                  2        GND                     
C7A14            CAP_1210-100UF,16V,20%,X5R,644A 1        VR_FET_SW_P12V_STBY_PVDDQ_DEF
                                  2        GND                     
C7A16            CAP_0402-1.0UF,16V,10%,X6S,D97A 1        VR_PVDDQ_DEF_PH1_VCIN   
                                  2        GND                     
C7A17            CAP_0402-0.22UF,16V,10%,X7R,A3A 1        P5V_STBY                
                                  2        GND                     
C7A18            CAP_A_0402V-1.0UF,6.3V,10%,X6SA 1        P5V_STBY                
                                  2        GND                     
C7A19            CAPP_2626-270UF,16V,20%,OSCON,A 1        VR_FET_SW_P12V_STBY_PVDDQ_DEF
                                  2        GND                     
C7A20            CAP_A_0402V-0.1UF,16V,10%,X7R,A 1        VR_FET_SW_P12V_STBY_PVDDQ_DEF
                                  2        GND                     
C7A21            CAP_0402-1.0UF,16V,10%,X6S,D97A 1        VR_FET_SW_P12V_STBY_PVDDQ_DEF
                                  2        GND                     
C7A22            CAP_0402-0.220UF,16V,10%,X7R,AA 1        VR_PVDDQ_DEF_PH2_BOOT   
                                  2        VR_PVDDQ_DEF_PH2_PHASE  
C7A24            CAP_0402-1.0UF,16V,10%,X6S,D97A 1        VR_PVDDQ_DEF_PH2_VCIN   
                                  2        GND                     
C7A25            CAP_0402-0.22UF,16V,10%,X7R,A3A 1        P5V_STBY                
                                  2        GND                     
C7A26            CAP_A_0402V-1.0UF,6.3V,10%,X6SA 1        P5V_STBY                
                                  2        GND                     
C7A27            CAPP_SM-470UF,2V,20%,ALUM,6990A 1        PVNN_PCH_STBY           
                                  2        GND                     
C7A28            CAP_0402LF-220PF,50V,10%,X7R,AA 1        VR_PVDDQ_DEF_AVSP       
                                  2        VSENSE_PVDDQ_DEF_N      
C7A29            CAP_0402LF-220PF,50V,10%,X7R,AA 1        A_TSENSE_PVDDQ_DEF      
                                  2        GND                     
C7A30            CAP_0805LF-22UF,4V,20%,X6S,C95A 1        PVNN_PCH_STBY           
                                  2        GND                     
C7A31            CAP_0805-47UF,4V,20%,X6S,C9533A 1        PVNN_PCH_STBY           
                                  2        GND                     
C7A32            CAP_0805-47UF,4V,20%,X6S,C9533A 1        PVNN_PCH_STBY           
                                  2        GND                     
C7A33            CAP_0805-47UF,4V,20%,X6S,C9533A 1        PVNN_PCH_STBY           
                                  2        GND                     
C7A34            CAP_0402LF-3300PF,50V,10%,EMPTA 1        VR_PVPP_DEF_PHASE       
                                  2        VR_PVPP_DEF_SNUB        
C7A35            CAP_0402LF-1000PF,50V,10%,X7R,A 1        VR_PVDDQ_DEF_VINSEN     
                                  2        GND                     
C7A36            CAP_A_0603V-22.0UF,4V,20%,X6S,A 1        PVNN_PCH_STBY           
                                  2        GND                     
C7A37            CAP_A_0402V-1.0UF,6.3V,10%,X6SA 1        VR_PVDDQ_DEF_VDD        
                                  2        GND                     
C7A38            CAP_A_0402V-0.1UF,16V,10%,X7R,A 1        VR_PVDDQ_DEF_VDD        
                                  2        GND                     
C7A39            CAP_A_0402V-0.1UF,16V,10%,X7R,A 1        VR_FET_SW_P12V_STBY_PVDDQ_DEF
                                  2        GND                     
C7A40            CAP_A_0402V-0.1UF,16V,10%,X7R,A 1        VR_FET_SW_P12V_STBY_PVDDQ_DEF
                                  2        GND                     
C7A41            CAP_0402-0.22UF,16V,10%,X7R,A3A 1        P5V_STBY                
                                  2        GND                     
C7A42            CAP_0805LF-22UF,4V,20%,X6S,C95A 1        P1V05_PCH_STBY          
                                  2        GND                     
C7A43            CAP_0402-0.220UF,16V,10%,X7R,AA 1        VR_PVNN_PCH_PH1_BOOT    
                                  2        VR_PVNN_PCH_PH1_PHASE   
C7A44            CAP_0402-0.220UF,16V,10%,X7R,AA 1        VR_P1V05_PCH_STBY_PH1_BOOT
                                  2        VR_P1V05_PCH_STBY_PH1_PHASE
C7B1             CAP_A_0402V-1.0UF,6.3V,10%,X6SA 1        VR_PVDDQ_DEF_VD12       
                                  2        GND                     
C7B2             CAP_A_0402V-0.1UF,16V,10%,X7R,A 1        VR_PVDDQ_DEF_VD12       
                                  2        GND                     
C7B3             CAP_0402LF-1000PF,50V,10%,X7R,A 1        PWRGD_PVDDQ_DEF_R       
                                  2        GND                     
C7B4             CAP_0805-47UF,4V,20%,X6S,C9533A 1        PVNN_PCH_STBY           
                                  2        GND                     
C7B5             CAP_0805-10UF,16V,10%,X6S,C953A 1        VR_FET_SW_P12V_STBY_PVPP_DEF
                                  2        GND                     
C7B6             CAP_A_0402V-0.1UF,16V,10%,X7R,A 1        VR_FET_SW_P12V_STBY_PVPP_DEF
                                  2        GND                     
C7B7             CAP_0805-47UF,4V,20%,X6S,C9533A 1        PVPP_DEF                
                                  2        GND                     
C7B8             CAP_1210-47UF,16V,20%,X6S,D384A 1        VR_FET_SW_P12V_STBY_PVPP_DEF
                                  2        GND                     
C7B9             CAP_0402LF-1000PF,50V,10%,EMPTA 1        FM_PVPP_CPU0_EN         
                                  2        AGND_PVPP_DEF           
C7B10            CAP_0402LF-100.0PF,50V,5%,COG,A 1        VR_FB_PVPP_DEF          
                                  2        VR_COMP_PVPP_DEF_3      
C7B11            CAP_0402-0.027UF,16V,10%,X7R,AA 1        VR_PVPP_DEF_SS          
                                  2        AGND_PVPP_DEF           
C7B12            CAP_0402LF-1000PF,50V,10%,X7R,A 1        PWRGD_PVPP_DEF_R        
                                  2        GND                     
C7B13            CAP_0402LF-2200PF,50V,10%,X7R,A 1        VR_COMP_PVPP_DEF        
                                  2        VR_FB_PVPP_DEF          
C7B14            CAP_0402LF-2200PF,50V,10%,X7R,A 1        VR_COMP_RC_PVPP_DEF     
                                  2        VR_COMP_PVPP_DEF_3      
C7B15            CAP_A_0603V-22.0UF,4V,20%,X6S,A 1        P1V05_PCH_STBY          
                                  2        GND                     
C7B16            CAP_A_0603V-22.0UF,4V,20%,X6S,A 1        P1V05_PCH_STBY          
                                  2        GND                     
C7B17            CAP_A_0603V-22.0UF,4V,20%,X6S,A 1        P1V05_PCH_STBY          
                                  2        GND                     
C7B18            CAP_A_0603V-22.0UF,4V,20%,X6S,A 1        P1V05_PCH_STBY          
                                  2        GND                     
C7B19            CAP_A_0603V-22.0UF,4V,20%,X6S,A 1        P1V05_PCH_STBY          
                                  2        GND                     
C7B20            CAP_A_0603V-22.0UF,4V,20%,X6S,A 1        P1V05_PCH_STBY          
                                  2        GND                     
C7B21            CAP_A_0603V-22.0UF,4V,20%,X6S,A 1        P1V05_PCH_STBY          
                                  2        GND                     
C7B22            CAP_A_0603V-22.0UF,4V,20%,X6S,A 1        P1V05_PCH_STBY          
                                  2        GND                     
C7B23            CAP_A_0603V-22.0UF,4V,20%,X6S,A 1        P1V05_PCH_STBY          
                                  2        GND                     
C7B24            CAP_A_0603V-22.0UF,4V,20%,X6S,A 1        P1V05_PCH_STBY          
                                  2        GND                     
C7B25            CAP_0402-0.22UF,16V,10%,X7R,A3A 1        DMI_CPU0_PCH_TX_DP<3>   
                                  2        DMI_CPU0_PCH_TX_C_DP<3> 
C7B26            CAP_0402-0.22UF,16V,10%,X7R,A3A 1        DMI_CPU0_PCH_TX_DN<3>   
                                  2        DMI_CPU0_PCH_TX_C_DN<3> 
C7B27            CAP_0402-0.22UF,16V,10%,X7R,A3A 1        DMI_CPU0_PCH_TX_DP<2>   
                                  2        DMI_CPU0_PCH_TX_C_DP<2> 
C7B28            CAP_0402-0.22UF,16V,10%,X7R,A3A 1        DMI_CPU0_PCH_TX_DP<1>   
                                  2        DMI_CPU0_PCH_TX_C_DP<1> 
C7B29            CAP_0402-0.22UF,16V,10%,X7R,A3A 1        DMI_CPU0_PCH_TX_DN<2>   
                                  2        DMI_CPU0_PCH_TX_C_DN<2> 
C7B30            CAP_0603LF-0.1UF,25V,10%,X7R,6A 1        VR_PVPP_DEF_PHASE       
                                  2        VR_PVPP_DEF_BOOT_R      
C7C1             CAP_0402-0.22UF,16V,10%,X7R,A3A 1        DMI_CPU0_PCH_TX_DN<1>   
                                  2        DMI_CPU0_PCH_TX_C_DN<1> 
C7C2             CAP_0402-0.22UF,16V,10%,X7R,A3A 1        DMI_CPU0_PCH_TX_DP<0>   
                                  2        DMI_CPU0_PCH_TX_C_DP<0> 
C7C3             CAP_0402-0.22UF,16V,10%,X7R,A3A 1        DMI_CPU0_PCH_TX_DN<0>   
                                  2        DMI_CPU0_PCH_TX_C_DN<0> 
C7C4             CAP_0402LF-15.0PF,50V,5%,COG,AA 1        XTAL_PCH_48M_IN         
                                  2        GND                     
C7C5             CAP_0402LF-15.0PF,50V,5%,COG,AA 1        XTAL_PCH_48M_OUT        
                                  2        GND                     
C7C6             CAP_A_0603V-22.0UF,4V,20%,X6S,A 1        PVCCIO_CPU0             
                                  2        GND                     
C7C7             CAP_1210-100UF,16V,20%,X5R,644A 1        VR_FET_SW_P12V_STBY_PVCCIO_CPU0
                                  2        GND                     
C7C8             CAP_1210-100UF,16V,20%,X5R,644A 1        VR_FET_SW_P12V_STBY_PVCCIO_CPU0
                                  2        GND                     
C7C9             CAP_A_0603V-22.0UF,4V,20%,X6S,A 1        PVNN_PCH_STBY           
                                  2        GND                     
C7C10            CAP_A_0603V-22.0UF,4V,20%,X6S,A 1        PVCCIO_CPU0             
                                  2        GND                     
C7C11            CAP_A_0402V-0.1UF,16V,10%,X7R,A 1        VR_FET_SW_P12V_STBY_PVCCIO_CPU0
                                  2        GND                     
C7C12            CAP_0402-1.0UF,16V,10%,X6S,D97A 1        VR_FET_SW_P12V_STBY_PVCCIO_CPU0
                                  2        GND                     
C7C13            CAP_0402LF-18PF,50V,5%,C0G,A36A 1        XTAL_33K_RTC1           
                                  2        GND                     
C7C14            CAP_0402-0.220UF,16V,10%,X7R,AA 1        VR_PVCCIO_CPU0_PH1_BOOT 
                                  2        VR_PVCCIO_CPU0_PH1_PHASE
C7C15            CAP_0402LF-18PF,50V,5%,C0G,A36A 1        XTAL_33K_RTC2           
                                  2        GND                     
C7C17            CAP_0402-1.0UF,16V,10%,X6S,D97A 1        VR_PVCCIO_CPU0_PH1_VCIN 
                                  2        GND                     
C7C18            CAP_0402-0.22UF,16V,10%,X7R,A3A 1        P5V_STBY                
                                  2        GND                     
C7C19            CAP_A_0402V-1.0UF,6.3V,10%,X6SA 1        RST_RTCRST_N            
                                  2        GND                     
C7C20            CAP_A_0402V-1.0UF,6.3V,10%,X6SA 1        P5V_STBY                
                                  2        GND                     
C7D1             CAP_A_0402V-0.1UF,16V,10%,X7R,A 1        P3V3_STBY               
                                  2        GND                     
C7D2             CAP_0603-10UF,6.3V,20%,X6S,E15A 1        P3V3_STBY               
                                  2        GND                     
C7D3             CAP_A_0603V-22.0UF,4V,20%,X6S,A 1        P1V8_PCH_STBY           
                                  2        GND                     
C7D4             CAP_0402-1.0UF,16V,10%,X6S,D97A 1        P3V3                    
                                  2        GND                     
C7D5             CAP_A_0402V-0.1UF,16V,10%,X7R,A 1        P0V7_GTL2104_VREF_0     
                                  2        GND                     
C7E1             CAP_A_0402V-0.1UF,16V,10%,X7R,A 1        PVCCIO_CPU0             
                                  2        GND                     
C7E2             CAP_A_0402V-0.1UF,16V,10%,X7R,A 1        PVPP_DEF                
                                  2        GND                     
C7E3             CAP_A_0402V-0.1UF,16V,10%,X7R,A 1        P3V3_STBY               
                                  2        GND                     
C7E4             CAP_A_0402V-0.1UF,16V,10%,X7R,A 1        P3V3_STBY               
                                  2        GND                     
C7E5             CAP_A_0402V-0.1UF,16V,10%,X7R,A 1        P12V_STBY               
                                  2        GND                     
C7E6             CAP_0805-10UF,16V,10%,X6S,C953A 1        P12V_STBY               
                                  2        GND                     
C7E8             CAP_0805-10UF,16V,10%,X6S,C953A 1        P12V                    
                                  2        GND                     
C7E9             CAP_A_0402V-0.1UF,16V,10%,X7R,A 1        P12V                    
                                  2        GND                     
C7E10            CAP_0402LF-1000PF,50V,10%,X7R,A 1        PWRGD_P5V_STBY_R        
                                  2        GND                     
C7E11            CAP_1206LF-22UF,16V,10%,X6S,D3A 1        VR_FET_SW_P5V_STBY_PVIN 
                                  2        GND                     
C7E12            CAP_1210-47UF,16V,20%,X6S,D384A 1        VR_FET_SW_P5V_STBY_PVIN 
                                  2        GND                     
C7E13            CAP_1210-47UF,16V,20%,X6S,D384A 1        VR_FET_SW_P5V_STBY_PVIN 
                                  2        GND                     
C7E14            CAP_0402-1.0UF,16V,10%,X6S,D97A 1        VR_P5V_STBY_VIN         
                                  2        GND                     
C7F1             CAP_A_0402V-0.01UF,25V,10%,X7RA 1        P3V3_STBY               
                                  2        GND                     
C7F2             CAP_A_0402V-1.0UF,6.3V,10%,X6SA 1        P3V3_STBY               
                                  2        GND                     
C7F3             CAP_0402LF-3300PF,50V,10%,EMPTA 1        VR_PVPP_ABC_PHASE       
                                  2        VR_PVPP_ABC_SNUB        
C7F4             CAP_0603LF-0.1UF,25V,10%,X7R,6A 1        VR_PVPP_ABC_PHASE       
                                  2        VR_PVPP_ABC_BOOT_R      
C7F5             CAP_0805-10UF,16V,10%,X6S,C953A 1        VR_FET_SW_P12V_STBY_PVPP_ABC
                                  2        GND                     
C7F6             CAP_A_0402V-0.1UF,16V,10%,X7R,A 1        VR_FET_SW_P12V_STBY_PVPP_ABC
                                  2        GND                     
C7F7             CAP_1210-47UF,16V,20%,X6S,D384A 1        VR_FET_SW_P12V_STBY_PVPP_ABC
                                  2        GND                     
C7F8             CAP_0402LF-1000PF,50V,10%,EMPTA 1        FM_PVPP_CPU0_EN         
                                  2        AGND_PVPP_ABC           
C7F9             CAP_0402LF-100.0PF,50V,5%,COG,A 1        VR_FB_PVPP_ABC          
                                  2        VR_COMP_PVPP_ABC_3      
C7F10            CAP_0402-0.027UF,16V,10%,X7R,AA 1        VR_PVPP_ABC_SS          
                                  2        AGND_PVPP_ABC           
C7F11            CAP_0402LF-1000PF,50V,10%,X7R,A 1        PWRGD_PVPP_ABC_R        
                                  2        GND                     
C7F12            CAP_0402LF-2200PF,50V,10%,X7R,A 1        VR_COMP_RC_PVPP_ABC     
                                  2        VR_COMP_PVPP_ABC_3      
C7F13            CAP_0402LF-2200PF,50V,10%,X7R,A 1        VR_COMP_PVPP_ABC        
                                  2        VR_FB_PVPP_ABC          
C7F14            CAP_0402LF-1000PF,50V,10%,X7R,A 1        PWRGD_PVDDQ_ABC_R       
                                  2        GND                     
C7F15            CAP_A_0402V-0.1UF,16V,10%,X7R,A 1        VR_PVDDQ_ABC_VD12       
                                  2        GND                     
C7F16            CAP_A_0402V-1.0UF,6.3V,10%,X6SA 1        VR_PVDDQ_ABC_VD12       
                                  2        GND                     
C7F17            CAP_A_0402V-0.1UF,16V,10%,X7R,A 1        VR_PVDDQ_ABC_VDD        
                                  2        GND                     
C7F18            CAP_A_0402V-1.0UF,6.3V,10%,X6SA 1        VR_PVDDQ_ABC_VDD        
                                  2        GND                     
C7G1             CAP_0402LF-1000PF,50V,10%,X7R,A 1        VR_PVDDQ_ABC_VINSEN     
                                  2        GND                     
C7G2             CAPP_2626-270UF,16V,20%,OSCON,A 1        VR_FET_SW_P12V_STBY_PVDDQ_ABC
                                  2        GND                     
C7G3             CAP_0402LF-220PF,50V,10%,X7R,AA 1        A_TSENSE_PVDDQ_ABC      
                                  2        GND                     
C7G4             CAP_0402LF-220PF,50V,10%,X7R,AA 1        VR_PVDDQ_ABC_AVSP       
                                  2        VSENSE_PVDDQ_ABC_N      
C7G5             CAP_0402-0.22UF,16V,10%,X7R,A3A 1        P3E_CPU0_PE2_SS_TXP<15> 
                                  2        P3E_CPU0_PE2_SS_C_TXP<15>
C7G6             CAP_0402-0.22UF,16V,10%,X7R,A3A 1        P3E_CPU0_PE2_SS_TXN<15> 
                                  2        P3E_CPU0_PE2_SS_C_TXN<15>
C7G7             CAP_0402-0.22UF,16V,10%,X7R,A3A 1        P3E_CPU0_PE2_SS_TXN<14> 
                                  2        P3E_CPU0_PE2_SS_C_TXN<14>
C7G8             CAP_0402-0.22UF,16V,10%,X7R,A3A 1        P3E_CPU0_PE2_SS_TXP<14> 
                                  2        P3E_CPU0_PE2_SS_C_TXP<14>
C7G9             CAP_0402-0.22UF,16V,10%,X7R,A3A 1        P3E_CPU0_PE2_SS_TXP<13> 
                                  2        P3E_CPU0_PE2_SS_C_TXP<13>
C7G10            CAP_0402-0.22UF,16V,10%,X7R,A3A 1        P3E_CPU0_PE2_SS_TXN<13> 
                                  2        P3E_CPU0_PE2_SS_C_TXN<13>
C7G11            CAP_0402-0.22UF,16V,10%,X7R,A3A 1        P3E_CPU0_PE2_SS_TXP<12> 
                                  2        P3E_CPU0_PE2_SS_C_TXP<12>
C7G12            CAP_0402-0.22UF,16V,10%,X7R,A3A 1        P3E_CPU0_PE2_SS_TXN<12> 
                                  2        P3E_CPU0_PE2_SS_C_TXN<12>
C7G13            CAP_0402-0.22UF,16V,10%,X7R,A3A 1        P3E_CPU0_PE2_SS_TXN<11> 
                                  2        P3E_CPU0_PE2_SS_C_TXN<11>
C7G14            CAP_0402-0.22UF,16V,10%,X7R,A3A 1        P3E_CPU0_PE2_SS_TXP<11> 
                                  2        P3E_CPU0_PE2_SS_C_TXP<11>
C7G15            CAP_0402-0.22UF,16V,10%,X7R,A3A 1        P3E_CPU0_PE2_SS_TXP<10> 
                                  2        P3E_CPU0_PE2_SS_C_TXP<10>
C7G16            CAP_0402-0.22UF,16V,10%,X7R,A3A 1        P3E_CPU0_PE2_SS_TXN<10> 
                                  2        P3E_CPU0_PE2_SS_C_TXN<10>
C7G17            CAP_0402-0.22UF,16V,10%,X7R,A3A 1        P3E_CPU0_PE2_SS_TXP<9>  
                                  2        P3E_CPU0_PE2_SS_C_TXP<9>
C7G18            CAP_0402-0.22UF,16V,10%,X7R,A3A 1        P3E_CPU0_PE2_SS_TXN<9>  
                                  2        P3E_CPU0_PE2_SS_C_TXN<9>
C7G19            CAP_0402-0.22UF,16V,10%,X7R,A3A 1        P3E_CPU0_PE2_SS_TXP<8>  
                                  2        P3E_CPU0_PE2_SS_C_TXP<8>
C7G20            CAP_0402-0.22UF,16V,10%,X7R,A3A 1        P3E_CPU0_PE2_SS_TXN<8>  
                                  2        P3E_CPU0_PE2_SS_C_TXN<8>
C7G21            CAP_0402-0.22UF,16V,10%,X7R,A3A 1        P3E_CPU0_PE2_SS_TXP<7>  
                                  2        P3E_CPU0_PE2_SS_C_TXP<7>
C7G22            CAP_0402-0.22UF,16V,10%,X7R,A3A 1        P3E_CPU0_PE2_SS_TXN<7>  
                                  2        P3E_CPU0_PE2_SS_C_TXN<7>
C7G23            CAP_0402-0.22UF,16V,10%,X7R,A3A 1        P3E_CPU0_PE2_SS_TXP<6>  
                                  2        P3E_CPU0_PE2_SS_C_TXP<6>
C7G24            CAP_0402-0.22UF,16V,10%,X7R,A3A 1        P3E_CPU0_PE2_SS_TXN<6>  
                                  2        P3E_CPU0_PE2_SS_C_TXN<6>
C7G25            CAP_0402-0.22UF,16V,10%,X7R,A3A 1        P3E_CPU0_PE2_SS_TXP<5>  
                                  2        P3E_CPU0_PE2_SS_C_TXP<5>
C7G26            CAP_0402-0.22UF,16V,10%,X7R,A3A 1        P3E_CPU0_PE2_SS_TXN<5>  
                                  2        P3E_CPU0_PE2_SS_C_TXN<5>
C7G27            CAP_0805LF-22UF,4V,20%,X6S,C95A 1        PVDDQ_ABC               
                                  2        GND                     
C7G28            CAPP_3018-470UF,2.5V,20%,ALUM,A 1        PVDDQ_ABC               
                                  2        GND                     
C7G29            CAP_A_0402V-0.1UF,16V,10%,X7R,A 1        VR_FET_SW_P12V_STBY_PVDDQ_ABC
                                  2        GND                     
C7G30            CAP_0402-1.0UF,16V,10%,X6S,D97A 1        VR_FET_SW_P12V_STBY_PVDDQ_ABC
                                  2        GND                     
C7G31            CAP_0402-0.220UF,16V,10%,X7R,AA 1        VR_PVDDQ_ABC_PH1_BOOT   
                                  2        VR_PVDDQ_ABC_PH1_PHASE  
C7G33            CAP_0402-1.0UF,16V,10%,X6S,D97A 1        VR_PVDDQ_ABC_PH1_VCIN   
                                  2        GND                     
C7G34            CAP_0402-0.22UF,16V,10%,X7R,A3A 1        P5V_STBY                
                                  2        GND                     
C7G35            CAP_A_0402V-1.0UF,6.3V,10%,X6SA 1        P5V_STBY                
                                  2        GND                     
C7G36            CAP_A_0402V-0.1UF,16V,10%,X7R,A 1        VR_FET_SW_P12V_STBY_PVDDQ_ABC
                                  2        GND                     
C7G37            CAP_0402-1.0UF,16V,10%,X6S,D97A 1        VR_FET_SW_P12V_STBY_PVDDQ_ABC
                                  2        GND                     
C7G38            CAP_0402-0.220UF,16V,10%,X7R,AA 1        VR_PVDDQ_ABC_PH2_BOOT   
                                  2        VR_PVDDQ_ABC_PH2_PHASE  
C7G40            CAP_0402-1.0UF,16V,10%,X6S,D97A 1        VR_PVDDQ_ABC_PH2_VCIN   
                                  2        GND                     
C7G41            CAP_0402-0.22UF,16V,10%,X7R,A3A 1        P5V_STBY                
                                  2        GND                     
C7G42            CAP_A_0402V-1.0UF,6.3V,10%,X6SA 1        P5V_STBY                
                                  2        GND                     
C7L1             CAP_0805-100UF,4V,20%,X5R,6024A 1        PVDDQ_KLM               
                                  2        GND                     
C7L2             CAP_0603LF-10UF,4V,20%,X6S,E15A 1        PVPP_KLM                
                                  2        GND                     
C7L3             CAP_0603LF-10UF,4V,20%,X6S,E15A 1        PVPP_KLM                
                                  2        GND                     
C7L4             CAP_A_0603V-22.0UF,4V,20%,X6S,A 1        PVDDQ_KLM               
                                  2        GND                     
C7L5             CAP_A_0603V-22.0UF,4V,20%,X6S,A 1        PVDDQ_KLM               
                                  2        GND                     
C7L6             CAP_0603LF-10UF,4V,20%,X6S,E15A 1        PVPP_KLM                
                                  2        GND                     
C7L7             CAP_0603LF-10UF,4V,20%,X6S,E15A 1        PVPP_KLM                
                                  2        GND                     
C7M1             CAP_A_0603V-22.0UF,4V,20%,X6S,A 1        PVDDQ_KLM               
                                  2        GND                     
C7M2             CAP_A_0603V-22.0UF,4V,20%,X6S,A 1        PVDDQ_KLM               
                                  2        GND                     
C7M3             CAP_0603LF-10UF,4V,20%,X6S,E15A 1        PVPP_KLM                
                                  2        GND                     
C7M4             CAP_0603LF-10UF,4V,20%,X6S,E15A 1        PVPP_KLM                
                                  2        GND                     
C7M5             CAP_A_0603V-47UF,4V,20%,X5R,60A 1        PVDDQ_KLM               
                                  2        GND                     
C7M6             CAPP_3018-68UF,16V,20%,TANT,72A 1        P12V_STBY               
                                  2        GND                     
C7P1             CAP_0805-47UF,4V,20%,X6S,C9533A 1        PVCCIN_CPU1             
                                  2        GND                     
C7P2             CAP_0805-47UF,4V,20%,X6S,C9533A 1        PVCCIN_CPU1             
                                  2        GND                     
C7P3             CAP_0805-47UF,4V,20%,X6S,C9533A 1        PVCCIO_CPU1             
                                  2        GND                     
C7P4             CAP_0805-47UF,4V,20%,X6S,C9533A 1        PVCCMCP_CPU1            
                                  2        GND                     
C7P5             CAP_0805-47UF,4V,20%,X6S,C9533A 1        PVCCMCP_CPU1            
                                  2        GND                     
C7P6             CAP_0805-47UF,4V,20%,X6S,C9533A 1        PVCCMCP_CPU1            
                                  2        GND                     
C7P7             CAP_0805-47UF,4V,20%,X6S,C9533A 1        PVCCMCP_CPU1            
                                  2        GND                     
C7P8             CAP_0805-47UF,4V,20%,X6S,C9533A 1        PVCCMCP_CPU1            
                                  2        GND                     
C7P9             CAP_0805-47UF,4V,20%,X6S,C9533A 1        PVCCMCP_CPU1            
                                  2        GND                     
C7P10            CAP_0805-47UF,4V,20%,X6S,C9533A 1        PVCCMCP_CPU1            
                                  2        GND                     
C7P11            CAP_0805-47UF,4V,20%,X6S,C9533A 1        PVCCMCP_CPU1            
                                  2        GND                     
C7P12            CAP_A_0603V-22.0UF,4V,20%,X6S,A 1        PVCCIO_CPU1             
                                  2        GND                     
C7P13            CAP_0805-47UF,4V,20%,X6S,C9533A 1        PVCCMCP_CPU1            
                                  2        GND                     
C7P14            CAP_0805-47UF,4V,20%,X6S,C9533A 1        PVCCMCP_CPU1            
                                  2        GND                     
C7P15            CAP_0805-47UF,4V,20%,X6S,C9533A 1        PVCCMCP_CPU1            
                                  2        GND                     
C7P16            CAP_A_0603V-22.0UF,4V,20%,X6S,A 1        PVCCIO_CPU1             
                                  2        GND                     
C7P17            CAP_0805-47UF,4V,20%,X6S,C9533A 1        PVCCIO_CPU1             
                                  2        GND                     
C7P18            CAP_0805-47UF,4V,20%,X6S,C9533A 1        PVCCIO_CPU1             
                                  2        GND                     
C7P19            CAP_0805-47UF,4V,20%,X6S,C9533A 1        PVCCIN_CPU1             
                                  2        GND                     
C7P20            CAP_0805-47UF,4V,20%,X6S,C9533A 1        PVCCIN_CPU1             
                                  2        GND                     
C7R1             CAP_A_0603V-22.0UF,4V,20%,X6S,A 1        PVCCIO_CPU1             
                                  2        GND                     
C7T1             CAP_0805-100UF,4V,20%,X5R,6024A 1        PVDDQ_GHJ               
                                  2        GND                     
C7T2             CAP_0603LF-10UF,4V,20%,X6S,E15A 1        PVPP_GHJ                
                                  2        GND                     
C7T3             CAP_0603LF-10UF,4V,20%,X6S,E15A 1        PVPP_GHJ                
                                  2        GND                     
C7T4             CAP_A_0603V-22.0UF,4V,20%,X6S,A 1        PVDDQ_GHJ               
                                  2        GND                     
C7T5             CAP_A_0603V-22.0UF,4V,20%,X6S,A 1        PVDDQ_GHJ               
                                  2        GND                     
C7U1             CAP_A_0603V-22.0UF,4V,20%,X6S,A 1        PVDDQ_GHJ               
                                  2        GND                     
C7U2             CAP_A_0603V-22.0UF,4V,20%,X6S,A 1        PVDDQ_GHJ               
                                  2        GND                     
C7U3             CAP_0603LF-10UF,4V,20%,X6S,E15A 1        PVPP_GHJ                
                                  2        GND                     
C7U4             CAP_0603LF-10UF,4V,20%,X6S,E15A 1        PVPP_GHJ                
                                  2        GND                     
C7U5             CAP_0603LF-10UF,4V,20%,X6S,E15A 1        PVPP_GHJ                
                                  2        GND                     
C7U6             CAP_0603LF-10UF,4V,20%,X6S,E15A 1        PVPP_GHJ                
                                  2        GND                     
C7U7             CAP_0805-100UF,4V,20%,X5R,6024A 1        PVDDQ_GHJ               
                                  2        GND                     
C8A2             CAP_0402LF-220PF,50V,10%,X7R,AA 1        VR_PVNN_PCH_AVSP        
                                  2        VSENSE_PVNN_PCH_STBY_AVSN
C8A3             CAP_0402LF-1000PF,50V,10%,X7R,A 1        VR_PVNN_PCH_VINSEN      
                                  2        GND                     
C8A4             CAP_0603LF-0.1UF,25V,10%,X7R,6A 1        P3V3_STBY               
                                  2        GND                     
C8A6             CAP_0603-10UF,6.3V,20%,X6S,E15A 1        P3V3_STBY               
                                  2        GND                     
C8A7             CAP_A_0402V-1.0UF,6.3V,10%,X6SA 1        VR_PVNN_P1V05_PCH_VD12  
                                  2        GND                     
C8A8             CAP_A_0402V-0.1UF,16V,10%,X7R,A 1        VR_PVNN_P1V05_PCH_VD12  
                                  2        GND                     
C8A9             CAP_0402LF-1000PF,50V,10%,X7R,A 1        PWRGD_PVNN_PCH_R        
                                  2        GND                     
C8A10            CAP_0402LF-1000PF,50V,10%,EMPTA 1        PWRGD_P3V3_STBY         
                                  2        GND                     
C8A11            CAP_0402LF-1000PF,50V,10%,X7R,A 1        PWRGD_P1V8_PCH_STBY_R   
                                  2        GND                     
C8A12            CAP_0805-47UF,4V,20%,X6S,C9533A 1        P1V8_PCH_STBY           
                                  2        GND                     
C8A13            CAP_0805-47UF,4V,20%,X6S,C9533A 1        P1V05_PCH_STBY          
                                  2        GND                     
C8A14            CAP_0805-22UF,6.3V,20%,X6S,C95A 1        P1V8_PCH_STBY           
                                  2        GND                     
C8A15            CAPP_SM-470UF,2V,20%,ALUM,6990A 1        P1V05_PCH_STBY          
                                  2        GND                     
C8B1             CAP_A_0603V-22.0UF,4V,20%,X6S,A 1        P1V8_PCH_STBY           
                                  2        GND                     
C8B2             CAP_A_0603V-22.0UF,4V,20%,X6S,A 1        P1V8_PCH_STBY           
                                  2        GND                     
C8B3             CAP_A_0603V-22.0UF,4V,20%,X6S,A 1        P1V8_PCH_STBY           
                                  2        GND                     
C8B4             CAP_A_0603V-22.0UF,4V,20%,X6S,A 1        P1V8_PCH_STBY           
                                  2        GND                     
C8B5             CAP_A_0402V-0.1UF,16V,10%,X7R,A 1        P5V_STBY                
                                  2        GND                     
C8B6             CAP_0805-10UF,16V,10%,X6S,C953A 1        P5V                     
                                  2        GND                     
C8B7             CAP_A_0402V-0.1UF,16V,10%,X7R,A 1        P5V                     
                                  2        GND                     
C8B8             CAP_A_0402V-0.1UF,16V,10%,X7R,A 1        P5V_STBY                
                                  2        GND                     
C8B9             CAP_A_0603V-22.0UF,4V,20%,X6S,A 1        P1V05_PCH_STBY          
                                  2        GND                     
C8B10            CAP_A_0603V-22.0UF,4V,20%,X6S,A 1        P1V05_PCH_STBY          
                                  2        GND                     
C8B11            CAP_A_0603V-22.0UF,4V,20%,X6S,A 1        P1V05_PCH_STBY          
                                  2        GND                     
C8B12            CAP_0805-10UF,16V,10%,X6S,C953A 1        P5V_STBY                
                                  2        GND                     
C8B13            CAP_A_0603V-22.0UF,4V,20%,X6S,A 1        P1V05_PCH_STBY          
                                  2        GND                     
C8B14            CAP_A_0603V-22.0UF,4V,20%,X6S,A 1        P1V05_PCH_STBY          
                                  2        GND                     
C8B15            CAP_0805-47UF,4V,20%,X6S,C9533A 1        P1V05_PCH_STBY          
                                  2        GND                     
C8B16            CAP_0805-47UF,4V,20%,X6S,C9533A 1        P1V05_PCH_STBY          
                                  2        GND                     
C8C1             CAP_0402LF-33.0PF,50V,5%,COG,AA 1        XTAL_KR_25M_IN          
                                  2        GND                     
C8C2             CAP_0402LF-33.0PF,50V,5%,COG,AA 1        XTAL_KR_25M_OUT         
                                  2        GND                     
C8C3             CAP_0603-10UF,6.3V,20%,X6S,E15A 1        P3V3_STBY               
                                  2        GND                     
C8C4             CAP_0603-10UF,6.3V,20%,X6S,E15A 1        P3V3_STBY               
                                  2        GND                     
C8C5             CAP_0603-10UF,6.3V,20%,X6S,E15A 1        P3V3_STBY               
                                  2        GND                     
C8C6             CAP_0603-10UF,6.3V,20%,X6S,E15A 1        P3V3_STBY               
                                  2        GND                     
C8C8             CAP_A_0402V-0.1UF,16V,10%,X7R,A 1        KR_P3_OCP_RX_DP         
                                  2        KR_P3_OCP_RX_C_DP       
C8C9             CAP_A_0402V-0.1UF,16V,10%,X7R,A 1        KR_P3_OCP_RX_DN         
                                  2        KR_P3_OCP_RX_C_DN       
C8C10            CAP_A_0402V-0.1UF,16V,10%,X7R,A 1        KR_P2_OCP_RX_DN         
                                  2        KR_P2_OCP_RX_C_DN       
C8C11            CAP_A_0402V-0.1UF,16V,10%,X7R,A 1        KR_P2_OCP_RX_DP         
                                  2        KR_P2_OCP_RX_C_DP       
C8C12            CAP_A_0402V-0.1UF,16V,10%,X7R,A 1        KR_P1_OCP_RX_DP         
                                  2        KR_P1_OCP_RX_C_DP       
C8C13            CAP_A_0402V-0.1UF,16V,10%,X7R,A 1        KR_P1_OCP_RX_DN         
                                  2        KR_P1_OCP_RX_C_DN       
C8C14            CAP_A_0402V-0.1UF,16V,10%,X7R,A 1        KR_P0_OCP_RX_DN         
                                  2        KR_P0_OCP_RX_C_DN       
C8C15            CAP_A_0402V-0.1UF,16V,10%,X7R,A 1        KR_P0_OCP_RX_DP         
                                  2        KR_P0_OCP_RX_C_DP       
C8D1             CAP_A_0402V-0.1UF,16V,10%,X7R,A 1        P3V3_STBY               
                                  2        GND                     
C8D2             CAP_A_0402V-0.1UF,16V,10%,X7R,A 1        P3V3_STBY               
                                  2        GND                     
C8D3             CAP_0402LF-470PF,50V,10%,EMPTYA 1        IRQ_SML1_PMBUS_ALERT_N  
                                  2        GND                     
C8D4             CAP_A_0402V-0.1UF,16V,10%,X7R,A 1        P3V3_STBY               
                                  2        GND                     
C8E1             CAP_A_0402V-0.1UF,16V,10%,X7R,A 1        P3V3_STBY               
                                  2        GND                     
C8E2             CAP_A_0402V-0.1UF,16V,10%,X7R,A 1        P3V3_STBY               
                                  2        GND                     
C8E3             CAP_A_0402V-0.1UF,16V,10%,X7R,A 1        PWRGD_P12V_HSC          
                                  2        GND                     
C8E4             CAPP_3018-470UF,6.3V,20%,POSCAA 1        P5V_STBY                
                                  2        GND                     
C8E5             CAP_A_0402V-0.1UF,16V,10%,X7R,A 1        P3V3_STBY               
                                  2        GND                     
C8E6             CAP_0603LF-0.1UF,25V,10%,X7R,6A 1        VR_P5V_STBY_BOOT        
                                  2        VR_P5V_STBY_PHASE       
C8E7             CAP_0805-22UF,6.3V,20%,X6S,C95A 1        P5V_STBY                
                                  2        GND                     
C8E8             CAP_A_0402V-0.1UF,16V,10%,X7R,A 1        P3V3_STBY               
                                  2        GND                     
C8E9             CAP_0805-22UF,6.3V,20%,X6S,C95A 1        P5V_STBY                
                                  2        GND                     
C8E10            CAP_1206LF-22UF,16V,10%,X6S,D3A 1        VR_FET_SW_P12V_STBY_P3V3_STBY
                                  2        GND                     
C8E11            CAP_1210-47UF,16V,20%,X6S,D384A 1        VR_FET_SW_P12V_STBY_P3V3_STBY
                                  2        GND                     
C8E12            CAP_0603LF-0.1UF,25V,10%,X7R,6A 1        VR_P3V3_STBY_PHASE      
                                  2        VR_P3V3_STBY_BOOT_R     
C8E13            CAP_0402LF-1000PF,50V,10%,EMPTA 1        PWRGD_P12V_HSC_DLY      
                                  2        AGND_P5V_STBY           
C8E14            CAP_0402-1.0UF,16V,10%,X6S,D97A 1        VR_FET_SW_P12V_STBY_P3V3_STBY
                                  2        GND                     
C8E15            CAP_0402LF-0.022UF,16V,10%,X7RA 1        VR_P5V_STBY_SS          
                                  2        AGND_P5V_STBY           
C8E16            CAP_0402LF-270PF,50V,10%,X7R,AA 1        VR_P5V_STBY_COMP        
                                  2        AGND_P5V_STBY           
C8E17            CAP_0402LF-1000PF,50V,10%,EMPTA 1        PWRGD_P5V_STBY          
                                  2        AGND_P3V3_STBY          
C8E18            CAP_A_0402V-0.1UF,16V,10%,X7R,A 1        P3V3_STBY               
                                  2        GND                     
C8E19            CAP_A_0402V-0.1UF,16V,10%,X7R,A 1        P5V_STBY                
                                  2        GND                     
C8F1             CAP_0402LF-2200PF,50V,10%,X7R,A 1        VR_P5V_STBY_RC_COMP     
                                  2        AGND_P5V_STBY           
C8F2             CAP_0402LF-1000PF,50V,10%,X7R,A 1        PWRGD_P3V3_STBY_R       
                                  2        GND                     
C8F3             CAP_0402LF-3300PF,50V,10%,EMPTA 1        VR_P3V3_STBY_PHASE      
                                  2        VR_P3V3_STBY_SNUB       
C8F4             CAP_A_0402V-1.0UF,6.3V,10%,X6SA 1        P3V3_STBY               
                                  2        GND                     
C8F5             CAP_A_0402V-0.01UF,25V,10%,X7RA 1        P3V3_STBY               
                                  2        GND                     
C8F6             CAP_A_0402V-0.01UF,25V,10%,EMPA 1        SATA6G_S0_TX_DP         
                                  2        P3E_PCH_M2_SATA6G_TX_R_DP
C8F7             CAP_0402-0.22UF,16V,10%,X7R,A3A 1        P3E_PCH_TX_0_DP         
                                  2        P3E_PCH_M2_SATA6G_TX_R_DP
C8F8             CAPP_3018-470UF,6.3V,20%,POSCAA 1        P3V3_STBY               
                                  2        GND                     
C8F9             CAP_A_0402V-1.0UF,6.3V,10%,EMPA 1        P1V8_BMC_STBY_PCIEA     
                                  2        GND                     
C8F10            CAP_0603-10UF,6.3V,20%,EMPTY,EA 1        P1V8_BMC_STBY_PCIEA     
                                  2        GND                     
C8F11            CAP_A_0402V-0.01UF,25V,10%,EMPA 1        SATA6G_S0_TX_DN         
                                  2        P3E_PCH_M2_SATA6G_TX_R_DN
C8F12            CAP_0402-0.22UF,16V,10%,X7R,A3A 1        P3E_PCH_TX_0_DN         
                                  2        P3E_PCH_M2_SATA6G_TX_R_DN
C8F13            CAP_A_0402V-0.01UF,25V,10%,EMPA 1        SATA6G_S0_RX_DP         
                                  2        P3E_PCH_M2_SATA6G_RX_R_DP
C8F14            CAPP_3018-470UF,6.3V,20%,POSCAA 1        P3V3_STBY               
                                  2        GND                     
C8F15            CAP_A_0402V-0.01UF,25V,10%,EMPA 1        SATA6G_S0_RX_DN         
                                  2        P3E_PCH_M2_SATA6G_RX_R_DN
C8F16            CAP_A_0402V-0.1UF,16V,10%,X7R,A 1        P3V3_STBY               
                                  2        GND                     
C8F17            CAP_A_0402V-0.1UF,16V,10%,X7R,A 1        P5V_STBY                
                                  2        GND                     
C8F18            CAP_0402LF-27.0PF,50V,5%,COG,AA 1        XTAL_CK_MNG_IN          
                                  2        GND                     
C8F19            CAP_0402LF-27.0PF,50V,5%,COG,AA 1        XTAL_CK_MNG_OUT         
                                  2        GND                     
C8G1             CAP_0402-0.22UF,16V,10%,X7R,A3A 1        P3E_CPU0_PE2_SS_TXP<4>  
                                  2        P3E_CPU0_PE2_SS_C_TXP<4>
C8G2             CAP_0402-0.22UF,16V,10%,X7R,A3A 1        P3E_CPU0_PE2_SS_TXN<4>  
                                  2        P3E_CPU0_PE2_SS_C_TXN<4>
C8G3             CAP_0402-0.22UF,16V,10%,X7R,A3A 1        P3E_CPU0_PE2_SS_TXP<3>  
                                  2        P3E_CPU0_PE2_SS_C_TXP<3>
C8G4             CAP_0402-0.22UF,16V,10%,X7R,A3A 1        P3E_CPU0_PE2_SS_TXN<3>  
                                  2        P3E_CPU0_PE2_SS_C_TXN<3>
C8G5             CAP_0402-0.22UF,16V,10%,X7R,A3A 1        P3E_CPU0_PE2_SS_TXP<2>  
                                  2        P3E_CPU0_PE2_SS_C_TXP<2>
C8G6             CAP_0402-0.22UF,16V,10%,X7R,A3A 1        P3E_CPU0_PE2_SS_TXN<2>  
                                  2        P3E_CPU0_PE2_SS_C_TXN<2>
C8G7             CAP_0402-0.22UF,16V,10%,X7R,A3A 1        P3E_CPU0_PE2_SS_TXN<1>  
                                  2        P3E_CPU0_PE2_SS_C_TXN<1>
C8G8             CAP_0402-0.22UF,16V,10%,X7R,A3A 1        P3E_CPU0_PE2_SS_TXP<1>  
                                  2        P3E_CPU0_PE2_SS_C_TXP<1>
C8G9             CAP_0402-0.22UF,16V,10%,X7R,A3A 1        P3E_CPU0_PE2_SS_TXP<0>  
                                  2        P3E_CPU0_PE2_SS_C_TXP<0>
C8G10            CAP_0402-0.22UF,16V,10%,X7R,A3A 1        P3E_CPU0_PE2_SS_TXN<0>  
                                  2        P3E_CPU0_PE2_SS_C_TXN<0>
C8L1             CAP_0805-100UF,4V,20%,X5R,6024A 1        PVDDQ_KLM               
                                  2        GND                     
C8L2             CAP_0805-100UF,4V,20%,X5R,6024A 1        PVDDQ_KLM               
                                  2        GND                     
C8L3             CAP_A_0603V-47UF,4V,20%,X5R,60A 1        PVTT_KLM                
                                  2        GND                     
C8L4             CAP_A_0603V-47UF,4V,20%,X5R,60A 1        PVTT_KLM                
                                  2        GND                     
C8L5             CAP_A_0603V-22.0UF,4V,20%,X6S,A 1        PVDDQ_KLM               
                                  2        GND                     
C8L6             CAP_A_0603V-22.0UF,4V,20%,X6S,A 1        PVDDQ_KLM               
                                  2        GND                     
C8L7             CAP_A_0603V-22.0UF,4V,20%,X6S,A 1        PVDDQ_KLM               
                                  2        GND                     
C8L8             CAP_A_0603V-22.0UF,4V,20%,X6S,A 1        PVDDQ_KLM               
                                  2        GND                     
C8L9             CAP_A_0603V-22.0UF,4V,20%,X6S,A 1        PVDDQ_KLM               
                                  2        GND                     
C8L10            CAP_A_0603V-22.0UF,4V,20%,X6S,A 1        PVDDQ_KLM               
                                  2        GND                     
C8L11            CAP_0805-100UF,4V,20%,X5R,6024A 1        PVDDQ_KLM               
                                  2        GND                     
C8L12            CAP_A_0603V-47UF,4V,20%,X5R,60A 1        PVDDQ_KLM               
                                  2        GND                     
C8M1             CAP_A_0603V-22.0UF,4V,20%,X6S,A 1        PVDDQ_KLM               
                                  2        GND                     
C8M2             CAP_A_0603V-47UF,4V,20%,X5R,60A 1        PVDDQ_KLM               
                                  2        GND                     
C8M3             CAP_A_0603V-22.0UF,4V,20%,X6S,A 1        PVDDQ_KLM               
                                  2        GND                     
C8M4             CAP_A_0603V-22.0UF,4V,20%,X6S,A 1        PVDDQ_KLM               
                                  2        GND                     
C8M5             CAP_A_0603V-22.0UF,4V,20%,X6S,A 1        PVDDQ_KLM               
                                  2        GND                     
C8M6             CAP_A_0603V-22.0UF,4V,20%,X6S,A 1        PVDDQ_KLM               
                                  2        GND                     
C8M7             CAP_0805-100UF,4V,20%,X5R,6024A 1        PVDDQ_KLM               
                                  2        GND                     
C8M8             CAP_A_0603V-47UF,4V,20%,X5R,60A 1        PVDDQ_KLM               
                                  2        GND                     
C8M9             CAP_A_0603V-47UF,4V,20%,X5R,60A 1        PVDDQ_KLM               
                                  2        GND                     
C8M10            CAP_A_0603V-47UF,4V,20%,X5R,60A 1        PVDDQ_KLM               
                                  2        GND                     
C8M11            CAP_0805-100UF,4V,20%,X5R,6024A 1        PVDDQ_KLM               
                                  2        GND                     
C8M12            CAP_A_0603V-47UF,4V,20%,X5R,60A 1        PVTT_KLM                
                                  2        GND                     
C8P1             CAP_0805LF-22UF,4V,20%,X6S,C95A 1        PVDDQ_KLM               
                                  2        GND                     
C8P2             CAP_0805LF-22UF,4V,20%,X6S,C95A 1        PVDDQ_KLM               
                                  2        GND                     
C8P3             CAP_0805-47UF,4V,20%,X6S,C9533A 1        PVCCIN_CPU1             
                                  2        GND                     
C8P4             CAP_0805-47UF,4V,20%,X6S,C9533A 1        PVCCIN_CPU1             
                                  2        GND                     
C8P5             CAP_0805LF-22UF,4V,20%,X6S,C95A 1        PVSA_CPU1               
                                  2        GND                     
C8P6             CAP_0805LF-22UF,4V,20%,X6S,C95A 1        PVSA_CPU1               
                                  2        GND                     
C8P7             CAP_0805LF-22UF,4V,20%,X6S,C95A 1        PVSA_CPU1               
                                  2        GND                     
C8P8             CAP_0805-47UF,4V,20%,X6S,C9533A 1        PVCCMCP_CPU1            
                                  2        GND                     
C8P9             CAP_0805-47UF,4V,20%,X6S,C9533A 1        PVCCMCP_CPU1            
                                  2        GND                     
C8P10            CAP_0805-47UF,4V,20%,X6S,C9533A 1        PVCCIN_CPU1             
                                  2        GND                     
C8P11            CAP_0805-47UF,4V,20%,X6S,C9533A 1        PVCCIN_CPU1             
                                  2        GND                     
C8P12            CAP_0805-47UF,4V,20%,X6S,C9533A 1        PVCCIN_CPU1             
                                  2        GND                     
C8P13            CAP_0805-47UF,4V,20%,X6S,C9533A 1        PVCCIN_CPU1             
                                  2        GND                     
C8P14            CAP_0805-47UF,4V,20%,X6S,C9533A 1        PVCCMCP_CPU1            
                                  2        GND                     
C8P15            CAP_0805-47UF,4V,20%,X6S,C9533A 1        PVCCMCP_CPU1            
                                  2        GND                     
C8P16            CAP_0805-47UF,4V,20%,X6S,C9533A 1        PVCCIN_CPU1             
                                  2        GND                     
C8P17            CAP_0805-47UF,4V,20%,X6S,C9533A 1        PVCCIN_CPU1             
                                  2        GND                     
C8P18            CAP_0805-47UF,4V,20%,X6S,C9533A 1        PVCCIN_CPU1             
                                  2        GND                     
C8P19            CAP_0805-47UF,4V,20%,X6S,C9533A 1        PVCCIN_CPU1             
                                  2        GND                     
C8P20            CAP_0805-47UF,4V,20%,X6S,C9533A 1        PVCCIN_CPU1             
                                  2        GND                     
C8P21            CAP_0805-47UF,4V,20%,X6S,C9533A 1        PVCCIN_CPU1             
                                  2        GND                     
C8P22            CAP_0805-47UF,4V,20%,X6S,C9533A 1        PVCCMCP_CPU1            
                                  2        GND                     
C8P23            CAP_0805-47UF,4V,20%,X6S,C9533A 1        PVCCMCP_CPU1            
                                  2        GND                     
C8P24            CAP_0805-47UF,4V,20%,X6S,C9533A 1        PVCCIN_CPU1             
                                  2        GND                     
C8P25            CAP_0805-47UF,4V,20%,X6S,C9533A 1        PVCCIN_CPU1             
                                  2        GND                     
C8P26            CAP_0805-47UF,4V,20%,X6S,C9533A 1        PVCCIN_CPU1             
                                  2        GND                     
C8P27            CAP_0805-47UF,4V,20%,X6S,C9533A 1        PVCCIN_CPU1             
                                  2        GND                     
C8P28            CAP_0805-47UF,4V,20%,X6S,C9533A 1        PVCCIN_CPU1             
                                  2        GND                     
C8P29            CAP_0805-47UF,4V,20%,X6S,C9533A 1        PVCCIN_CPU1             
                                  2        GND                     
C8P30            CAP_0805LF-22UF,4V,20%,X6S,C95A 1        PVDDQ_GHJ               
                                  2        GND                     
C8P31            CAP_0805LF-22UF,4V,20%,X6S,C95A 1        PVDDQ_GHJ               
                                  2        GND                     
C8P32            CAP_0805-47UF,4V,20%,X6S,C9533A 1        PVCCIN_CPU1             
                                  2        GND                     
C8P33            CAP_0805-47UF,4V,20%,X6S,C9533A 1        PVCCIN_CPU1             
                                  2        GND                     
C8P34            CAP_0805-47UF,4V,20%,X6S,C9533A 1        PVCCIN_CPU1             
                                  2        GND                     
C8T1             CAP_A_0603V-47UF,4V,20%,X5R,60A 1        PVDDQ_GHJ               
                                  2        GND                     
C8T2             CAP_A_0603V-47UF,4V,20%,X5R,60A 1        PVDDQ_GHJ               
                                  2        GND                     
C8T3             CAP_A_0603V-47UF,4V,20%,X5R,60A 1        PVTT_GHJ                
                                  2        GND                     
C8T4             CAP_A_0603V-47UF,4V,20%,X5R,60A 1        PVDDQ_GHJ               
                                  2        GND                     
C8T5             CAP_A_0603V-22.0UF,4V,20%,X6S,A 1        PVDDQ_GHJ               
                                  2        GND                     
C8T6             CAP_A_0603V-22.0UF,4V,20%,X6S,A 1        PVDDQ_GHJ               
                                  2        GND                     
C8T7             CAP_A_0603V-22.0UF,4V,20%,X6S,A 1        PVDDQ_GHJ               
                                  2        GND                     
C8T8             CAP_A_0603V-22.0UF,4V,20%,X6S,A 1        PVDDQ_GHJ               
                                  2        GND                     
C8T9             CAP_A_0603V-22.0UF,4V,20%,X6S,A 1        PVDDQ_GHJ               
                                  2        GND                     
C8T10            CAP_A_0603V-22.0UF,4V,20%,X6S,A 1        PVDDQ_GHJ               
                                  2        GND                     
C8T11            CAP_A_0603V-47UF,4V,20%,X5R,60A 1        PVDDQ_GHJ               
                                  2        GND                     
C8U1             CAP_0805-100UF,4V,20%,X5R,6024A 1        PVDDQ_GHJ               
                                  2        GND                     
C8U2             CAP_A_0603V-22.0UF,4V,20%,X6S,A 1        PVDDQ_GHJ               
                                  2        GND                     
C8U3             CAP_A_0603V-22.0UF,4V,20%,X6S,A 1        PVDDQ_GHJ               
                                  2        GND                     
C8U4             CAP_A_0603V-22.0UF,4V,20%,X6S,A 1        PVDDQ_GHJ               
                                  2        GND                     
C8U5             CAP_A_0603V-22.0UF,4V,20%,X6S,A 1        PVDDQ_GHJ               
                                  2        GND                     
C8U6             CAP_A_0603V-22.0UF,4V,20%,X6S,A 1        PVDDQ_GHJ               
                                  2        GND                     
C8U7             CAP_A_0603V-22.0UF,4V,20%,X6S,A 1        PVDDQ_GHJ               
                                  2        GND                     
C8U8             CAP_0805-100UF,4V,20%,X5R,6024A 1        PVDDQ_GHJ               
                                  2        GND                     
C8U9             CAP_A_0603V-47UF,4V,20%,X5R,60A 1        PVDDQ_GHJ               
                                  2        GND                     
C8U10            CAP_A_0603V-47UF,4V,20%,X5R,60A 1        PVTT_GHJ                
                                  2        GND                     
C8U11            CAP_0805-100UF,4V,20%,X5R,6024A 1        PVDDQ_GHJ               
                                  2        GND                     
C8U12            CAP_0805-100UF,4V,20%,X5R,6024A 1        PVDDQ_GHJ               
                                  2        GND                     
C8U13            CAP_A_0603V-47UF,4V,20%,X5R,60A 1        PVDDQ_GHJ               
                                  2        GND                     
C9A1             CAP_A_0402V-0.1UF,16V,10%,X7R,A 1        P5V_STBY_DGB_FS         
                                  2        GND                     
C9A2             CAP_A_0402V-0.1UF,16V,10%,X7R,A 1        XDP_SYSPWROK            
                                  2        GND                     
C9A3             CAP_A_0402V-0.1UF,16V,10%,X7R,A 1        P3V3_STBY               
                                  2        GND                     
C9A4             CAP_A_0402V-0.1UF,16V,10%,X7R,A 1        XDP_CPU_PWR_DEBUG_N     
                                  2        GND                     
C9A5             CAP_A_0402V-0.1UF,16V,10%,X7R,A 1        XDP_RST_CO_N            
                                  2        GND                     
C9A6             CAP_A_0402V-1.0UF,6.3V,10%,X6SA 1        P1V05_PCH_STBY          
                                  2        GND                     
C9B1             CAP_0805-10UF,16V,10%,X6S,C953A 1        P5V_HDD_SATA            
                                  2        GND                     
C9B2             CAP_0805-10UF,16V,10%,X6S,C953A 1        P12V_HDD_SATA           
                                  2        GND                     
C9B7             CAP_A_0402V-0.1UF,16V,10%,X7R,A 1        P3V3_STBY               
                                  2        GND                     
C9B8             CAPP_7343HLF-330UF,10V,20%,POSA 1        P5V_USB                 
                                  2        GND                     
C9B9             CAP_A_0402V-1.0UF,6.3V,10%,X6SA 1        P5V_STBY                
                                  2        GND                     
C9B10            CAP_A_0402V-0.1UF,16V,10%,X7R,A 1        P5V_STBY                
                                  2        GND                     
C9E1             CAP_A_0603V-22.0UF,4V,20%,EMPTA 1        P0V9_LAN                
                                  2        GND                     
C9E4             CAP_A_0402V-0.1UF,16V,10%,X7R,A 1        PE_PCH_SPRV_RX_DP       
                                  2        PE_PCH_SPRV_RX_C_DP     
C9E5             CAP_A_0402V-0.1UF,16V,10%,X7R,A 1        PE_PCH_SPRV_RX_DN       
                                  2        PE_PCH_SPRV_RX_C_DN     
C9E6             CAP_1210-47UF,16V,20%,EMPTY,D3A 1        P1V5_LAN                
                                  2        GND                     
C9E7             CAP_0402LF-0.039UF,25V,10%,X7RA 1        A_CTOP                  
                                  2        A_CBOT                  
C9E8             CAP_0402LF-22.0PF,50V,5%,COG,AA 1        XTAL_25MHZ_OUT_R        
                                  2        GND                     
C9E9             CAP_0402LF-22.0PF,50V,5%,COG,AA 1        XTAL_25MHZ_IN           
                                  2        GND                     
C9E10            CAP_0603-10UF,6.3V,20%,X6S,E15A 1        P1V26_BMC_STBY          
                                  2        GND                     
C9E11            CAP_0402-1.0UF,16V,10%,X6S,D97A 1        P3V3_STBY               
                                  2        GND                     
C9E12            CAP_A_0603V-22.0UF,4V,20%,EMPTA 1        P0V9_LAN                
                                  2        GND                     
C9F1             CAP_1210-47UF,16V,20%,X6S,D384A 1        VR_FET_SW_P12V_STBY_P3V3_STBY
                                  2        GND                     
C9F2             CAP_1210-47UF,16V,20%,EMPTY,D3A 1        P3V3_STBY               
                                  2        GND                     
C9F3             CAP_0603-10UF,6.3V,20%,X6S,E15A 1        P1V538_BMC_STBY         
                                  2        GND                     
C9F4             CAP_0805LF-22UF,4V,20%,X6S,C95A 1        P1V26_BMC_STBY          
                                  2        GND                     
C9F5             CAP_A_0402V-0.1UF,16V,10%,X7R,A 1        P3V3_STBY               
                                  2        GND                     
C9F6             CAP_0402LF-1000PF,50V,10%,EMPTA 1        PWRGD_P3V3_STBY         
                                  2        GND                     
C9F8             CAP_0402LF-1000PF,50V,10%,X7R,A 1        PWRGD_P1V26_BMC_STBY_R  
                                  2        GND                     
C9F9             CAP_0402LF-1000PF,50V,10%,EMPTA 1        PWRGD_P1V538_BMC_STBY   
                                  2        GND                     
C9F10            CAP_0402LF-1000PF,50V,10%,X7R,A 1        PWRGD_P1V538_BMC_STBY_R 
                                  2        GND                     
C9F11            CAP_A_0402V-0.1UF,16V,10%,X7R,A 1        P3V3_STBY               
                                  2        GND                     
C9F12            CAP_A_0402V-1.0UF,6.3V,10%,X6SA 1        P1V26_BMC_STBY_V1PLLAV12
                                  2        GND                     
C9F13            CAP_0805LF-22UF,4V,20%,X6S,C95A 1        P1V538_BMC_STBY         
                                  2        GND                     
C9F14            CAP_A_0402V-0.1UF,16V,10%,X7R,A 1        P1V26_BMC_STBY_V1PLLAV12
                                  2        GND                     
C9F15            CAP_A_0402V-0.1UF,16V,10%,EMPTA 1        P1V8_BMC_STBY_PCIEA     
                                  2        GND                     
C9F16            CAP_A_0402V-0.1UF,16V,10%,EMPTA 1        P2E_SSB_BMC_RX_DN       
                                  2        P2E_SSB_BMC_RX_C_DN     
C9F17            CAP_A_0402V-0.1UF,16V,10%,EMPTA 1        P2E_SSB_BMC_RX_DP       
                                  2        P2E_SSB_BMC_RX_C_DP     
C9F18            CAP_0402LF-100.0PF,50V,5%,COG,A 1        P1V26_BMC_STBY_V1PLLAV12
                                  2        GND                     
C9F19            CAP_A_0402V-0.1UF,16V,10%,X7R,A 1        P3V3_STBY               
                                  2        GND                     
C9F20            CAP_0402LF-12.0PF,50V,5%,COG,AA 1        XTAL_24MHZ_PI7C9X1172_IN
                                  2        GND                     
C9F21            CAP_0402LF-12.0PF,50V,5%,COG,AA 1        XTAL_24MHZ_PI7C9X1172_OUT
                                  2        GND                     
C9F22            CAP_0402LF-470PF,50V,10%,X7R,AA 1        LED_LAN_1_N             
                                  2        GND                     
C9F23            CAP_A_0402V-0.1UF,16V,10%,X7R,A 1        P3V3_STBY               
                                  2        GND                     
C9G1             CAP_0402LF-470PF,50V,10%,X7R,AA 1        LED_LAN_2_N             
                                  2        GND                     
C9G2             CAP_0402LF-470PF,50V,10%,X7R,AA 1        P3V3_STBY               
                                  2        GND                     
C9G3             CAP_0402LF-470PF,50V,10%,X7R,AA 1        LED_LAN_0_N             
                                  2        GND                     
C9G4             CAP_A_0402V-0.1UF,16V,10%,X7R,A 1        GND_LAN_TRCT1234_C      
                                  2        GND                     
C9G5             CAP_0402-1.0UF,16V,10%,X7S,G71A 1        GND_LAN_TRCT1234_C      
                                  2        GND                     
C9G6             CAP_A_0402V-0.1UF,16V,10%,X7R,A 1        GND_LAN_TRCT1234_C      
                                  2        GND                     
C9G7             CAP_A_0402V-0.1UF,16V,10%,X7R,A 1        P3V3_STBY               
                                  2        GND                     
C9G8             CAP_A_0402V-0.1UF,16V,10%,EMPTA 1        P3V3_STBY_BMC_ADCVREFP  
                                  2        P3V3_STBY_BMC_ADCVREFN  
C9G9             CAP_0402LF-4700PF,50V,10%,EMPTA 1        NIC_SER_P_MDI_3_DP      
                                  2        NIC_MDI_MNG_RX_DP       
C9G10            CAP_A_0402V-0.1UF,16V,10%,EMPTA 1        GND                     
                                  2        P3V3_STBY_BMC_ADCVREFN  
C9G11            CAP_A_0402V-0.1UF,16V,10%,EMPTA 1        P3V3_STBY_BMC_ADCAV33   
                                  2        P3V3_STBY_BMC_ADCVREFP  
C9G12            CAP_0402LF-4700PF,50V,10%,EMPTA 1        NIC_SER_N_MDI_3_DN      
                                  2        NIC_MDI_MNG_RX_DN       
C9G13            CAP_0402LF-4700PF,50V,10%,EMPTA 1        NIC_SET_N_MDI_2_DN      
                                  2        NIC_MDI_MNG_TX_DN       
C9G14            CAP_0402LF-47.0PF,50V,5%,COG,AA 1        A_P3V3_SCALED           
                                  2        GND                     
C9G15            CAP_0402LF-47.0PF,50V,5%,COG,AA 1        A_P5V_SCALED            
                                  2        GND                     
C9G16            CAP_0402LF-4700PF,50V,10%,EMPTA 1        NIC_SET_P_MDI_2_DP      
                                  2        NIC_MDI_MNG_TX_DP       
C9G17            CAP_0402LF-47.0PF,50V,5%,COG,AA 1        A_P12V_STBY_SCALED      
                                  2        GND                     
C9G18            CAP_0402LF-47.0PF,50V,5%,COG,AA 1        A_PVNN_STBY_PCH_SENSOR  
                                  2        GND                     
C9G19            CAP_A_0402V-0.1UF,16V,10%,X7R,A 1        P3V3_FB_ADC128_VCC      
                                  2        GND                     
C9G20            CAP_0402LF-47.0PF,50V,5%,COG,AA 1        A_P3V3_STBY_SCALED      
                                  2        GND                     
C9G21            CAP_0402LF-47.0PF,50V,5%,COG,AA 1        A_P5V_STBY_SCALED       
                                  2        GND                     
C9G22            CAP_0402LF-10.0PF,50V,5%,COG,AA 1        A_P3V_BAT_SCALED        
                                  2        GND                     
C9L1             CAP_A_0402V-0.01UF,25V,10%,X7RA 1        M_M_VREF                
                                  2        GND                     
C9L2             CAPP_3018-470UF,2.5V,20%,ALUM,A 1        PVDDQ_KLM               
                                  2        GND                     
C9L3             CAP_A_0402V-0.01UF,25V,10%,X7RA 1        M_M_CPU_VREF            
                                  2        GND                     
C9L4             CAPP_3018-470UF,2.5V,20%,ALUM,A 1        PVDDQ_KLM               
                                  2        GND                     
C9L5             CAP_0805-10UF,16V,10%,X6S,C953A 1        VR_FET_SW_P12V_STBY_PVDDQ_KLM
                                  2        GND                     
C9L6             CAP_0805-10UF,16V,10%,X6S,C953A 1        VR_FET_SW_P12V_STBY_PVDDQ_KLM
                                  2        GND                     
C9L7             CAP_A_0402V-0.01UF,25V,10%,X7RA 1        M_L_VREF                
                                  2        GND                     
C9L8             CAP_A_0402V-0.01UF,25V,10%,X7RA 1        M_L_CPU_VREF            
                                  2        GND                     
C9L9             CAPP_3018-470UF,2.5V,20%,ALUM,A 1        PVDDQ_KLM               
                                  2        GND                     
C9L10            CAP_0805-10UF,16V,10%,X6S,C953A 1        VR_FET_SW_P12V_STBY_PVDDQ_KLM
                                  2        GND                     
C9L11            CAP_0805-10UF,16V,10%,X6S,C953A 1        VR_FET_SW_P12V_STBY_PVDDQ_KLM
                                  2        GND                     
C9L12            CAPP_3018-470UF,2.5V,20%,ALUM,A 1        PVDDQ_KLM               
                                  2        GND                     
C9L13            CAP_0805-10UF,16V,10%,X6S,C953A 1        VR_FET_SW_P12V_STBY_PVDDQ_KLM
                                  2        GND                     
C9L14            CAP_0805-10UF,16V,10%,X6S,C953A 1        VR_FET_SW_P12V_STBY_PVDDQ_KLM
                                  2        GND                     
C9M1             CAP_A_0402V-0.01UF,25V,10%,X7RA 1        M_K_VREF                
                                  2        GND                     
C9M2             CAP_A_0402V-0.01UF,25V,10%,X7RA 1        M_K_CPU_VREF            
                                  2        GND                     
C9M3             CAPP_3018-68UF,16V,20%,TANT,72A 1        P12V_STBY               
                                  2        GND                     
C9M4             CAP_0805-10UF,16V,10%,X6S,C953A 1        P12V_FAN                
                                  2        GND                     
C9M5             CAP_A_0402V-0.1UF,16V,10%,X7R,A 1        P12V_FAN                
                                  2        GND                     
C9M6             CAP_A_0402V-0.1UF,16V,10%,X7R,A 1        P5V_STBY                
                                  2        GND                     
C9M7             CAP_A_0402V-0.1UF,16V,10%,X7R,A 1        P3V3_STBY               
                                  2        GND                     
C9M8             CAP_A_0402V-0.1UF,16V,10%,X7R,A 1        PVCCIO_CPU1             
                                  2        GND                     
C9M9             CAP_A_0402V-0.1UF,16V,10%,X7R,A 1        P12V_STBY               
                                  2        GND                     
C9M10            CAP_0805-10UF,16V,10%,X6S,C953A 1        P12V_STBY               
                                  2        GND                     
C9M11            CAP_A_0402V-0.1UF,16V,10%,X7R,A 1        VR_PVDDQ_KLM_AIINSEN    
                                  2        GND                     
C9N1             CAP_0402-0.22UF,16V,10%,X7R,A3A 1        P3E_CPU1_PE3_MP_C_TXP<10>
                                  2        P3E_CPU1_PE3_MP_TXP<10> 
C9N2             CAP_0402-0.22UF,16V,10%,X7R,A3A 1        P3E_CPU1_PE3_MP_C_TXN<10>
                                  2        P3E_CPU1_PE3_MP_TXN<10> 
C9N3             CAP_0402-0.22UF,16V,10%,X7R,A3A 1        P3E_CPU1_PE3_MP_C_TXN<11>
                                  2        P3E_CPU1_PE3_MP_TXN<11> 
C9N4             CAP_0402-0.22UF,16V,10%,X7R,A3A 1        P3E_CPU1_PE3_MP_C_TXP<11>
                                  2        P3E_CPU1_PE3_MP_TXP<11> 
C9N5             CAP_0402-0.22UF,16V,10%,X7R,A3A 1        P3E_CPU1_PE3_MP_C_TXP<13>
                                  2        P3E_CPU1_PE3_MP_TXP<13> 
C9N6             CAP_0402-0.22UF,16V,10%,X7R,A3A 1        P3E_CPU1_PE3_MP_C_TXN<13>
                                  2        P3E_CPU1_PE3_MP_TXN<13> 
C9N7             CAP_0402-0.22UF,16V,10%,X7R,A3A 1        P3E_CPU1_PE3_MP_C_TXP<15>
                                  2        P3E_CPU1_PE3_MP_TXP<15> 
C9N8             CAP_0402-0.22UF,16V,10%,X7R,A3A 1        P3E_CPU1_PE3_MP_C_TXN<14>
                                  2        P3E_CPU1_PE3_MP_TXN<14> 
C9N9             CAP_0402-0.22UF,16V,10%,X7R,A3A 1        P3E_CPU1_PE3_MP_C_TXN<15>
                                  2        P3E_CPU1_PE3_MP_TXN<15> 
C9N10            CAP_0402-0.22UF,16V,10%,X7R,A3A 1        P3E_CPU1_PE3_MP_C_TXP<14>
                                  2        P3E_CPU1_PE3_MP_TXP<14> 
C9N11            CAPP_3018-470UF,2.5V,20%,ALUM,A 1        PVSA_CPU1               
                                  2        GND                     
C9N12            CAP_0402-0.22UF,16V,10%,X7R,A3A 1        P3E_CPU1_PE3_MP_C_TXP<9>
                                  2        P3E_CPU1_PE3_MP_TXP<9>  
C9N13            CAP_0805-10UF,16V,10%,X6S,C953A 1        VR_FET_SW_P12V_STBY_PVCCIN_CPU1
                                  2        GND                     
C9N14            CAP_0402-0.22UF,16V,10%,X7R,A3A 1        P3E_CPU1_PE3_MP_C_TXP<12>
                                  2        P3E_CPU1_PE3_MP_TXP<12> 
C9N15            CAP_0402-0.22UF,16V,10%,X7R,A3A 1        P3E_CPU1_PE3_MP_C_TXN<9>
                                  2        P3E_CPU1_PE3_MP_TXN<9>  
C9N16            CAP_0402-0.22UF,16V,10%,X7R,A3A 1        P3E_CPU1_PE3_MP_C_TXN<12>
                                  2        P3E_CPU1_PE3_MP_TXN<12> 
C9N17            CAP_0402-0.22UF,16V,10%,X7R,A3A 1        P3E_CPU1_PE3_MP_C_TXP<8>
                                  2        P3E_CPU1_PE3_MP_TXP<8>  
C9N18            CAP_0402-0.22UF,16V,10%,X7R,A3A 1        P3E_CPU1_PE3_MP_C_TXN<8>
                                  2        P3E_CPU1_PE3_MP_TXN<8>  
C9N19            CAP_0805-10UF,16V,10%,X6S,C953A 1        VR_FET_SW_P12V_STBY_PVCCIN_CPU1
                                  2        GND                     
C9N20            CAPP_3018-470UF,2.5V,20%,ALUM,A 1        PVSA_CPU1               
                                  2        GND                     
C9N21            CAP_0805-10UF,16V,10%,X6S,C953A 1        VR_FET_SW_P12V_STBY_PVCCIN_CPU1
                                  2        GND                     
C9N22            CAP_A_0603V-22.0UF,4V,20%,X6S,A 1        PVSA_CPU1               
                                  2        GND                     
C9N24            CAPP_3018-470UF,2.5V,20%,ALUM,A 1        PVCCIN_CPU1             
                                  2        GND                     
C9N25            CAP_0805-10UF,16V,10%,X6S,C953A 1        VR_FET_SW_P12V_STBY_PVCCIN_CPU1
                                  2        GND                     
C9N26            CAP_0805-10UF,16V,10%,X6S,C953A 1        VR_FET_SW_P12V_STBY_PVCCIN_CPU1
                                  2        GND                     
C9N27            CAP_0805-10UF,16V,10%,X6S,C953A 1        VR_FET_SW_P12V_STBY_PVCCIN_CPU1
                                  2        GND                     
C9P1             CAP_0805-10UF,16V,10%,X6S,C953A 1        VR_FET_SW_P12V_STBY_PVCCIN_CPU1
                                  2        GND                     
C9P2             CAP_0805-10UF,16V,10%,X6S,C953A 1        VR_FET_SW_P12V_STBY_PVCCIN_CPU1
                                  2        GND                     
C9P3             CAP_A_0603V-22.0UF,4V,20%,X6S,A 1        PVCCIN_CPU1             
                                  2        GND                     
C9P4             CAP_0805-10UF,16V,10%,X6S,C953A 1        VR_FET_SW_P12V_STBY_PVCCIN_CPU1
                                  2        GND                     
C9P5             CAPP_3018-470UF,2.5V,20%,ALUM,A 1        PVCCIN_CPU1             
                                  2        GND                     
C9P6             CAP_A_0402V-0.1UF,16V,10%,X7R,A 1        P12V_STBY               
                                  2        AGND_HSC                
C9P7             CAP_0805-10UF,16V,10%,X6S,C953A 1        VR_FET_SW_P12V_STBY_PVCCIN_CPU1
                                  2        GND                     
C9P8             CAPP_3018-470UF,2.5V,20%,ALUM,A 1        PVCCIN_CPU1             
                                  2        GND                     
C9P9             CAP_0805-10UF,16V,10%,X6S,C953A 1        VR_FET_SW_P12V_STBY_PVCCIN_CPU1
                                  2        GND                     
C9P10            CAP_A_0603V-22.0UF,4V,20%,X6S,A 1        PVCCIN_CPU1             
                                  2        GND                     
C9P11            CAP_A_0402V-0.1UF,16V,10%,X7R,A 1        P3V3_STBY               
                                  2        GND                     
C9P12            CAP_A_0402V-0.1UF,16V,10%,EMPTA 1        A_HSC_VOUT              
                                  2        AGND_HSC                
C9P14            CAP_0603LF-0.033UF,50V,10%,X7RA 1        A_HSC_TIMER             
                                  2        AGND_HSC                
C9P15            CAP_A_0402V-0.1UF,16V,10%,X7R,A 1        A_HSC_ISET              
                                  2        AGND_HSC                
C9P16            CAP_A_0402V-0.1UF,16V,10%,EMPTA 1        A_HSC_MOP               
                                  2        AGND_HSC                
C9P17            CAP_A_0402V-0.1UF,16V,10%,EMPTA 1        A_HSC_MON               
                                  2        AGND_HSC                
C9P18            CAPP_3018-470UF,2.5V,20%,ALUM,A 1        PVCCIN_CPU1             
                                  2        GND                     
C9P20            CAP_A_0603V-22.0UF,4V,20%,X6S,A 1        PVCCIN_CPU1             
                                  2        GND                     
C9P22            CAP_0805-10UF,16V,10%,X6S,C953A 1        VR_FET_SW_P12V_STBY_PVCCIN_CPU1
                                  2        GND                     
C9P23            CAPP_3018-470UF,2.5V,20%,ALUM,A 1        PVCCIN_CPU1             
                                  2        GND                     
C9P24            CAP_0805-10UF,16V,10%,X6S,C953A 1        VR_FET_SW_P12V_STBY_PVCCIN_CPU1
                                  2        GND                     
C9P25            CAP_0805-10UF,16V,10%,X6S,C953A 1        VR_FET_SW_P12V_STBY_PVCCIN_CPU1
                                  2        GND                     
C9P26            CAP_0805-10UF,16V,10%,X6S,C953A 1        VR_FET_SW_P12V_STBY_PVCCIN_CPU1
                                  2        GND                     
C9R2             CAP_A_0603V-22.0UF,4V,20%,X6S,A 1        PVCCIN_CPU1             
                                  2        GND                     
C9R3             CAPP_3018-470UF,2.5V,20%,ALUM,A 1        PVCCIN_CPU1             
                                  2        GND                     
C9R5             CAP_0805-10UF,16V,10%,X6S,C953A 1        P12V_PSU                
                                  2        GND                     
C9R6             CAP_A_0402V-0.1UF,16V,10%,X7R,A 1        P12V_PSU                
                                  2        GND                     
C9R7             CAP_0805-10UF,16V,10%,X6S,C953A 1        VR_FET_SW_P12V_STBY_PVCCIN_CPU1
                                  2        GND                     
C9R8             CAP_A_0603V-22.0UF,4V,20%,X6S,A 1        PVCCIN_CPU1             
                                  2        GND                     
C9R9             CAPP_3018-470UF,2.5V,20%,ALUM,A 1        PVCCIN_CPU1             
                                  2        GND                     
C9R10            CAP_0805-10UF,16V,10%,X6S,C953A 1        VR_FET_SW_P12V_STBY_PVCCIN_CPU1
                                  2        GND                     
C9R11            CAP_0805-10UF,16V,10%,X6S,C953A 1        VR_FET_SW_P12V_STBY_PVCCIN_CPU1
                                  2        GND                     
C9R12            CAP_A_0402V-0.1UF,16V,10%,X7R,A 1        P12V_PSU                
                                  2        GND                     
C9R13            CAP_A_0402V-0.1UF,16V,10%,X7R,A 1        P3V3_STBY               
                                  2        GND                     
C9R14            CAP_A_0402V-0.1UF,16V,10%,X7R,A 1        P3V3_STBY               
                                  2        GND                     
C9T1             CAP_A_0402V-0.01UF,25V,10%,X7RA 1        FAN_TACH1               
                                  2        GND                     
C9T3             CAPP_3018-68UF,16V,20%,TANT,72A 1        P12V_STBY               
                                  2        GND                     
C9T4             CAP_0805-10UF,16V,10%,X6S,C953A 1        VR_FET_SW_P12V_STBY_PVDDQ_GHJ
                                  2        GND                     
C9T5             CAPP_3018-470UF,2.5V,20%,ALUM,A 1        PVDDQ_GHJ               
                                  2        GND                     
C9T6             CAP_0805-10UF,16V,10%,X6S,C953A 1        VR_FET_SW_P12V_STBY_PVDDQ_GHJ
                                  2        GND                     
C9T7             CAP_A_0402V-0.01UF,25V,10%,X7RA 1        M_G_VREF                
                                  2        GND                     
C9T8             CAP_0805-10UF,16V,10%,X7R,G106A 1        P12V_NVDIMM_GHJ         
                                  2        GND                     
C9T9             CAP_0805-10UF,16V,10%,X6S,C953A 1        VR_FET_SW_P12V_STBY_PVDDQ_GHJ
                                  2        GND                     
C9U2             CAPP_3018-470UF,2.5V,20%,ALUM,A 1        PVDDQ_GHJ               
                                  2        GND                     
C9U3             CAP_0805-10UF,16V,10%,X6S,C953A 1        VR_FET_SW_P12V_STBY_PVDDQ_GHJ
                                  2        GND                     
C9U4             CAP_0805-10UF,16V,10%,X6S,C953A 1        VR_FET_SW_P12V_STBY_PVDDQ_GHJ
                                  2        GND                     
C9U5             CAPP_3018-470UF,2.5V,20%,ALUM,A 1        PVDDQ_GHJ               
                                  2        GND                     
C9U6             CAP_0805-10UF,16V,10%,X6S,C953A 1        VR_FET_SW_P12V_STBY_PVDDQ_GHJ
                                  2        GND                     
C9U7             CAP_A_0402V-0.01UF,25V,10%,X7RA 1        M_H_VREF                
                                  2        GND                     
C9U8             CAP_0805-10UF,16V,10%,X7R,G106A 1        P12V_NVDIMM_GHJ         
                                  2        GND                     
C9U9             CAPP_3018-470UF,2.5V,20%,ALUM,A 1        PVDDQ_GHJ               
                                  2        GND                     
C9U10            CAP_A_0402V-0.01UF,25V,10%,X7RA 1        M_J_VREF                
                                  2        GND                     
C9U11            CAP_0805-10UF,16V,10%,X7R,G106A 1        P12V_NVDIMM_GHJ         
                                  2        GND                     
C9U12            CAP_A_0402V-0.1UF,16V,10%,X7R,A 1        VR_PVDDQ_GHJ_AIINSEN    
                                  2        GND                     
CR1B1            DIODE_SM-SDMK0340L,EMPTY,H7179A 1        P5V_STBY                
                                  2        FAN_PWM_OUT_SYS1_R      
CR1B2            DIODE_SM-SDMK0340L,IC,H71799-0A 1        FAN_TACH2_CPU1_D1       
                                  2        FAN_TACH2_CPU1_D2       
CR1B3            DIODE_SM-SDMK0340L,IC,H71799-0A 1        FAN_TACH3_CPU1_D1       
                                  2        FAN_TACH3_CPU1_D2       
CR1E1            DIODE_SM-SDMK0340L,EMPTY,H7179A 1        P5V_STBY                
                                  2        FAN_PWM_OUT_SYS0_R      
CR1F1            DIODE_SM-SDMK0340L,IC,H71799-0A 1        FAN_TACH0_CPU0_D1       
                                  2        FAN_TACH0_CPU0_D2       
CR1F2            DIODE_SM-SDMK0340L,IC,H71799-0A 1        FAN_TACH1_CPU1_D1       
                                  2        FAN_TACH1_CPU1_D2       
CR1F3            DIODE_SM-SDMK0340L,IC,H71799-0A 1        FM_MATED_IN_D2_N        
                                  2        FM_MATED_IN_D1_N        
CR1F4            DIODE_SM-SDMK0340L,IC,H71799-0A 1        FM_MATED_IN_D1_N        
                                  2        FM_MATED_IN_N           
CR1F5            DIODE_SM-MBRS340T3G,EMPTY,C819A 1        P12V_STBY               
                                  2        GND                     
CR1L1            DIODE_SM-1N4148W,IC,D89194-001 1        FM_DB_UART_SEL1_N       
                                  2        FM_DB_UART_SEL0_N       
CR1L2            DIODE_SM-1N4148W,IC,D89194-001 1        FM_DB_UART_SEL2_N       
                                  2        FM_DB_UART_SEL1_N       
CR1L3            DIODE_SM-1N4148W,IC,D89194-001 1        FM_DB_UART_SEL3_N       
                                  2        FM_DB_UART_SEL2_N       
CR1L4            DIODE_SM-1N4148W,IC,D89194-001 1        FM_DB_UART_SEL4_N       
                                  2        FM_DB_UART_SEL3_N       
CR1M1            DIODEAC_DUAL_ARRAY_SM9-ESD3V3UA 1        USB3_P01_FB_TXN         
                                  2        USB3_P01_FB_TXP         
                                  3        GND                     
                                  4        USB3_P01_FB_RXN         
                                  5        USB3_P01_FB_RXP         
                                  6        USB3_P01_FB_RXP         
                                  7        USB3_P01_FB_RXN         
                                  8        USB3_P01_FB_TXP         
                                  9        USB3_P01_FB_TXN         
CR1M2            DIODEAC_DUAL_ARRAY_SM9-ESD3V3UA 1        USB2_P01_ESD_DP         
                                  2        USB2_P01_ESD_DN         
                                  3        GND                     
                                  4        TP_USB_ESD_AC2          
                                  5        TP_USB_ESD_AC3          
                                  6        TP_USB_ESD_OUT3         
                                  7        TP_USB_ESD_OUT2         
                                  8        USB2_P01_ESD_DN         
                                  9        USB2_P01_ESD_DP         
CR2U1            DIODE2A_DUAL_SMLF-BAS70-05,DIOA 1        P3V3_STBY               
                                  2        A_P3V_BAT_R             
                                  3        P3V3_RTC_STBY           
CR3U1            DIODE_SMLF-1N5819HW,IC,D55839-A 1        P3V3_STBY_PLD_D         
                                  2        P3V3_STBY               
CR7E1            DIODE_SMLF-BAT54WS,IC,C73510-0A 1        PWRGD_P3V3_STBY         
                                  2        PWRGD_DSW_PWROK         
CR8E1            DIODE_SMLF-BAT54WS,IC,C73510-0A 1        PWRGD_P12V_HSC          
                                  2        PWRGD_P12V_HSC_DLY      
CR9P1            DIODE_SMLF-BAT54WS,IC,C73510-0A 1        IRQ_UV_DETECT_N         
                                  2        FM_DISABLE_FAN_N        
CR9P2            DIODE_SMLF-BAT54WS,IC,C73510-0A 1        FM_UV_ADR_TRIGGER_N     
                                  2        FM_DISABLE_FAN_N        
CTI1             CAP_A_0402V-0.1UF,16V,10%,X7R,A 1        VR_PVCCIN_CPU0_AIREF1   
                                  2        GND                     
CTI2             CAP_0402LF-1000PF,50V,10%,X7R,A 1        A_TSENSE_PVCCIN_CPU0    
                                  2        GND                     
CTI3             SC2K2P50V3KX-GP_SMD-BCG6-SC2K2A 1        VR_PVCCIN_CPU0_PHASE1   
                                  2        UNNAMED_202_3D01R5F-GP_I75_2
CTI4             CAP_0402LF-1000PF,50V,10%,X7R,A 1        A_TSENSE_PVCCIN_CPU0    
                                  2        GND                     
CTI5             SC2K2P50V3KX-GP_SMD-BCG6-SC2K2A 1        VR_PVCCIN_CPU0_PHASE2   
                                  2        UNNAMED_202_3D01R5F-GP_I83_2
CTI6             CAP_A_0402V-0.1UF,16V,10%,X7R,A 1        VR_PVCCIN_CPU0_AIREF2   
                                  2        GND                     
CTI7             CAP_A_0402V-0.1UF,16V,10%,X7R,A 1        VR_PVDDQ_KLM_AIREF1     
                                  2        GND                     
CTI8             CAP_0402LF-1000PF,50V,10%,X7R,A 1        A_TSENSE_PVDDQ_KLM      
                                  2        GND                     
CTI9             SC2K2P50V3KX-GP_SMD-BCG6-SC2K2A 1        VR_PVDDQ_KLM_PH1_SW     
                                  2        UNNAMED_227_3D01R5F-GP_I125_1
CTI10            CAP_0402LF-1000PF,50V,10%,X7R,A 1        A_TSENSE_PVDDQ_KLM      
                                  2        GND                     
CTI11            SC2K2P50V3KX-GP_SMD-BCG6-SC2K2A 1        VR_PVDDQ_KLM_PH2_SW     
                                  2        UNNAMED_227_3D01R5F-GP_I124_1
CTI12            CAP_A_0402V-0.1UF,16V,10%,X7R,A 1        VR_PVDDQ_KLM_AIREF2     
                                  2        GND                     
CTI13            CAP_A_0402V-0.1UF,16V,10%,X7R,A 1        VR_PVCCIN_CPU1_AIREF5   
                                  2        GND                     
CTI14            SC2K2P50V3KX-GP_SMD-BCG6-SC2K2A 1        VR_PVCCIN_CPU1_PHASE5   
                                  2        UNNAMED_209_3D01R5F-GP_I66_2
CTI15            CAP_0402LF-1000PF,50V,10%,X7R,A 1        A_TSENSE_PVCCIN_CPU1    
                                  2        GND                     
CTI16            CAP_A_0402V-0.1UF,16V,10%,X7R,A 1        VR_PVCCIN_CPU1_AIREF3   
                                  2        GND                     
CTI17            CAP_0402LF-1000PF,50V,10%,X7R,A 1        A_TSENSE_PVCCIN_CPU1    
                                  2        GND                     
CTI18            SC2K2P50V3KX-GP_SMD-BCG6-SC2K2A 1        VR_PVCCIN_CPU1_PHASE3   
                                  2        UNNAMED_208_3D01R5F-GP_I86_2
CTI19            CAP_0402LF-1000PF,50V,10%,X7R,A 1        A_TSENSE_PVCCIN_CPU1    
                                  2        GND                     
CTI20            SC2K2P50V3KX-GP_SMD-BCG6-SC2K2A 1        VR_PVCCIN_CPU1_PHASE4   
                                  2        UNNAMED_208_3D01R5F-GP_I94_2
CTI21            CAP_A_0402V-0.1UF,16V,10%,X7R,A 1        VR_PVCCIN_CPU1_AIREF4   
                                  2        GND                     
CTI22            CAP_0402LF-1000PF,50V,10%,X7R,A 1        A_TSENSE_PVCCIN_CPU1    
                                  2        GND                     
CTI23            SC2K2P50V3KX-GP_SMD-BCG6-SC2K2A 1        VR_PVCCIN_CPU1_PHASE1   
                                  2        UNNAMED_207_3D01R5F-GP_I76_2
CTI24            CAP_A_0402V-0.1UF,16V,10%,X7R,A 1        VR_PVCCIN_CPU1_AIREF1   
                                  2        GND                     
CTI25            CAP_A_0402V-0.1UF,16V,10%,X7R,A 1        VR_PVCCIN_CPU1_AIREF2   
                                  2        GND                     
CTI26            CAP_0402LF-1000PF,50V,10%,X7R,A 1        A_TSENSE_PVCCIN_CPU1    
                                  2        GND                     
CTI27            SC2K2P50V3KX-GP_SMD-BCG6-SC2K2A 1        VR_PVCCIN_CPU1_PHASE2   
                                  2        UNNAMED_207_3D01R5F-GP_I85_2
CTI28            CAP_0402LF-1000PF,50V,10%,X7R,A 1        A_TSENSE_PVDDQ_GHJ      
                                  2        GND                     
CTI29            SC2K2P50V3KX-GP_SMD-BCG6-SC2K2A 1        VR_PVDDQ_GHJ_PH1_SW     
                                  2        UNNAMED_224_3D01R5F-GP_I119_2
CTI30            CAP_A_0402V-0.1UF,16V,10%,X7R,A 1        VR_PVDDQ_GHJ_AIREF1     
                                  2        GND                     
CTI31            CAP_A_0402V-0.1UF,16V,10%,X7R,A 1        VR_PVDDQ_GHJ_AIREF2     
                                  2        GND                     
CTI32            CAP_0402LF-1000PF,50V,10%,X7R,A 1        A_TSENSE_PVDDQ_GHJ      
                                  2        GND                     
CTI33            SC2K2P50V3KX-GP_SMD-BCG6-SC2K2A 1        VR_PVDDQ_GHJ_PH2_SW     
                                  2        UNNAMED_224_3D01R5F-GP_I129_2
CTI34            CAP_0402LF-1000PF,50V,10%,X7R,A 1        A_TSENSE_PVCCIN_CPU0    
                                  2        GND                     
CTI35            SC2K2P50V3KX-GP_SMD-BCG6-SC2K2A 1        VR_PVCCIN_CPU0_PHASE5   
                                  2        UNNAMED_204_3D01R5F-GP_I91_2
CTI36            CAP_A_0402V-0.1UF,16V,10%,X7R,A 1        VR_PVCCIN_CPU0_AIREF5   
                                  2        GND                     
CTI37            CAP_0402LF-1000PF,50V,10%,X7R,A 1        A_TSENSE_PVCCIN_CPU0    
                                  2        GND                     
CTI38            SC2K2P50V3KX-GP_SMD-BCG6-SC2K2A 1        VR_PVCCIN_CPU0_PHASE3   
                                  2        UNNAMED_203_3D01R5F-GP_I102_2
CTI39            CAP_A_0402V-0.1UF,16V,10%,X7R,A 1        VR_PVCCIN_CPU0_AIREF3   
                                  2        GND                     
CTI40            CAP_A_0402V-0.1UF,16V,10%,X7R,A 1        VR_PVCCIN_CPU0_AIREF4   
                                  2        GND                     
CTI41            SC2K2P50V3KX-GP_SMD-BCG6-SC2K2A 1        VR_PVCCIN_CPU0_PHASE4   
                                  2        UNNAMED_203_3D01R5F-GP_I105_2
CTI42            CAP_0402LF-1000PF,50V,10%,X7R,A 1        A_TSENSE_PVCCIN_CPU0    
                                  2        GND                     
CTI43            CAP_0402LF-1000PF,50V,10%,X7R,A 1        A_TSENSE_PVDDQ_DEF      
                                  2        GND                     
CTI44            SC2K2P50V3KX-GP_SMD-BCG6-SC2K2A 1        VR_PVDDQ_DEF_PH1_SW     
                                  2        UNNAMED_219_3D01R5F-GP_I126_2
CTI45            CAP_A_0402V-0.1UF,16V,10%,X7R,A 1        VR_PVDDQ_DEF_AIREF1     
                                  2        GND                     
CTI46            CAP_A_0402V-0.1UF,16V,10%,X7R,A 1        VR_PVDDQ_DEF_AIREF2     
                                  2        GND                     
CTI47            SC2K2P50V3KX-GP_SMD-BCG6-SC2K2A 1        VR_PVDDQ_DEF_PH2_SW     
                                  2        UNNAMED_219_3D01R5F-GP_I123_2
CTI48            CAP_0402LF-1000PF,50V,10%,X7R,A 1        A_TSENSE_PVDDQ_DEF      
                                  2        GND                     
CTI49            CAP_0402LF-1000PF,50V,10%,X7R,A 1        A_TSENSE_PVDDQ_ABC      
                                  2        GND                     
CTI50            SC2K2P50V3KX-GP_SMD-BCG6-SC2K2A 1        VR_PVDDQ_ABC_PH1_SW     
                                  2        UNNAMED_216_3D01R5F-GP_I114_2
CTI51            CAP_A_0402V-0.1UF,16V,10%,X7R,A 1        VR_PVDDQ_ABC_AIREF1     
                                  2        GND                     
CTI52            CAP_A_0402V-0.1UF,16V,10%,X7R,A 1        VR_PVDDQ_ABC_AIREF2     
                                  2        GND                     
CTI53            SC2K2P50V3KX-GP_SMD-BCG6-SC2K2A 1        VR_PVDDQ_ABC_PH2_SW     
                                  2        UNNAMED_216_3D01R5F-GP_I123_2
CTI54            CAP_0402LF-1000PF,50V,10%,X7R,A 1        A_TSENSE_PVDDQ_ABC      
                                  2        GND                     
CTI55            CAP_0402LF-1000PF,50V,10%,X7R,A 1        A_TSENSE_PVSA_CPU1      
                                  2        GND                     
CTI56            SC2K2P50V3KX-GP_SMD-BCG6-SC2K2A 1        VR_PVSA_CPU1_PHASE_SW   
                                  2        UNNAMED_210_3D01R5F-GP_I59_2
CTI57            CAP_A_0402V-0.1UF,16V,10%,X7R,A 1        VR_PVSA_CPU1_BIREF1     
                                  2        GND                     
CTI58            CAP_0402LF-1000PF,50V,10%,X7R,A 1        A_TSENSE_PVSA_CPU0      
                                  2        GND                     
CTI59            SC2K2P50V3KX-GP_SMD-BCG6-SC2K2A 1        VR_PVSA_CPU0_PHASE_SW   
                                  2        UNNAMED_205_3D01R5F-GP_I68_2
CTI60            CAP_A_0402V-0.1UF,16V,10%,X7R,A 1        VR_PVSA_CPU0_BIREF1     
                                  2        GND                     
CTI61            CAP_0402LF-1000PF,50V,10%,X7R,A 1        A_TSENSE_PVCCIO_CPU1    
                                  2        GND                     
CTI62            SC2K2P50V3KX-GP_SMD-BCG6-SC2K2A 1        VR_PVCCIO_CPU1_PH1_SW   
                                  2        UNNAMED_214_3D01R5F-GP_I132_2
CTI63            CAP_A_0402V-0.1UF,16V,10%,X7R,A 1        VR_PVCCIO_CPU1_AIREF1   
                                  2        GND                     
CTI64            CAP_0402LF-1000PF,50V,10%,X7R,A 1        A_TSENSE_PVNN_PCH_TMON  
                                  2        GND                     
CTI65            SC2K2P50V3KX-GP_SMD-BCG6-SC2K2A 1        VR_PVNN_PCH_PH1_PHASE_SW
                                  2        UNNAMED_236_3D01R5F-GP_I132_2
CTI66            CAP_A_0402V-0.1UF,16V,10%,X7R,A 1        VR_PVNN_PCH_AIREF1      
                                  2        GND                     
CTI67            CAP_A_0402V-0.1UF,16V,10%,X7R,A 1        VR_P1V05_PCH_BIREF1     
                                  2        GND                     
CTI68            SC2K2P50V3KX-GP_SMD-BCG6-SC2K2A 1        VR_P1V05_PCH_STBY_PH1_PHASE_SW
                                  2        UNNAMED_236_3D01R5F-GP_I137_2
CTI69            CAP_0402LF-1000PF,50V,10%,X7R,A 1        A_TSENSE_P1V05_PCH_STBY_TMON
                                  2        GND                     
CTI70            CAP_A_0402V-0.1UF,16V,10%,X7R,A 1        VR_PVCCIO_CPU0_AIREF1   
                                  2        GND                     
CTI71            CAP_0402LF-1000PF,50V,10%,X7R,A 1        A_TSENSE_PVCCIO_CPU0    
                                  2        GND                     
CTI72            SC2K2P50V3KX-GP_SMD-BCG6-SC2K2A 1        VR_PVCCIO_CPU0_PH1_SW   
                                  2        UNNAMED_212_3D01R5F-GP_I112_2
DS9A1            LED_1NC-BLUE,IC,C96565-012 1        FP_ID_LED_P5V_STBY_N    
                                  2        FP_ID_LED_XOR_R         
DS9A2            LED_1NCLF-GREEN,IC,C96565-011 1        FP_LED_HDD_ACTIVITY_AND_N
                                  2        FP_LED_HDD_ACTIVITY_AND_R_N
DS9A3            LED_1NCLF-YELLOW,IC,C96565-003 1        FM_SPEAKER_PCH_N        
                                  2        FM_BEEP_LED_P           
DS9A4            LED_A1LF-GREEN,IC,D14725-022 1        FM_UARTSW_LSB_R_N       
                                  2        FM_UARTSW_LSB_N         
DS9A5            LED_A1LF-GREEN,IC,C97278-010 1        FM_PWR_LED_A            
                                  2        FM_PWR_LED_K            
DS9A6            LED_A1LF-GREEN,IC,C97278-010 1        LED_P5V_STBY            
                                  2        GND                     
DS9A7            LED_A1LF-GREEN,IC,D14725-022 1        FM_UARTSW_MSB_R_N       
                                  2        FM_UARTSW_MSB_N         
DS9E1            LED_A1LF-GREEN,IC,C97278-010 1        FM_HEARTBEAT_LED_A      
                                  2        FM_HEARTBEAT_LED_K      
DS9F1            LED_A1-RED,IC,D14725-005 1        FM_RED_LED_ANODE        
                                  2        FM_RED_LED_CATHODE      
EU1A1            IR354XX_SM-IR35411,IC,H73688-0A 1        PVDDQ_KLM               
                                  2        GND                     
                                  3        VR_PVDDQ_KLM_PH2_VCIN   
                                  4        P5V_STBY                
                                  5        GND                     
                                  6        TP_PVDDQ_KLM_PH2_GL_0   
                                  7        GND                     
                                  10       VR_PVDDQ_KLM_PH2_SW     
                                  25       VR_FET_SW_P12V_STBY_PVDDQ_KLM
                                  30       VR_FET_SW_P12V_STBY_PVDDQ_KLM
                                  31       NC_PVDDQ_KLM_PH2_P31    
                                  32       VR_PVDDQ_KLM_PH2_PHASE  
                                  33       VR_PVDDQ_KLM_PH2_BOOT_R 
                                  34       VR_PVDDQ_KLM_PWM2       
                                  35       P5V_STBY                
                                  36       A_TSENSE_PVDDQ_KLM      
                                  37       VR_PVDDQ_KLM_PH2_OCSET  
                                  38       ISENSE_PVDDQ_KLM_PH2_IMON
                                  39       VR_PVDDQ_KLM_AIREF2     
                                  40       GND                     
                                  41       TP_PVDDQ_KLM_PH2_GL_1   
EU1A2            IR354XX_SM-IR35411,IC,H73688-0A 1        PVDDQ_KLM               
                                  2        GND                     
                                  3        VR_PVDDQ_KLM_PH1_VCIN   
                                  4        P5V_STBY                
                                  5        GND                     
                                  6        TP_PVDDQ_KLM_PH1_GL_0   
                                  7        GND                     
                                  10       VR_PVDDQ_KLM_PH1_SW     
                                  25       VR_FET_SW_P12V_STBY_PVDDQ_KLM
                                  30       VR_FET_SW_P12V_STBY_PVDDQ_KLM
                                  31       NC_PVDDQ_KLM_PH1_P31    
                                  32       VR_PVDDQ_KLM_PH1_PHASE  
                                  33       VR_PVDDQ_KLM_PH1_BOOT_R 
                                  34       VR_PVDDQ_KLM_PWM1       
                                  35       P5V_STBY                
                                  36       A_TSENSE_PVDDQ_KLM      
                                  37       VR_PVDDQ_KLM_PH1_OCSET  
                                  38       ISENSE_PVDDQ_KLM_PH1_IMON
                                  39       VR_PVDDQ_KLM_AIREF1     
                                  40       GND                     
                                  41       TP_PVDDQ_KLM_PH1_GL_1   
EU1B1            PXM1310B_QFN-IC,H89186-001 1        TP_PVDDQ_KLM_BPWM1      
                                  2        NC_PVDDQ_KLM_DNC0       
                                  3        NC_PVDDQ_KLM_PWM3       
                                  4        VR_PVDDQ_KLM_PWM2       
                                  5        VR_PVDDQ_KLM_PWM1       
                                  6        SMB_VR_SDA_VDDQ_KLM     
                                  7        SMB_VR_SCL_VDDQ_KLM     
                                  8        TP_PVDDQ_KLM_RESET_N    
                                  9        PWRGD_PVDDQ_KLM_R       
                                  10       VR_PVDDQ_KLM_VREN       
                                  11       IRQ_PVDDQ_KLM_VRHOT_LVT3_R_N
                                  12       NC_PVDDQ_KLM_PINALRT_N  
                                  13       PU_VR_PVDDQ_KLM_FAULT1  
                                  14       NC_PVDDQ_KLM_GP1        
                                  15       SVID_CLK_PVDDQ_KLM      
                                  16       SVID_VDIO_PVDDQ_KLM     
                                  17       SVID_ALERT_PVDDQ_KLM    
                                  18       NC_PVDDQ_KLM_GP0        
                                  19       VR_PVDDQ_KLM_AVSP       
                                  20       VSENSE_PVDDQ_KLM_N      
                                  21       VR_PVDDQ_KLM_AIREF1     
                                  22       ISENSE_PVDDQ_KLM_PH1_IMON
                                  23       VR_PVDDQ_KLM_AIREF2     
                                  24       ISENSE_PVDDQ_KLM_PH2_IMON
                                  25       TP_PVDDQ_KLM_PH3_IMON_REF
                                  26       TP_PVDDQ_KLM_PH3_IMON   
                                  27       GND                     
                                  28       NC_PVDDQ_KLM_DNC1       
                                  29       TP_PVDDQ_KLM_BVSEN      
                                  30       TP_PVDDQ_KLM_BVREF      
                                  31       TP_PVDDQ_KLM_BREF1      
                                  32       GND                     
                                  33       VR_PVDDQ_KLM_XADDR2     
                                  34       TP_PVDDQ_KLM_BTSEN      
                                  35       A_TSENSE_PVDDQ_KLM      
                                  36       VR_PVDDQ_KLM_XADDR1     
                                  37       VR_PVDDQ_KLM_VINSEN     
                                  38       VR_PVDDQ_KLM_AIINSEN    
                                  39       VR_PVDDQ_KLM_VDD        
                                  40       VR_PVDDQ_KLM_VD12       
                                  41       GND                     
EU1C1            IR354XX_SM-IR35412,IC,H73684-0A 1        PVSA_CPU1               
                                  2        GND                     
                                  3        VR_PVSA_CPU1_VCIN       
                                  4        P5V_STBY                
                                  5        GND                     
                                  6        TP_PVSA_CPU1_GL_0       
                                  7        GND                     
                                  10       VR_PVSA_CPU1_PHASE_SW   
                                  25       VR_FET_SW_P12V_STBY_PVCCIN_CPU1
                                  30       VR_FET_SW_P12V_STBY_PVCCIN_CPU1
                                  31       NC_PVSA_CPU1_P31        
                                  32       VR_PVSA_CPU1_PHASE      
                                  33       VR_PVSA_CPU1_BOOT_R     
                                  34       VR_PVSA_CPU1_PWM        
                                  35       P5V_STBY                
                                  36       A_TSENSE_PVSA_CPU1      
                                  37       VR_PVSA_CPU1_OCSET      
                                  38       ISENSE_PVSA_CPU1_IMON   
                                  39       VR_PVSA_CPU1_BIREF1     
                                  40       GND                     
                                  41       TP_PVSA_CPU1_GL_1       
EU1C2            PXE1610B_QFN-IC,H79206-001 1        VR_PVSA_CPU1_PWM        
                                  2        TP_PVCCIN_CPU1_APWM6    
                                  3        VR_PVCCIN_CPU1_PWM5     
                                  4        VR_PVCCIN_CPU1_PWM4     
                                  5        VR_PVCCIN_CPU1_PWM3     
                                  6        VR_PVCCIN_CPU1_PWM2     
                                  7        VR_PVCCIN_CPU1_PWM1     
                                  8        SMB_VR_SDA_R1           
                                  9        SMB_VR_SCL_R1           
                                  10       TP_PVCCIN_CPU1_RESET_N  
                                  11       VR_VRRDY_PVCCIN_CPU1    
                                  12       VR_PVCCIN_CPU1_VREN     
                                  13       IRQ_PVCCIN_CPU1_VRHOT_LVC3_R_N
                                  14       FM_PVCCIN_CPU1_PWR_IN_ALERT_N
                                  15       PWRGD_PVSA_CPU1_R       
                                  16       TP_PVCCIN_CPU1_GP1      
                                  17       SVID_VCLK_PVCCIN_CPU1   
                                  18       SVID_VDIO_PVCCIN_CPU1   
                                  19       SVID_VALERT_VCCIN_CPU1  
                                  20       PU_VR_PVCCIN_CPU1_FLT1_SMBALT_N
                                  21       VSENSE_PVCCIN_CPU1_AVSP 
                                  22       VSENSE_PVCCIN_CPU1_N    
                                  23       VR_PVCCIN_CPU1_AIREF1   
                                  24       ISENSE_PVCCIN_CPU1_PH1_IMON
                                  25       VR_PVCCIN_CPU1_AIREF2   
                                  26       ISENSE_PVCCIN_CPU1_PH2_IMON
                                  27       VR_PVCCIN_CPU1_AIREF3   
                                  28       ISENSE_PVCCIN_CPU1_PH3_IMON
                                  29       VR_PVCCIN_CPU1_AIREF4   
                                  30       ISENSE_PVCCIN_CPU1_PH4_IMON
                                  31       VR_PVCCIN_CPU1_AIREF5   
                                  32       ISENSE_PVCCIN_CPU1_PH5_IMON
                                  33       TP_PVCCIN_CPU1_AIREF6   
                                  34       TP_PVCCIN_CPU1_AISEN6   
                                  35       VSENSE_PVSA_CPU1_BVSP   
                                  36       VSENSE_PVSA_CPU1_N      
                                  37       VR_PVSA_CPU1_BIREF1     
                                  38       ISENSE_PVSA_CPU1_IMON   
                                  39       PU_VR_PVCCIN_CPU1_IMON  
                                  40       TP_PVCCIN_CPU1_FAULT1_20
                                  41       VR_PVCCIN_CPU1_XADDR2   
                                  42       A_TSENSE_PVSA_CPU1      
                                  43       A_TSENSE_PVCCIN_CPU1    
                                  44       VR_PVCCIN_CPU1_XADDR1   
                                  45       VR_PVCCIN_CPU1_AVINSEN  
                                  46       PVCCIN_PVSA_CPU1_IINSEN 
                                  47       VR_PVCCIN_CPU1_VDD      
                                  48       VR_PVCCIN_CPU1_VD12     
                                  49       GND                     
EU1C3            IR354XX_SM-IR35411,IC,H73688-0A 1        PVCCIN_CPU1             
                                  2        GND                     
                                  3        VR_PVCCIN_CPU1_PH5_VCIN 
                                  4        P5V_STBY                
                                  5        GND                     
                                  6        TP_PVCCIN_CPU1_PH5_GL_0 
                                  7        GND                     
                                  10       VR_PVCCIN_CPU1_PHASE5   
                                  25       VR_FET_SW_P12V_STBY_PVCCIN_CPU1
                                  30       VR_FET_SW_P12V_STBY_PVCCIN_CPU1
                                  31       NC_PVCCIN_CPU1_PH5_P31  
                                  32       VR_PVCCIN_CPU1_PH5_PHASE
                                  33       VR_PVCCIN_CPU1_PH5_BOOT_R
                                  34       VR_PVCCIN_CPU1_PWM5     
                                  35       P5V_STBY                
                                  36       A_TSENSE_PVCCIN_CPU1    
                                  37       VR_PVCCIN_CPU1_PH5_OCSET
                                  38       ISENSE_PVCCIN_CPU1_PH5_IMON
                                  39       VR_PVCCIN_CPU1_AIREF5   
                                  40       GND                     
                                  41       TP_PVCCIN_CPU1_PH5_GL_1 
EU1D1            IR354XX_SM-IR35411,IC,H73688-0A 1        PVCCIN_CPU1             
                                  2        GND                     
                                  3        VR_PVCCIN_CPU1_PH4_VCIN 
                                  4        P5V_STBY                
                                  5        GND                     
                                  6        TP_PVCCIN_CPU1_PH4_GL_0 
                                  7        GND                     
                                  10       VR_PVCCIN_CPU1_PHASE4   
                                  25       VR_FET_SW_P12V_STBY_PVCCIN_CPU1
                                  30       VR_FET_SW_P12V_STBY_PVCCIN_CPU1
                                  31       NC_PVCCIN_CPU1_PH4_P31  
                                  32       VR_PVCCIN_CPU1_PH4_PHASE
                                  33       VR_PVCCIN_CPU1_PH4_BOOT_R
                                  34       VR_PVCCIN_CPU1_PWM4     
                                  35       P5V_STBY                
                                  36       A_TSENSE_PVCCIN_CPU1    
                                  37       VR_PVCCIN_CPU1_PH4_OCSET
                                  38       ISENSE_PVCCIN_CPU1_PH4_IMON
                                  39       VR_PVCCIN_CPU1_AIREF4   
                                  40       GND                     
                                  41       TP_PVCCIN_CPU1_PH4_GL_1 
EU1D2            ADM1278_SM-IC,G99251-001 1        A_HSC_PSET              
                                  2        A_HSC_VCAP              
                                  3        A_HSC_ISET              
                                  4        A_HSC_ISTART            
                                  5        A_HSC_TIMER             
                                  6        IRQ_HSC_FAULT_R_N       
                                  7        FM_P12V_HSC_ADR1        
                                  8        FM_P12V_HSC_ADR2        
                                  9        TP_HSC_SPISSN           
                                  10       TP_HSC_MCLK             
                                  11       TP_HSC_MDAT             
                                  12       FM_P12V_HOTSWAP0_EN     
                                  13       IRQ_SML1_PMBUS_ALERT_R_N
                                  14       TP_HSC_ALERT2_N         
                                  15       SMB_3V3SB_HSC_SDA_R     
                                  16       SMB_3V3SB_HSC_SCL_R     
                                  17       PD_HSC_RETRY_N          
                                  18       PWRGD_P12V_R            
                                  19       A_HSC_CSOUT             
                                  20       A_HSC_VOUT              
                                  21       A_HSC_PWGIN             
                                  22       AGND_HSC                
                                  23       GND                     
                                  24       A_HSC_GATE              
                                  25       A_HSC_TEMP              
                                  26       A_HSC_MON               
                                  27       A_HSC_HSN               
                                  28       A_HSC_HSP               
                                  29       A_HSC_MOP               
                                  30       P12V_HSC_VCC            
                                  31       A_HSC_UV                
                                  32       A_HSC_OV                
                                  33       AGND_HSC                
EU1D3            IR354XX_SM-IR35411,IC,H73688-0A 1        PVCCIN_CPU1             
                                  2        GND                     
                                  3        VR_PVCCIN_CPU1_PH3_VCIN 
                                  4        P5V_STBY                
                                  5        GND                     
                                  6        TP_PVCCIN_CPU1_PH3_GL_0 
                                  7        GND                     
                                  10       VR_PVCCIN_CPU1_PHASE3   
                                  25       VR_FET_SW_P12V_STBY_PVCCIN_CPU1
                                  30       VR_FET_SW_P12V_STBY_PVCCIN_CPU1
                                  31       NC_PVCCIN_CPU1_PH3_P31  
                                  32       VR_PVCCIN_CPU1_PH3_PHASE
                                  33       VR_PVCCIN_CPU1_PH3_BOOT_R
                                  34       VR_PVCCIN_CPU1_PWM3     
                                  35       P5V_STBY                
                                  36       A_TSENSE_PVCCIN_CPU1    
                                  37       VR_PVCCIN_CPU1_PH3_OCSET
                                  38       ISENSE_PVCCIN_CPU1_PH3_IMON
                                  39       VR_PVCCIN_CPU1_AIREF3   
                                  40       GND                     
                                  41       TP_PVCCIN_CPU1_PH3_GL_1 
EU1D4            IR354XX_SM-IR35411,IC,H73688-0A 1        PVCCIN_CPU1             
                                  2        GND                     
                                  3        VR_PVCCIN_CPU1_PH2_VCIN 
                                  4        P5V_STBY                
                                  5        GND                     
                                  6        TP_PVCCINC_CPU1_PH2_GL_0
                                  7        GND                     
                                  10       VR_PVCCIN_CPU1_PHASE2   
                                  25       VR_FET_SW_P12V_STBY_PVCCIN_CPU1
                                  30       VR_FET_SW_P12V_STBY_PVCCIN_CPU1
                                  31       NC_PVCCIN_CPU1_PH2_P31  
                                  32       VR_PVCCIN_CPU1_PH2_PHASE
                                  33       VR_PVCCIN_CPU1_PH2_BOOT_R
                                  34       VR_PVCCIN_CPU1_PWM2     
                                  35       P5V_STBY                
                                  36       A_TSENSE_PVCCIN_CPU1    
                                  37       VR_PVCCIN_CPU1_PH2_OCSET
                                  38       ISENSE_PVCCIN_CPU1_PH2_IMON
                                  39       VR_PVCCIN_CPU1_AIREF2   
                                  40       GND                     
                                  41       TP_PVCCINC_CPU1_PH2_GL_1
EU1E1            MOSFETN_1D3S_SOT5-IC,G68777-001 1        P12V_STBY               
                                  2        P12V_STBY               
                                  3        P12V_STBY               
                                  4        A_HSC_GATE3_R           
                                  5        P12V_MB0_SW             
EU1E2            IR354XX_SM-IR35411,IC,H73688-0A 1        PVCCIN_CPU1             
                                  2        GND                     
                                  3        VR_PVCCIN_CPU1_PH1_VCIN 
                                  4        P5V_STBY                
                                  5        GND                     
                                  6        TP_PVCCINC_CPU1_PH1_GL_0
                                  7        GND                     
                                  10       VR_PVCCIN_CPU1_PHASE1   
                                  25       VR_FET_SW_P12V_STBY_PVCCIN_CPU1
                                  30       VR_FET_SW_P12V_STBY_PVCCIN_CPU1
                                  31       NC_PVCCIN_CPU1_PH1_P31  
                                  32       VR_PVCCIN_CPU1_PH1_PHASE
                                  33       VR_PVCCIN_CPU1_PH1_BOOT_R
                                  34       VR_PVCCIN_CPU1_PWM1     
                                  35       P5V_STBY                
                                  36       A_TSENSE_PVCCIN_CPU1    
                                  37       VR_PVCCIN_CPU1_PH1_OCSET
                                  38       ISENSE_PVCCIN_CPU1_PH1_IMON
                                  39       VR_PVCCIN_CPU1_AIREF1   
                                  40       GND                     
                                  41       TP_PVCCINC_CPU1_PH1_GL_1
EU1E3            MOSFETN_1D3S_SOT5-IC,G68777-001 1        P12V_STBY               
                                  2        P12V_STBY               
                                  3        P12V_STBY               
                                  4        A_HSC_GATE1_R           
                                  5        P12V_MB0_SW             
EU1F1            IR354XX_SM-IR35411,IC,H73688-0A 1        PVDDQ_GHJ               
                                  2        GND                     
                                  3        VR_PVDDQ_GHJ_PH2_VCIN   
                                  4        P5V_STBY                
                                  5        GND                     
                                  6        TP_PVDDQ_GHJ_PH2_GL_0   
                                  7        GND                     
                                  10       VR_PVDDQ_GHJ_PH2_SW     
                                  25       VR_FET_SW_P12V_STBY_PVDDQ_GHJ
                                  30       VR_FET_SW_P12V_STBY_PVDDQ_GHJ
                                  31       NC_PVDDQ_GHJ_PH2_P31    
                                  32       VR_PVDDQ_GHJ_PH2_PHASE  
                                  33       VR_PVDDQ_GHJ_PH2_BOOT_R 
                                  34       VR_PVDDQ_GHJ_PWM2       
                                  35       P5V_STBY                
                                  36       A_TSENSE_PVDDQ_GHJ      
                                  37       VR_PVDDQ_GHJ_PH2_OCSET  
                                  38       ISENSE_PVDDQ_GHJ_PH2_IMON
                                  39       VR_PVDDQ_GHJ_AIREF2     
                                  40       GND                     
                                  41       TP_PVDDQ_GHJ_PH2_GL_1   
EU1G1            IR354XX_SM-IR35411,IC,H73688-0A 1        PVDDQ_GHJ               
                                  2        GND                     
                                  3        VR_PVDDQ_GHJ_PH1_VCIN   
                                  4        P5V_STBY                
                                  5        GND                     
                                  6        TP_PVDDQ_GHJ_PH1_GL_0   
                                  7        GND                     
                                  10       VR_PVDDQ_GHJ_PH1_SW     
                                  25       VR_FET_SW_P12V_STBY_PVDDQ_GHJ
                                  30       VR_FET_SW_P12V_STBY_PVDDQ_GHJ
                                  31       NC_PVDDQ_GHJ_PH1_P31    
                                  32       VR_PVDDQ_GHJ_PH1_PHASE  
                                  33       VR_PVDDQ_GHJ_PH1_BOOT_R 
                                  34       VR_PVDDQ_GHJ_PWM1       
                                  35       P5V_STBY                
                                  36       A_TSENSE_PVDDQ_GHJ      
                                  37       VR_PVDDQ_GHJ_PH1_OCSET  
                                  38       ISENSE_PVDDQ_GHJ_PH1_IMON
                                  39       VR_PVDDQ_GHJ_AIREF1     
                                  40       GND                     
                                  41       TP_PVDDQ_GHJ_PH1_GL_1   
EU1G2            PXM1310B_QFN-IC,H89186-001 1        TP_PVDDQ_GHJ_BPWM1      
                                  2        NC_PVDDQ_GHJ_DNC0       
                                  3        TP_PVDDQ_GHJ_PWM3       
                                  4        VR_PVDDQ_GHJ_PWM2       
                                  5        VR_PVDDQ_GHJ_PWM1       
                                  6        SMB_VR_SDA_VDDQ_GHJ     
                                  7        SMB_VR_SCL_VDDQ_GHJ     
                                  8        TP_PVDDQ_GHJ_RESET_N    
                                  9        PWRGD_PVDDQ_GHJ_R       
                                  10       VR_PVDDQ_GHJ_VREN       
                                  11       IRQ_PVDDQ_GHJ_VRHOT_LVT3_R_N
                                  12       NC_PVDDQ_GHJ_PINALRT_N  
                                  13       PU_VR_PVDDQ_GHJ_FAULT1  
                                  14       TP_PVDDQ_GHJ_MP1        
                                  15       SVID_CLK_PVDDQ_GHJ      
                                  16       SVID_VDIO_PVDDQ_GHJ     
                                  17       SVID_ALERT_PVDDQ_GHJ    
                                  18       TP_PVDDQ_GHJ_MP2        
                                  19       VR_PVDDQ_GHJ_AVSP       
                                  20       VSENSE_PVDDQ_GHJ_N      
                                  21       VR_PVDDQ_GHJ_AIREF1     
                                  22       ISENSE_PVDDQ_GHJ_PH1_IMON
                                  23       VR_PVDDQ_GHJ_AIREF2     
                                  24       ISENSE_PVDDQ_GHJ_PH2_IMON
                                  25       TP_PVDDQ_GHJ_PH3_IMON_REF
                                  26       TP_PVDDQ_GHJ_PH3_IMON   
                                  27       GND                     
                                  28       NC_PVDDQ_GHJ_DNC1       
                                  29       TP_PVDDQ_GHJ_BVSEN      
                                  30       TP_PVDDQ_GHJ_BVREF      
                                  31       TP_PVDDQ_GHJ_BREF1      
                                  32       GND                     
                                  33       VR_PVDDQ_GHJ_XADDR2     
                                  34       TP_PVDDQ_GHJ_BTSEN      
                                  35       A_TSENSE_PVDDQ_GHJ      
                                  36       VR_PVDDQ_GHJ_XADDR1     
                                  37       VR_PVDDQ_GHJ_VINSEN     
                                  38       VR_PVDDQ_GHJ_AIINSEN    
                                  39       VR_PVDDQ_GHJ_VDD        
                                  40       VR_PVDDQ_GHJ_VD12       
                                  41       GND                     
EU2T1            SLG55021_SM-IC,G56246-001 1        P5V_STBY                
                                  2        FM_P3V3_CPLD_EN         
                                  3        P5V_STBY                
                                  4        GND                     
                                  5        P3V3_STBY               
                                  6        P3V3                    
                                  7        P3V3_SWITCH_G           
                                  8        TP_SLG55021_P3V3_8      
                                  9        GND                     
EU3P1            PXE1110B_QFN-IC,H89187-001 1        NC_PVCCIO_CPU0_DNC0     
                                  2        NC_PVCCIO_CPU0_DNC1     
                                  3        TP_PVCCIO_CPU0_BPWM1    
                                  4        NC_PVCCIO_CPU0_DNC2     
                                  5        VR_PVCCIO_CPU0_PWM1     
                                  6        SMB_VR_SDA_PVCCIO_CPU0  
                                  7        SMB_VR_SCL_PVCCIO_CPU0  
                                  8        TP_PVCCIO_CPU0_RESET_N  
                                  9        PWRGD_PVCCIO_CPU0_R     
                                  10       VR_PVCCIO_CPU0_EN       
                                  11       IRQ_PVCCIO_CPU0_VRHOT_N 
                                  12       TP_PVCCIO_CPU0_PINALRT_N
                                  13       TP_VR_PVCCIO_CPU0_MP0   
                                  14       TP_VR_PVCCIO_CPU0_MP1   
                                  15       SVID_CLK_PVCCIO_CPU0    
                                  16       SVID_VDIO_PVCCIO_CPU0   
                                  17       SVID_ALERT_PVCCIO_CPU0  
                                  18       TP_VR_PVCCIO_CPU0_MP2   
                                  19       VR_PVCCIO_CPU0_AVSP     
                                  20       VSENSE_PVCCIO_CPU0_AVSN 
                                  21       VR_PVCCIO_CPU0_AIREF1   
                                  22       ISENSE_PVCCIO_CPU0_PH1_IMON
                                  23       GND                     
                                  24       NC_PVCCIO_CPU0_DNC3     
                                  25       TP_PVCCIO_CPU0_BIREF1   
                                  26       GND                     
                                  27       GND                     
                                  28       NC_PVCCIO_CPU0_DNC4     
                                  29       TP_PVCCIO_CPU0_BVSEN    
                                  30       TP_PVCCIO_CPU0_BVREF    
                                  31       TP_VR_PVCCIO_CPU0_MP3   
                                  32       PU_VR_PVCCIO_CPU0_FAULT1
                                  33       VR_PVCCIO_CPU0_XADDR2   
                                  34       TP_PVCCIO_CPU0_BTSEN    
                                  35       A_TSENSE_PVCCIO_CPU0    
                                  36       VR_PVCCIO_CPU0_XADDR1   
                                  37       VR_PVCCIO_CPU0_VINSEN   
                                  38       TP_VR_PVCCIO_CPU0_AIINSEN
                                  39       VR_PVCCIO_CPU0_VDD      
                                  40       VR_PVCCIO_CPU0_VD12     
                                  41       GND                     
EU4A1            MIC5166_DFN-IC,H55101-001 1        VR_PVTT_DEF_VREF        
                                  2        VR_PVTT_DEF_BIAS        
                                  3        GND                     
                                  4        VSENSE_PVDDQ_DEF_VTT    
                                  5        PWRGD_PVTT_DEF_CPU0_R   
                                  6        VR_PVTT_DEF_SNS         
                                  7        FM_PVTT_DEF_EN_R        
                                  8        GND                     
                                  9        PVTT_DEF                
                                  10       PVDDQ_DEF               
                                  11       GND                     
EU4A2            MIC5166_DFN-IC,H55101-001 1        VR_PVTT_KLM_VREF        
                                  2        VR_PVTT_KLM_BIAS        
                                  3        GND                     
                                  4        VSENSE_PVDDQ_KLM_VTT    
                                  5        PWRGD_PVTT_KLM_CPU1_R   
                                  6        VR_PVTT_KLM_SNS         
                                  7        FM_PVTT_KLM_EN_R        
                                  8        GND                     
                                  9        PVTT_KLM                
                                  10       PVDDQ_KLM               
                                  11       GND                     
EU4A3            NCP3232L_SM-IC,H86355-001 1        VR_PVPP_KLM_SS          
                                  2        VR_FB_PVPP_KLM          
                                  3        VR_COMP_PVPP_KLM_3      
                                  4        VR_PVPP_KLM_ISET        
                                  5        AGND_PVPP_KLM           
                                  6        AGND_PVPP_KLM           
                                  7        PWRGD_PVPP_KLM_R        
                                  8        VR_FET_SW_P12V_STBY_PVPP_KLM
                                  9        VR_FET_SW_P12V_STBY_PVPP_KLM
                                  10       VR_FET_SW_P12V_STBY_PVPP_KLM
                                  11       VR_FET_SW_P12V_STBY_PVPP_KLM
                                  12       VR_FET_SW_P12V_STBY_PVPP_KLM
                                  13       VR_FET_SW_P12V_STBY_PVPP_KLM
                                  14       VR_FET_SW_P12V_STBY_PVPP_KLM
                                  15       VR_PVPP_KLM_PHASE       
                                  16       GND                     
                                  17       GND                     
                                  18       GND                     
                                  19       GND                     
                                  20       GND                     
                                  21       GND                     
                                  22       GND                     
                                  23       GND                     
                                  24       GND                     
                                  25       GND                     
                                  26       GND                     
                                  27       GND                     
                                  28       GND                     
                                  29       VR_PVPP_KLM_PHASE       
                                  30       VR_PVPP_KLM_PHASE       
                                  31       VR_PVPP_KLM_PHASE       
                                  32       VR_PVPP_KLM_PHASE       
                                  33       VR_PVPP_KLM_PHASE       
                                  34       VR_PVPP_KLM_PHASE       
                                  35       VR_PVPP_KLM_PHASE       
                                  36       VR_PVPP_KLM_BOOT        
                                  37       GND                     
                                  38       VR_VB_PVPP_KLM          
                                  39       VR_FET_SW_P12V_STBY_PVPP_KLM
                                  40       FM_PVPP_PVDDQ_CPU1_EN_KLM
                                  41       GND                     
                                  42       VR_FET_SW_P12V_STBY_PVPP_KLM
                                  43       VR_PVPP_KLM_PHASE       
EU4C1            IR354XX_SM-IR35412,IC,H73684-0A 1        PVSA_CPU0               
                                  2        GND                     
                                  3        VR_PVSA_CPU0_VCIN       
                                  4        P5V_STBY                
                                  5        GND                     
                                  6        TP_PVSA_CPU0_GL_0       
                                  7        GND                     
                                  10       VR_PVSA_CPU0_PHASE_SW   
                                  25       VR_FET_SW_P12V_STBY_PVCCIN_CPU0
                                  30       VR_FET_SW_P12V_STBY_PVCCIN_CPU0
                                  31       NC_PVSA_CPU0_P31        
                                  32       VR_PVSA_CPU0_PHASE      
                                  33       VR_PVSA_CPU0_BOOT_R     
                                  34       VR_PVSA_CPU0_PWM        
                                  35       P5V_STBY                
                                  36       A_TSENSE_PVSA_CPU0      
                                  37       VR_PVSA_CPU0_OCSET      
                                  38       ISENSE_PVSA_CPU0_IMON   
                                  39       VR_PVSA_CPU0_BIREF1     
                                  40       GND                     
                                  41       TP_PVSA_CPU0_GL_1       
EU4C2            IR354XX_SM-IR35411,IC,H73688-0A 1        PVCCIN_CPU0             
                                  2        GND                     
                                  3        VR_PVCCIN_CPU0_PH5_VCIN 
                                  4        P5V_STBY                
                                  5        GND                     
                                  6        TP_PVCCIN_CPU0_PH5_GL_0 
                                  7        GND                     
                                  10       VR_PVCCIN_CPU0_PHASE5   
                                  25       VR_FET_SW_P12V_STBY_PVCCIN_CPU0
                                  30       VR_FET_SW_P12V_STBY_PVCCIN_CPU0
                                  31       NC_PVCCIN_CPU0_PH5_P31  
                                  32       VR_PVCCIN_CPU0_PH5_PHASE
                                  33       VR_PVCCIN_CPU0_PH5_BOOT_R
                                  34       VR_PVCCIN_CPU0_PWM5     
                                  35       P5V_STBY                
                                  36       A_TSENSE_PVCCIN_CPU0    
                                  37       VR_PVCCIN_CPU0_PH5_OCSET
                                  38       ISENSE_PVCCIN_CPU0_PH5_IMON
                                  39       VR_PVCCIN_CPU0_AIREF5   
                                  40       GND                     
                                  41       TP_PVCCIN_CPU0_PH5_GL_1 
EU4D1            IR354XX_SM-IR35411,IC,H73688-0A 1        PVCCIN_CPU0             
                                  2        GND                     
                                  3        VR_PVCCIN_CPU0_PH4_VCIN 
                                  4        P5V_STBY                
                                  5        GND                     
                                  6        TP_PVCCIN_CPU0_PH4_GL_0 
                                  7        GND                     
                                  10       VR_PVCCIN_CPU0_PHASE4   
                                  25       VR_FET_SW_P12V_STBY_PVCCIN_CPU0
                                  30       VR_FET_SW_P12V_STBY_PVCCIN_CPU0
                                  31       NC_PVCCIN_CPU0_PH4_P31  
                                  32       VR_PVCCIN_CPU0_PH4_PHASE
                                  33       VR_PVCCIN_CPU0_PH4_BOOT_R
                                  34       VR_PVCCIN_CPU0_PWM4     
                                  35       P5V_STBY                
                                  36       A_TSENSE_PVCCIN_CPU0    
                                  37       VR_PVCCIN_CPU0_PH4_OCSET
                                  38       ISENSE_PVCCIN_CPU0_PH4_IMON
                                  39       VR_PVCCIN_CPU0_AIREF4   
                                  40       GND                     
                                  41       TP_PVCCIN_CPU0_PH4_GL_1 
EU4D2            NB3W1200L_LCC-IC,H13585-001 1        P3V3_DB1200_A           
                                  2        GND                     
                                  3        NC_DB1200ZL<0>          
                                  4        FM_100M_N               
                                  5        FM_HBW_BYPASS_LOWBW_N   
                                  6        FM_DB1200_PWRGD         
                                  7        GND                     
                                  8        P3V3_DB1200_R           
                                  9        CLK_100M_DB1200_DP      
                                  10       CLK_100M_DB1200_DN      
                                  11       FM_DB1200_SMB_SA0       
                                  12       SMB_HOST_STBY_LVC3_SDA_R2
                                  13       SMB_HOST_STBY_LVC3_SCL_R2
                                  14       FM_DB1200_SMB_SA1       
                                  15       NC_DB1200ZL<2>          
                                  16       NC_DB1200ZL<1>          
                                  17       CLK_100M_CPU0_BCLK0_R_DP
                                  18       CLK_100M_CPU0_BCLK0_R_DN
                                  19       FM_DB1200ZL_BCLKS_EN_N  
                                  20       FM_DB1200ZL_BCLKS_EN_N  
                                  21       CLK_100M_CPU0_BCLK1_R_DP
                                  22       CLK_100M_CPU0_BCLK1_R_DN
                                  23       GND                     
                                  24       P3V3_DB1200             
                                  25       P3V3_DB1200             
                                  26       CLK_100M_CPU0_BCLK2_R_DP
                                  27       CLK_100M_CPU0_BCLK2_R_DN
                                  28       FM_DB1200ZL_BCLKS_EN_N  
                                  29       FM_CPU0_MCP_CLK_EN_N    
                                  30       CLK_100M_CPU0_PE_REFCLK_R_DP
                                  31       CLK_100M_CPU0_PE_REFCLK_R_DN
                                  32       P3V3_DB1200             
                                  33       GND                     
                                  34       CLK_100M_CPU0_RC_REFCLK0_R_DP
                                  35       CLK_100M_CPU0_RC_REFCLK0_R_DN
                                  36       FM_CPU0_MCP_CLK_EN_N    
                                  37       FM_CPU0_MCP_CLK_EN_N    
                                  38       CLK_100M_CPU0_RC_REFCLK1_R_DP
                                  39       CLK_100M_CPU0_RC_REFCLK1_R_DN
                                  40       P3V3_DB1200             
                                  41       GND                     
                                  42       CLK_100M_CPU1_BCLK0_R_DP
                                  43       CLK_100M_CPU1_BCLK0_R_DN
                                  44       FM_DB1200ZL_BCLKS_EN_N  
                                  45       FM_DB1200ZL_BCLKS_EN_N  
                                  46       CLK_100M_CPU1_BCLK1_R_DP
                                  47       CLK_100M_CPU1_BCLK1_R_DN
                                  48       GND                     
                                  49       P3V3_DB1200             
                                  50       CLK_100M_CPU1_BCLK2_R_DP
                                  51       CLK_100M_CPU1_BCLK2_R_DN
                                  52       FM_DB1200ZL_BCLKS_EN_N  
                                  53       FM_CPU1_MCP_CLK_EN_N    
                                  54       CLK_100M_CPU1_PE_REFCLK_R_DP
                                  55       CLK_100M_CPU1_PE_REFCLK_R_DN
                                  56       P3V3_DB1200             
                                  57       P3V3_DB1200             
                                  58       GND                     
                                  59       CLK_100M_CPU1_RC_REFCLK0_R_DP
                                  60       CLK_100M_CPU1_RC_REFCLK0_R_DN
                                  61       FM_CPU1_MCP_CLK_EN_N    
                                  62       FM_CPU1_MCP_CLK_EN_N    
                                  63       CLK_100M_CPU1_RC_REFCLK1_R_DP
                                  64       CLK_100M_CPU1_RC_REFCLK1_R_DN
                                  65       GND                     
EU4D3            IR354XX_SM-IR35411,IC,H73688-0A 1        PVCCIN_CPU0             
                                  2        GND                     
                                  3        VR_PVCCIN_CPU0_PH3_VCIN 
                                  4        P5V_STBY                
                                  5        GND                     
                                  6        TP_PVCCIN_CPU0_PH3_GL_0 
                                  7        GND                     
                                  10       VR_PVCCIN_CPU0_PHASE3   
                                  25       VR_FET_SW_P12V_STBY_PVCCIN_CPU0
                                  30       VR_FET_SW_P12V_STBY_PVCCIN_CPU0
                                  31       NC_PVCCIN_CPU0_PH3_P31  
                                  32       VR_PVCCIN_CPU0_PH3_PHASE
                                  33       VR_PVCCIN_CPU0_PH3_BOOT_R
                                  34       VR_PVCCIN_CPU0_PWM3     
                                  35       P5V_STBY                
                                  36       A_TSENSE_PVCCIN_CPU0    
                                  37       VR_PVCCIN_CPU0_PH3_OCSET
                                  38       ISENSE_PVCCIN_CPU0_PH3_IMON
                                  39       VR_PVCCIN_CPU0_AIREF3   
                                  40       GND                     
                                  41       TP_PVCCIN_CPU0_PH3_GL_1 
EU4D4            PXE1610B_QFN-IC,H79206-001 1        VR_PVSA_CPU0_PWM        
                                  2        TP_PVCCIN_CPU0_APWM6    
                                  3        VR_PVCCIN_CPU0_PWM5     
                                  4        VR_PVCCIN_CPU0_PWM4     
                                  5        VR_PVCCIN_CPU0_PWM3     
                                  6        VR_PVCCIN_CPU0_PWM2     
                                  7        VR_PVCCIN_CPU0_PWM1     
                                  8        SMB_VR_SDA_R            
                                  9        SMB_VR_SCL_R            
                                  10       TP_PVCCIN_CPU0_RESET    
                                  11       VR_VRRDY_PVCCIN_CPU0    
                                  12       VR_PVCCIN_CPU0_VREN     
                                  13       IRQ_PVCCIN_CPU0_VRHOT_LVC3_R_N
                                  14       FM_PVCCIN_CPU0_PWR_IN_ALERT_N
                                  15       PWRGD_PVSA_CPU0_R       
                                  16       TP_PVCCIN_CPU0_GP1      
                                  17       SVID_VCLK_PVCCIN_CPU0   
                                  18       SVID_VDIO_PVCCIN_CPU0   
                                  19       SVID_VALERT_VCCIN_CPU0  
                                  20       PU_VR_PVCCIN_CPU0_FLT1_SMBALT_N
                                  21       VSENSE_PVCCIN_CPU0_AVSP 
                                  22       VSENSE_PVCCIN_CPU0_N    
                                  23       VR_PVCCIN_CPU0_AIREF1   
                                  24       ISENSE_PVCCIN_CPU0_PH1_IMON
                                  25       VR_PVCCIN_CPU0_AIREF2   
                                  26       ISENSE_PVCCIN_CPU0_PH2_IMON
                                  27       VR_PVCCIN_CPU0_AIREF3   
                                  28       ISENSE_PVCCIN_CPU0_PH3_IMON
                                  29       VR_PVCCIN_CPU0_AIREF4   
                                  30       ISENSE_PVCCIN_CPU0_PH4_IMON
                                  31       VR_PVCCIN_CPU0_AIREF5   
                                  32       ISENSE_PVCCIN_CPU0_PH5_IMON
                                  33       TP_PVCCIN_CPU0_AIREF6   
                                  34       TP_PVCCIN_CPU0_AISEN6   
                                  35       VSENSE_PVSA_CPU0_BVSP   
                                  36       VSENSE_PVSA_CPU0_N      
                                  37       VR_PVSA_CPU0_BIREF1     
                                  38       ISENSE_PVSA_CPU0_IMON   
                                  39       PU_VR_PVCCIN_CPU0_IMON  
                                  40       TP_PVCCIN_CPU0_FAULT1_20
                                  41       VR_PVCCIN_CPU0_XADDR2   
                                  42       A_TSENSE_PVSA_CPU0      
                                  43       A_TSENSE_PVCCIN_CPU0    
                                  44       VR_PVCCIN_CPU0_XADDR1   
                                  45       VR_PVCCIN_CPU0_AVINSEN  
                                  46       PVCCIN_PVSA_CPU0_IINSEN 
                                  47       VR_PVCCIN_CPU0_VDD      
                                  48       VR_PVCCIN_CPU0_VD12     
                                  49       GND                     
EU4D5            PXE1110B_QFN-IC,H89187-001 1        NC_PVCCIO_CPU1_DNC0     
                                  2        NC_PVCCIO_CPU1_DNC1     
                                  3        TP_PVCCIO_CPU1_BPWM1    
                                  4        NC_PVCCIO_CPU1_DNC2     
                                  5        VR_PVCCIO_CPU1_PWM1     
                                  6        SMB_VR_SDA_PVCCIO_CPU1  
                                  7        SMB_VR_SCL_PVCCIO_CPU1  
                                  8        TP_PVCCIO_CPU1_RESET_N  
                                  9        PWRGD_PVCCIO_CPU1_R     
                                  10       VR_PVCCIO_CPU1_EN       
                                  11       IRQ_PVCCIO_CPU1_VRHOT_N 
                                  12       TP_PVCCIO_CPU1_PINALRT_N
                                  13       TP_VR_PVCCIO_CPU1_MP0   
                                  14       TP_VR_PVCCIO_CPU1_MP1   
                                  15       SVID_CLK_PVCCIO_CPU1    
                                  16       SVID_VDIO_PVCCIO_CPU1   
                                  17       SVID_ALERT_PVCCIO_CPU1  
                                  18       TP_VR_PVCCIO_CPU1_MP2   
                                  19       VR_PVCCIO_CPU1_AVSP     
                                  20       VSENSE_PVCCIO_CPU1_AVSN 
                                  21       VR_PVCCIO_CPU1_AIREF1   
                                  22       ISENSE_PVCCIO_CPU1_PH1_IMON
                                  23       GND                     
                                  24       NC_PVCCIO_CPU1_DNC3     
                                  25       TP_PVCCIO_CPU1_BIREF1   
                                  26       GND                     
                                  27       GND                     
                                  28       NC_PVCCIO_CPU1_DNC4     
                                  29       TP_PVCCIO_CPU1_BVSEN    
                                  30       TP_PVCCIO_CPU1_BVREF    
                                  31       TP_VR_PVCCIO_CPU1_MP3   
                                  32       PU_VR_PVCCIO_CPU1_FAULT1
                                  33       VR_PVCCIO_CPU1_XADDR2   
                                  34       TP_PVCCIO_CPU1_BTSEN    
                                  35       A_TSENSE_PVCCIO_CPU1    
                                  36       VR_PVCCIO_CPU1_XADDR1   
                                  37       VR_PVCCIO_CPU1_VINSEN   
                                  38       TP_VR_PVCCIO_CPU1_AIINSEN
                                  39       VR_PVCCIO_CPU1_VDD      
                                  40       VR_PVCCIO_CPU1_VD12     
                                  41       GND                     
EU4D6            IR354XX_SM-IR35411,IC,H73688-0A 1        PVCCIN_CPU0             
                                  2        GND                     
                                  3        VR_PVCCIN_CPU0_PH2_VCIN 
                                  4        P5V_STBY                
                                  5        GND                     
                                  6        TP_PVCCIN_CPU0_PH2_GL_0 
                                  7        GND                     
                                  10       VR_PVCCIN_CPU0_PHASE2   
                                  25       VR_FET_SW_P12V_STBY_PVCCIN_CPU0
                                  30       VR_FET_SW_P12V_STBY_PVCCIN_CPU0
                                  31       NC_PVCCIN_CPU0_PH2_P31  
                                  32       VR_PVCCIN_CPU0_PH2_PHASE
                                  33       VR_PVCCIN_CPU0_PH2_BOOT_R
                                  34       VR_PVCCIN_CPU0_PWM2     
                                  35       P5V_STBY                
                                  36       A_TSENSE_PVCCIN_CPU0    
                                  37       VR_PVCCIN_CPU0_PH2_OCSET
                                  38       ISENSE_PVCCIN_CPU0_PH2_IMON
                                  39       VR_PVCCIN_CPU0_AIREF2   
                                  40       GND                     
                                  41       TP_PVCCIN_CPU0_PH2_GL_1 
EU4E1            IR354XX_SM-IR35411,IC,H73688-0A 1        PVCCIN_CPU0             
                                  2        GND                     
                                  3        VR_PVCCIN_CPU0_PH1_VCIN 
                                  4        P5V_STBY                
                                  5        GND                     
                                  6        TP_PVCCIN_CPU0_PH1_GL_0 
                                  7        GND                     
                                  10       VR_PVCCIN_CPU0_PHASE1   
                                  25       VR_FET_SW_P12V_STBY_PVCCIN_CPU0
                                  30       VR_FET_SW_P12V_STBY_PVCCIN_CPU0
                                  31       NC_PVCCIN_CPU0_PH1_P31  
                                  32       VR_PVCCIN_CPU0_PH1_PHASE
                                  33       VR_PVCCIN_CPU0_PH1_BOOT_R
                                  34       VR_PVCCIN_CPU0_PWM1     
                                  35       P5V_STBY                
                                  36       A_TSENSE_PVCCIN_CPU0    
                                  37       VR_PVCCIN_CPU0_PH1_OCSET
                                  38       ISENSE_PVCCIN_CPU0_PH1_IMON
                                  39       VR_PVCCIN_CPU0_AIREF1   
                                  40       GND                     
                                  41       TP_PVCCIN_CPU0_PH1_GL_1 
EU4E2            IR354XX_SM-IR35412,IC,H73684-0A 1        PVCCIO_CPU1             
                                  2        GND                     
                                  3        VR_PVCCIO_CPU1_PH1_VCIN 
                                  4        P5V_STBY                
                                  5        GND                     
                                  6        TP_PVCCIO_CPU1_GL_0     
                                  7        GND                     
                                  10       VR_PVCCIO_CPU1_PH1_SW   
                                  25       VR_FET_SW_P12V_STBY_PVCCIN_CPU0
                                  30       VR_FET_SW_P12V_STBY_PVCCIN_CPU0
                                  31       NC_PVCCIO_CPU1_PH1_P31  
                                  32       VR_PVCCIO_CPU1_PH1_PHASE
                                  33       VR_PVCCIO_CPU1_PH1_BOOT_R
                                  34       VR_PVCCIO_CPU1_PWM1     
                                  35       P5V_STBY                
                                  36       A_TSENSE_PVCCIO_CPU1    
                                  37       VR_PVCCIO_CPU1_OCSET    
                                  38       ISENSE_PVCCIO_CPU1_PH1_IMON
                                  39       VR_PVCCIO_CPU1_AIREF1   
                                  40       GND                     
                                  41       TP_PVCCIO_CPU1_GL_1     
EU4G1            NCP3232L_SM-IC,H86355-001 1        VR_PVPP_GHJ_SS          
                                  2        VR_FB_PVPP_GHJ          
                                  3        VR_COMP_PVPP_GHJ_3      
                                  4        VR_PVPP_GHJ_ISET        
                                  5        AGND_PVPP_GHJ           
                                  6        AGND_PVPP_GHJ           
                                  7        PWRGD_PVPP_GHJ_R        
                                  8        VR_FET_SW_P12V_STBY_PVPP_GHJ
                                  9        VR_FET_SW_P12V_STBY_PVPP_GHJ
                                  10       VR_FET_SW_P12V_STBY_PVPP_GHJ
                                  11       VR_FET_SW_P12V_STBY_PVPP_GHJ
                                  12       VR_FET_SW_P12V_STBY_PVPP_GHJ
                                  13       VR_FET_SW_P12V_STBY_PVPP_GHJ
                                  14       VR_FET_SW_P12V_STBY_PVPP_GHJ
                                  15       VR_PVPP_GHJ_PHASE       
                                  16       GND                     
                                  17       GND                     
                                  18       GND                     
                                  19       GND                     
                                  20       GND                     
                                  21       GND                     
                                  22       GND                     
                                  23       GND                     
                                  24       GND                     
                                  25       GND                     
                                  26       GND                     
                                  27       GND                     
                                  28       GND                     
                                  29       VR_PVPP_GHJ_PHASE       
                                  30       VR_PVPP_GHJ_PHASE       
                                  31       VR_PVPP_GHJ_PHASE       
                                  32       VR_PVPP_GHJ_PHASE       
                                  33       VR_PVPP_GHJ_PHASE       
                                  34       VR_PVPP_GHJ_PHASE       
                                  35       VR_PVPP_GHJ_PHASE       
                                  36       VR_PVPP_GHJ_BOOT        
                                  37       GND                     
                                  38       VR_VB_PVPP_GHJ          
                                  39       VR_FET_SW_P12V_STBY_PVPP_GHJ
                                  40       FM_PVPP_PVDDQ_CPU1_EN_GHJ
                                  41       GND                     
                                  42       VR_FET_SW_P12V_STBY_PVPP_GHJ
                                  43       VR_PVPP_GHJ_PHASE       
EU4G2            MIC5166_DFN-IC,H55101-001 1        VR_PVTT_GHJ_VREF        
                                  2        VR_PVTT_GHJ_BIAS        
                                  3        GND                     
                                  4        VSENSE_PVDDQ_GHJ_VTT    
                                  5        PWRGD_PVTT_GHJ_CPU1_R   
                                  6        VR_PVTT_GHJ_SNS         
                                  7        FM_PVTT_GHJ_EN_R        
                                  8        GND                     
                                  9        PVTT_GHJ                
                                  10       PVDDQ_GHJ               
                                  11       GND                     
EU4G3            MIC5166_DFN-IC,H55101-001 1        VR_PVTT_ABC_VREF        
                                  2        VR_PVTT_ABC_BIAS        
                                  3        GND                     
                                  4        VSENSE_PVDDQ_ABC_VTT    
                                  5        PWRGD_PVTT_ABC_CPU0_R   
                                  6        VR_PVTT_ABC_SNS         
                                  7        FM_PVTT_ABC_EN_R        
                                  8        GND                     
                                  9        PVTT_ABC                
                                  10       PVDDQ_ABC               
                                  11       GND                     
EU7A1            IR354XX_SM-IR35411,IC,H73688-0A 1        PVDDQ_DEF               
                                  2        GND                     
                                  3        VR_PVDDQ_DEF_PH1_VCIN   
                                  4        P5V_STBY                
                                  5        GND                     
                                  6        TP_PVDDQ_DEF_PH1_GL_0   
                                  7        GND                     
                                  10       VR_PVDDQ_DEF_PH1_SW     
                                  25       VR_FET_SW_P12V_STBY_PVDDQ_DEF
                                  30       VR_FET_SW_P12V_STBY_PVDDQ_DEF
                                  31       NC_PVDDQ_DEF_PH1_P31    
                                  32       VR_PVDDQ_DEF_PH1_PHASE  
                                  33       VR_PVDDQ_DEF_PH1_BOOT_R 
                                  34       VR_PVDDQ_DEF_PWM1       
                                  35       P5V_STBY                
                                  36       A_TSENSE_PVDDQ_DEF      
                                  37       VR_PVDDQ_DEF_PH1_OCSET  
                                  38       ISENSE_PVDDQ_DEF_PH1_IMON
                                  39       VR_PVDDQ_DEF_AIREF1     
                                  40       GND                     
                                  41       TP_PVDDQ_DEF_PH1_GL_1   
EU7A2            IR354XX_SM-IR35412,IC,H73684-0A 1        P1V05_PCH_STBY          
                                  2        GND                     
                                  3        VR_P1V05_PCH_STBY_PH1_VCIN
                                  4        P5V_STBY                
                                  5        GND                     
                                  6        TP_P1V05_PCH_GL_0       
                                  7        GND                     
                                  10       VR_P1V05_PCH_STBY_PH1_PHASE_SW
                                  25       VR_FET_SW_P12V_STBY_PVDDQ_DEF
                                  30       VR_FET_SW_P12V_STBY_PVDDQ_DEF
                                  31       NC_P1V05_PCH_STBY_PH1_P31
                                  32       VR_P1V05_PCH_STBY_PH1_PHASE
                                  33       VR_P1V05_PCH_STBY_PH1_BOOT_R
                                  34       VR_P1V05_PCH_STBY_PWM1  
                                  35       P5V_STBY                
                                  36       A_TSENSE_P1V05_PCH_STBY_TMON
                                  37       VR_P1V05_PCH_STBY_OCSET 
                                  38       ISENSE_P1V05_PCH_STBY_PH1_IMON
                                  39       VR_P1V05_PCH_BIREF1     
                                  40       GND                     
                                  41       TP_P1V05_PCH_GL_1       
EU7A3            IR354XX_SM-IR35412,IC,H73684-0A 1        PVNN_PCH_STBY           
                                  2        GND                     
                                  3        VR_PVNN_PCH_PH1_VCIN    
                                  4        P5V_STBY                
                                  5        GND                     
                                  6        TP_PVNN_PCH_GL_0        
                                  7        GND                     
                                  10       VR_PVNN_PCH_PH1_PHASE_SW
                                  25       VR_FET_SW_P12V_STBY_PVDDQ_DEF
                                  30       VR_FET_SW_P12V_STBY_PVDDQ_DEF
                                  31       NC_PVNN_PCH_PH1_P31     
                                  32       VR_PVNN_PCH_PH1_PHASE   
                                  33       VR_PVNN_PCH_PH1_BOOT_R  
                                  34       VR_PVNN_PCH_PWM1        
                                  35       P5V_STBY                
                                  36       A_TSENSE_PVNN_PCH_TMON  
                                  37       VR_PVNN_PCH_STBY_OCSET  
                                  38       ISENSE_PVNN_PCH_PH1_IMON
                                  39       VR_PVNN_PCH_AIREF1      
                                  40       GND                     
                                  41       TP_PVNN_PCH_GL_1        
EU7A4            IR354XX_SM-IR35411,IC,H73688-0A 1        PVDDQ_DEF               
                                  2        GND                     
                                  3        VR_PVDDQ_DEF_PH2_VCIN   
                                  4        P5V_STBY                
                                  5        GND                     
                                  6        TP_PVDDQ_DEF_PH2_GL_0   
                                  7        GND                     
                                  10       VR_PVDDQ_DEF_PH2_SW     
                                  25       VR_FET_SW_P12V_STBY_PVDDQ_DEF
                                  30       VR_FET_SW_P12V_STBY_PVDDQ_DEF
                                  31       NC_PVDDQ_DEF_PH2_P31    
                                  32       VR_PVDDQ_DEF_PH2_PHASE  
                                  33       VR_PVDDQ_DEF_PH2_BOOT_R 
                                  34       VR_PVDDQ_DEF_PWM2       
                                  35       P5V_STBY                
                                  36       A_TSENSE_PVDDQ_DEF      
                                  37       VR_PVDDQ_DEF_PH2_OCSET  
                                  38       ISENSE_PVDDQ_DEF_PH2_IMON
                                  39       VR_PVDDQ_DEF_AIREF2     
                                  40       GND                     
                                  41       TP_PVDDQ_DEF_PH2_GL_1   
EU7A5            PXM1310B_QFN-IC,H89186-001 1        TP_PVDDQ_DEF_BPWM1      
                                  2        NC_PVDDQ_DEF_DNC0       
                                  3        TP_PVDDQ_DEF_PWM3       
                                  4        VR_PVDDQ_DEF_PWM2       
                                  5        VR_PVDDQ_DEF_PWM1       
                                  6        SMB_VR_SDA_VDDQ_DEF     
                                  7        SMB_VR_SCL_VDDQ_DEF     
                                  8        TP_PVDDQ_DEF_RESET_N    
                                  9        PWRGD_PVDDQ_DEF_R       
                                  10       VR_PVDDQ_DEF_VREN       
                                  11       IRQ_PVDDQ_DEF_VRHOT_LVT3_R_N
                                  12       TP_PVDDQ_DEF_PINALRT_N  
                                  13       PU_VR_PVDDQ_DEF_FAULT1  
                                  14       TP_PVDDQ_DEF_MP1        
                                  15       SVID_CLK_PVDDQ_DEF      
                                  16       SVID_VDIO_PVDDQ_DEF     
                                  17       SVID_ALERT_PVDDQ_DEF    
                                  18       TP_PVDDQ_DEF_MP2        
                                  19       VR_PVDDQ_DEF_AVSP       
                                  20       VSENSE_PVDDQ_DEF_N      
                                  21       VR_PVDDQ_DEF_AIREF1     
                                  22       ISENSE_PVDDQ_DEF_PH1_IMON
                                  23       VR_PVDDQ_DEF_AIREF2     
                                  24       ISENSE_PVDDQ_DEF_PH2_IMON
                                  25       TP_PVDDQ_DEF_PH3_IMON_REF
                                  26       TP_PVDDQ_DEF_PH3_IMON   
                                  27       GND                     
                                  28       NC_PVDDQ_DEF_DNC1       
                                  29       TP_PVDDQ_DEF_BVSEN      
                                  30       TP_PVDDQ_DEF_BVREF      
                                  31       TP_PVDDQ_DEF_BREF1      
                                  32       GND                     
                                  33       VR_PVDDQ_DEF_XADDR2     
                                  34       TP_PVDDQ_DEF_BTSEN      
                                  35       A_TSENSE_PVDDQ_DEF      
                                  36       VR_PVDDQ_DEF_XADDR1     
                                  37       VR_PVDDQ_DEF_VINSEN     
                                  38       VR_PVDDQ_DEF_AIINSEN    
                                  39       VR_PVDDQ_DEF_VDD        
                                  40       VR_PVDDQ_DEF_VD12       
                                  41       GND                     
EU7B1            NCP3232L_SM-IC,H86355-001 1        VR_PVPP_DEF_SS          
                                  2        VR_FB_PVPP_DEF          
                                  3        VR_COMP_PVPP_DEF_3      
                                  4        VR_PVPP_DEF_ISET        
                                  5        AGND_PVPP_DEF           
                                  6        AGND_PVPP_DEF           
                                  7        PWRGD_PVPP_DEF_R        
                                  8        VR_FET_SW_P12V_STBY_PVPP_DEF
                                  9        VR_FET_SW_P12V_STBY_PVPP_DEF
                                  10       VR_FET_SW_P12V_STBY_PVPP_DEF
                                  11       VR_FET_SW_P12V_STBY_PVPP_DEF
                                  12       VR_FET_SW_P12V_STBY_PVPP_DEF
                                  13       VR_FET_SW_P12V_STBY_PVPP_DEF
                                  14       VR_FET_SW_P12V_STBY_PVPP_DEF
                                  15       VR_PVPP_DEF_PHASE       
                                  16       GND                     
                                  17       GND                     
                                  18       GND                     
                                  19       GND                     
                                  20       GND                     
                                  21       GND                     
                                  22       GND                     
                                  23       GND                     
                                  24       GND                     
                                  25       GND                     
                                  26       GND                     
                                  27       GND                     
                                  28       GND                     
                                  29       VR_PVPP_DEF_PHASE       
                                  30       VR_PVPP_DEF_PHASE       
                                  31       VR_PVPP_DEF_PHASE       
                                  32       VR_PVPP_DEF_PHASE       
                                  33       VR_PVPP_DEF_PHASE       
                                  34       VR_PVPP_DEF_PHASE       
                                  35       VR_PVPP_DEF_PHASE       
                                  36       VR_PVPP_DEF_BOOT        
                                  37       GND                     
                                  38       VR_VB_PVPP_DEF          
                                  39       VR_FET_SW_P12V_STBY_PVPP_DEF
                                  40       FM_PVPP_PVDDQ_CPU0_EN_DEF
                                  41       GND                     
                                  42       VR_FET_SW_P12V_STBY_PVPP_DEF
                                  43       VR_PVPP_DEF_PHASE       
EU7C1            IR354XX_SM-IR35412,IC,H73684-0A 1        PVCCIO_CPU0             
                                  2        GND                     
                                  3        VR_PVCCIO_CPU0_PH1_VCIN 
                                  4        P5V_STBY                
                                  5        GND                     
                                  6        TP_PVCCIO_CPU0_GL_0     
                                  7        GND                     
                                  10       VR_PVCCIO_CPU0_PH1_SW   
                                  25       VR_FET_SW_P12V_STBY_PVCCIO_CPU0
                                  30       VR_FET_SW_P12V_STBY_PVCCIO_CPU0
                                  31       NC_PVCCIO_CPU0_PH1_P31  
                                  32       VR_PVCCIO_CPU0_PH1_PHASE
                                  33       VR_PVCCIO_CPU0_PH1_BOOT_R
                                  34       VR_PVCCIO_CPU0_PWM1     
                                  35       P5V_STBY                
                                  36       A_TSENSE_PVCCIO_CPU0    
                                  37       VR_PVCCIO_CPU0_OCSET    
                                  38       ISENSE_PVCCIO_CPU0_PH1_IMON
                                  39       VR_PVCCIO_CPU0_AIREF1   
                                  40       GND                     
                                  41       TP_PVCCIO_CPU0_GL_1     
EU7E1            SLG55021_SM-IC,G56246-001 1        P5V_STBY                
                                  2        FM_P12V_MAIN_SW_EN      
                                  3        P5V_STBY                
                                  4        GND                     
                                  5        P12V_STBY               
                                  6        P12V                    
                                  7        P12V_SWITCH_G           
                                  8        TP_SLG55021_P12V_MAIN_8 
                                  9        GND                     
EU7E2            TPS54821_LCC-IC,H63269-001 1        VR_P5V_STBY_RT          
                                  2        GND                     
                                  3        GND                     
                                  4        VR_FET_SW_P5V_STBY_PVIN 
                                  5        VR_FET_SW_P5V_STBY_PVIN 
                                  6        VR_P5V_STBY_VIN         
                                  7        VR_P5V_STBY_VSENSE      
                                  8        VR_P5V_STBY_COMP        
                                  9        VR_P5V_STBY_SS          
                                  10       VR_P5V_STBY_EN          
                                  11       VR_P5V_STBY_PHASE       
                                  12       VR_P5V_STBY_PHASE       
                                  13       VR_P5V_STBY_BOOT        
                                  14       PWRGD_P5V_STBY_R        
                                  15       GND                     
EU7F1            NCP3232L_SM-IC,H86355-001 1        VR_PVPP_ABC_SS          
                                  2        VR_FB_PVPP_ABC          
                                  3        VR_COMP_PVPP_ABC_3      
                                  4        VR_PVPP_ABC_ISET        
                                  5        AGND_PVPP_ABC           
                                  6        AGND_PVPP_ABC           
                                  7        PWRGD_PVPP_ABC_R        
                                  8        VR_FET_SW_P12V_STBY_PVPP_ABC
                                  9        VR_FET_SW_P12V_STBY_PVPP_ABC
                                  10       VR_FET_SW_P12V_STBY_PVPP_ABC
                                  11       VR_FET_SW_P12V_STBY_PVPP_ABC
                                  12       VR_FET_SW_P12V_STBY_PVPP_ABC
                                  13       VR_FET_SW_P12V_STBY_PVPP_ABC
                                  14       VR_FET_SW_P12V_STBY_PVPP_ABC
                                  15       VR_PVPP_ABC_PHASE       
                                  16       GND                     
                                  17       GND                     
                                  18       GND                     
                                  19       GND                     
                                  20       GND                     
                                  21       GND                     
                                  22       GND                     
                                  23       GND                     
                                  24       GND                     
                                  25       GND                     
                                  26       GND                     
                                  27       GND                     
                                  28       GND                     
                                  29       VR_PVPP_ABC_PHASE       
                                  30       VR_PVPP_ABC_PHASE       
                                  31       VR_PVPP_ABC_PHASE       
                                  32       VR_PVPP_ABC_PHASE       
                                  33       VR_PVPP_ABC_PHASE       
                                  34       VR_PVPP_ABC_PHASE       
                                  35       VR_PVPP_ABC_PHASE       
                                  36       VR_PVPP_ABC_BOOT        
                                  37       GND                     
                                  38       VR_VB_PVPP_ABC          
                                  39       VR_FET_SW_P12V_STBY_PVPP_ABC
                                  40       FM_PVPP_PVDDQ_CPU0_EN_ABC
                                  41       GND                     
                                  42       VR_FET_SW_P12V_STBY_PVPP_ABC
                                  43       VR_PVPP_ABC_PHASE       
EU7G1            PXM1310B_QFN-IC,H89186-001 1        TP_PVDDQ_ABC_BPWM1      
                                  2        NC_PVDDQ_ABC_DNC0       
                                  3        TP_PVDDQ_ABC_PWM3       
                                  4        VR_PVDDQ_ABC_PWM2       
                                  5        VR_PVDDQ_ABC_PWM1       
                                  6        SMB_VR_SDA_VDDQ_ABC     
                                  7        SMB_VR_SCL_VDDQ_ABC     
                                  8        TP_PVDDQ_ABC_RESET_N    
                                  9        PWRGD_PVDDQ_ABC_R       
                                  10       VR_PVDDQ_ABC_VREN       
                                  11       IRQ_PVDDQ_ABC_VRHOT_LVT3_R_N
                                  12       TP_PVDDQ_ABC_PINALRT_N  
                                  13       PU_VR_PVDDQ_ABC_FAULT1  
                                  14       TP_PVDDQ_ABC_MP1        
                                  15       SVID_CLK_PVDDQ_ABC      
                                  16       SVID_VDIO_PVDDQ_ABC     
                                  17       SVID_ALERT_PVDDQ_ABC    
                                  18       TP_PVDDQ_ABC_MP2        
                                  19       VR_PVDDQ_ABC_AVSP       
                                  20       VSENSE_PVDDQ_ABC_N      
                                  21       VR_PVDDQ_ABC_AIREF1     
                                  22       ISENSE_PVDDQ_ABC_PH1_IMON
                                  23       VR_PVDDQ_ABC_AIREF2     
                                  24       ISENSE_PVDDQ_ABC_PH2_IMON
                                  25       TP_PVDDQ_ABC_PH3_IMON_REF
                                  26       TP_PVDDQ_ABC_PH3_IMON   
                                  27       GND                     
                                  28       NC_PVDDQ_ABC_DNC1       
                                  29       TP_PVDDQ_ABC_BVSEN      
                                  30       TP_PVDDQ_ABC_BVREF      
                                  31       TP_PVDDQ_ABC_BREF1      
                                  32       GND                     
                                  33       VR_PVDDQ_ABC_XADDR2     
                                  34       TP_PVDDQ_ABC_BTSEN      
                                  35       A_TSENSE_PVDDQ_ABC      
                                  36       VR_PVDDQ_ABC_XADDR1     
                                  37       VR_PVDDQ_ABC_VINSEN     
                                  38       VR_PVDDQ_ABC_AIINSEN    
                                  39       VR_PVDDQ_ABC_VDD        
                                  40       VR_PVDDQ_ABC_VD12       
                                  41       GND                     
EU7G2            IR354XX_SM-IR35411,IC,H73688-0A 1        PVDDQ_ABC               
                                  2        GND                     
                                  3        VR_PVDDQ_ABC_PH1_VCIN   
                                  4        P5V_STBY                
                                  5        GND                     
                                  6        TP_PVDDQ_ABC_PH1_GL_0   
                                  7        GND                     
                                  10       VR_PVDDQ_ABC_PH1_SW     
                                  25       VR_FET_SW_P12V_STBY_PVDDQ_ABC
                                  30       VR_FET_SW_P12V_STBY_PVDDQ_ABC
                                  31       NC_PVDDQ_ABC_PH1_P31    
                                  32       VR_PVDDQ_ABC_PH1_PHASE  
                                  33       VR_PVDDQ_ABC_PH1_BOOT_R 
                                  34       VR_PVDDQ_ABC_PWM1       
                                  35       P5V_STBY                
                                  36       A_TSENSE_PVDDQ_ABC      
                                  37       VR_PVDDQ_ABC_PH1_OCSET  
                                  38       ISENSE_PVDDQ_ABC_PH1_IMON
                                  39       VR_PVDDQ_ABC_AIREF1     
                                  40       GND                     
                                  41       TP_PVDDQ_ABC_PH1_GL_1   
EU7G3            IR354XX_SM-IR35411,IC,H73688-0A 1        PVDDQ_ABC               
                                  2        GND                     
                                  3        VR_PVDDQ_ABC_PH2_VCIN   
                                  4        P5V_STBY                
                                  5        GND                     
                                  6        TP_PVDDQ_ABC_PH2_GL_0   
                                  7        GND                     
                                  10       VR_PVDDQ_ABC_PH2_SW     
                                  25       VR_FET_SW_P12V_STBY_PVDDQ_ABC
                                  30       VR_FET_SW_P12V_STBY_PVDDQ_ABC
                                  31       NC_PVDDQ_ABC_PH2_P31    
                                  32       VR_PVDDQ_ABC_PH2_PHASE  
                                  33       VR_PVDDQ_ABC_PH2_BOOT_R 
                                  34       VR_PVDDQ_ABC_PWM2       
                                  35       P5V_STBY                
                                  36       A_TSENSE_PVDDQ_ABC      
                                  37       VR_PVDDQ_ABC_PH2_OCSET  
                                  38       ISENSE_PVDDQ_ABC_PH2_IMON
                                  39       VR_PVDDQ_ABC_AIREF2     
                                  40       GND                     
                                  41       TP_PVDDQ_ABC_PH2_GL_1   
EU8A1            PXE1110B_QFN-IC,H89187-001 1        NC_PVNN_PCH_DNC0        
                                  2        NC_PVNN_PCH_DNC1        
                                  3        VR_P1V05_PCH_STBY_PWM1  
                                  4        NC_PVNN_PCH_DNC2        
                                  5        VR_PVNN_PCH_PWM1        
                                  6        SMB_VR_SDA_PVNN_PCH     
                                  7        SMB_VR_SCL_PVNN_PCH     
                                  8        TP_PVNN_PCH_RESET_N     
                                  9        PWRGD_PVNN_PCH_R        
                                  10       VR_PVNN_PCH_VREN        
                                  11       IRQ_PVNN_PCH_VRHOT_N    
                                  12       TP_PVNN_PCH_PINALRT_N   
                                  13       VID_PCH_CORE_PVNN_AUX_VID_0
                                  14       VID_PCH_CORE_PVNN_AUX_VID_1
                                  15       TP_PVNN_PCH_VCLK        
                                  16       TP_PVNN_PCH_VDIO        
                                  17       TP_PVNN_PCH_SVID_ALERT  
                                  18       TP_PVNN_PCH_MP2         
                                  19       VR_PVNN_PCH_AVSP        
                                  20       VSENSE_PVNN_PCH_STBY_AVSN
                                  21       VR_PVNN_PCH_AIREF1      
                                  22       ISENSE_PVNN_PCH_PH1_IMON
                                  23       GND                     
                                  24       NC_PVNN_PCH_DNC3        
                                  25       VR_P1V05_PCH_BIREF1     
                                  26       ISENSE_P1V05_PCH_STBY_PH1_IMON
                                  27       GND                     
                                  28       NC_PVNN_PCH_DNC4        
                                  29       VR_P1V05_PCH_STBY_AVSP  
                                  30       VSENSE_P1V05_PCH_STBY_AVSN
                                  31       TP_PVNN_PCH_MP3         
                                  32       PU_VR_PVNN_PCH_FAULT1   
                                  33       VR_PVNN_PCH_XADDR2      
                                  34       A_TSENSE_P1V05_PCH_STBY_TMON
                                  35       A_TSENSE_PVNN_PCH_TMON  
                                  36       VR_PVNN_PCH_XADDR1      
                                  37       VR_PVNN_PCH_VINSEN      
                                  38       TP_VR_PVNN_PCH_AIINSEN  
                                  39       VR_PVNN_PCH_VDD         
                                  40       VR_PVNN_P1V05_PCH_VD12  
                                  41       GND                     
EU8A2            RT9059_DFN-IC,H65765-001 1        P1V8_PCH_STBY           
                                  2        P1V8_PCH_STBY           
                                  3        P1V8_PCH_STBY           
                                  4        VR_P1V8_PCH_STBY_FB     
                                  5        PWRGD_P1V8_PCH_STBY_R   
                                  6        PWRGD_P3V3_STBY         
                                  7        P3V3_STBY               
                                  8        P3V3_STBY               
                                  9        P3V3_STBY               
                                  10       P3V3_STBY               
                                  11       GND                     
EU8B1            SLG55021_SM-IC,G56246-001 1        P5V_STBY                
                                  2        FM_CTNR_PS_ON           
                                  3        P5V_STBY                
                                  4        GND                     
                                  5        P5V_STBY                
                                  6        P5V                     
                                  7        P5V_SWITCH_G            
                                  8        TP_SLG55021_P5V_8       
                                  9        GND                     
EU8E1            CSD87384M_SM-IC,H66258-001 1        VR_P3V3_STBY_UGATE      
                                  2        VR_FET_SW_P12V_STBY_P3V3_STBY
                                  3        GND                     
                                  4        VR_P3V3_STBY_LGATE      
                                  5        VR_P3V3_STBY_PHASE      
EU8F1            RT8240_QFN-IC,H66262-001 1        VR_P3V3_STBY_LGATE      
                                  2        VR_P3V3_STBY_PHASE      
                                  3        VR_P3V3_STBY_UGATE      
                                  4        VR_P3V3_STBY_BOOT       
                                  5        P5V_STBY                
                                  6        VSENSE_VOUT_P3V3_STBY   
                                  7        VSENSE_RGND_P3V3_STBY   
                                  8        VR_P3V3_STBY_EN         
                                  9        PWRGD_P3V3_STBY_R       
                                  10       VR_P3V3_STBY_OCSELECT   
                                  11       AGND_P3V3_STBY          
                                  12       AGND_P3V3_STBY          
                                  13       AGND_P3V3_STBY          
EU8F2            ICS9FGP204_MLFP-IC,E95226-001 1        GND                     
                                  2        P3V3_STBY_MNG           
                                  3        TP_CLK_96M_CKMNG_P      
                                  4        TP_CLK_96M_CKMNG_N      
                                  5        PD_CKMNG_OE             
                                  6        PD_CKMNG_OE             
                                  7        TP_CLK_100M_R_DP        
                                  8        TP_CLK_100M_R_DN        
                                  9        P3V3_STBY_MNG_CPU       
                                  10       GND                     
                                  11       A_COMP_CKMNG            
                                  12       P3V3_STBY_MNG           
                                  13       CLK_32K_SUSCLK_PLD_R    
                                  14       GND                     
                                  15       P3V3_STBY_MNG           
                                  16       CLK_25M_BMC_R           
                                  17       CLK_25M_CPLD_R          
                                  18       GND                     
                                  19       XTAL_CK_MNG_IN          
                                  20       XTAL_CK_MNG_OUT         
                                  21       GND                     
                                  22       TP_33P_33M_SMBADR       
                                  23       P3V3_STBY_MNG           
                                  24       TP_CLK5_50M_CKMNG       
                                  25       CLK_50M_CKMNG_PCH_10GBE_R
                                  26       P3V3_STBY_MNG_RMII      
                                  27       GND                     
                                  28       CLK_50M_CKMNG_SPRVLLE_R 
                                  29       CLK_50M_CKMNG_BMC_2_R   
                                  30       GND                     
                                  31       P3V3_STBY_MNG_RMII      
                                  32       CLK_50M_CKMNG_BMC_1_R   
                                  33       CLK_50M_CKMNG_OCP_R     
                                  34       P3V3_STBY_MNG_RGMII     
                                  35       GND                     
                                  36       TP_CLK_125M             
                                  37       TP_CLK_125M_BMCA        
                                  38       SMB_HOST_STBY_LVC3_SCL  
                                  39       SMB_HOST_STBY_LVC3_SDA  
                                  40       PWRGD_P3V3_STBY         
                                  41       GND                     
EU9E1            SPRINGVILLE_SM1-IC,G47144-004 1        PU_SPRV_LAN_PWR_GOOD    
                                  2        CLK_50M_CKMNG_SPRVLLE   
                                  3        RMII_BMC_PCH_SPRNGVLLE_CRSDV_R
                                  4        PU_JTAG_SPRV_TDO        
                                  5        RMII_SPRNGVLLE_BMC_PCH_RXD1_R
                                  6        RMII_SPRNGVLLE_BMC_PCH_RXD0_R
                                  7        RMII_BMC_PCH_SPRNGVLLE_TXEN
                                  8        RMII_BMC_PCH_SPRNGVLLE_TXD1
                                  9        RMII_BMC_PCH_SPRNGVLLE_TXD0
                                  10       P3V3_STBY               
                                  11       P0V9_LAN                
                                  12       SPI_NIC_MOSI_R          
                                  13       SPI_NIC_SCLK_R          
                                  14       SPI_NIC_MISO            
                                  15       SPI_NIC_CS_R_N          
                                  16       FM_PE_SPRV_WAKE_N       
                                  17       RST_PLTRST_SPRV_R_N     
                                  18       PU_JTAG_SPRV_TMS        
                                  19       PU_JTAG_SPRV_TCK        
                                  20       PE_PCH_SPRV_RX_DN       
                                  21       PE_PCH_SPRV_RX_DP       
                                  22       NC_SPRNGVLLE_22         
                                  23       PE_PCH_SPRV_TX_C_DN     
                                  24       PE_PCH_SPRV_TX_C_DP     
                                  25       CLK_100M_SPRV_DN        
                                  26       CLK_100M_SPRV_DP        
                                  27       P3V3_STBY               
                                  28       FM_1GB_LOM_DISABLE_N    
                                  29       PU_JTAG_SPRV_TDI        
                                  30       LED_LAN_1_N             
                                  31       LED_LAN_0_N             
                                  32       P0V9_LAN                
                                  33       LED_LAN_2_N             
                                  34       SMB_SPRINGVILLE_STBY_LVC3_SCL
                                  35       IRQ_LOM_ALERT_N         
                                  36       SMB_SPRINGVILLE_STBY_LVC3_SDA
                                  37       A_CBOT                  
                                  38       P0V9_LAN_I210           
                                  39       P1V5_LAN                
                                  40       A_CTOP                  
                                  41       P3V3_STBY               
                                  42       P0V9_LAN                
                                  43       RMII_PCH_SPRNGVLLE_ARB_OUT
                                  44       RMII_PCH_SPRNGVLLE_ARB_IN_R
                                  45       XTAL_25MHZ_OUT          
                                  46       XTAL_25MHZ_IN_R         
                                  47       P1V5_LAN                
                                  48       PD_SPRV_RSET            
                                  49       NIC_SER_N_MDI_3_DN      
                                  50       NIC_SER_P_MDI_3_DP      
                                  51       P3V3_STBY_P1V5_LAN_I210 
                                  52       NIC_SET_N_MDI_2_DN      
                                  53       NIC_SET_P_MDI_2_DP      
                                  54       NIC_MDI_SPRV_RJ45_1_DN  
                                  55       NIC_MDI_SPRV_RJ45_1_DP  
                                  56       P1V5_LAN_I210           
                                  57       NIC_MDI_SPRV_RJ45_0_DN  
                                  58       NIC_MDI_SPRV_RJ45_0_DP  
                                  59       P0V9_LAN                
                                  60       TP_SPRV_SDP3            
                                  61       TP_SPRV_SDP1            
                                  62       TP_SPRV_SDP2            
                                  63       TP_SPRV_SDP0            
                                  64       P3V3_STBY               
                                  65       GND                     
EU9F1            RT9059_DFN-IC,H65765-001 1        P1V26_BMC_STBY          
                                  2        P1V26_BMC_STBY          
                                  3        P1V26_BMC_STBY          
                                  4        VR_P1V26_BMC_STBY_FB    
                                  5        PWRGD_P1V26_BMC_STBY_R  
                                  6        PWRGD_P1V538_BMC_STBY   
                                  7        P1V538_BMC_STBY         
                                  8        P1V538_BMC_STBY         
                                  9        P1V538_BMC_STBY         
                                  10       P3V3_STBY               
                                  11       GND                     
EU9F2            RT9059_DFN-IC,H65765-001 1        P1V538_BMC_STBY         
                                  2        P1V538_BMC_STBY         
                                  3        P1V538_BMC_STBY         
                                  4        VR_P1V538_BMC_STBY_FB   
                                  5        PWRGD_P1V538_BMC_STBY_R 
                                  6        PWRGD_P3V3_STBY         
                                  7        P3V3_STBY               
                                  8        P3V3_STBY               
                                  9        P3V3_STBY               
                                  10       P3V3_STBY               
                                  11       GND                     
EU9F3            PI7C9X1172_QFN-IC,H66899-001 1        NC_PI7C9X1172_1         
                                  2        TP_PI7C9X1172_SO        
                                  3        SMB_SLOTX24_PCH_STBY_LVC3_SDA
                                  4        UART_BRIDGE_RXD5        
                                  5        SP1_HOST_BRIDGE_UART_RX 
                                  6        SP1_HOST_BRIDGE_UART_TX 
                                  7        UART_BRIDGE_TXD5        
                                  8        NC_PI7C9X1172_8         
                                  9        XTAL_24MHZ_IN_R         
                                  10       XTAL_24MHZ_OUT_R        
                                  11       TP_GPIO2_CDB_N          
                                  12       GND                     
                                  13       TP_GPIO0_DSRB_N         
                                  14       TP_GPIO3_RIB_N          
                                  15       TP_PI7C9X1172_RTSB_N    
                                  16       GND                     
                                  17       SMB_SLOTX24_PCH_STBY_LVC3_SCL
                                  18       TP_PI7C9X1172_ENIR_N    
                                  19       TP_PI7C9X1172_EN485_N   
                                  20       FM_UART_ALERT_N         
                                  21       TP_PI7C9X1172_RTSA_N    
                                  22       TP_GPIO5_DTRA_N         
                                  23       TP_GPIO1_DTRB_N         
                                  24       PWRGD_DSW_PWROK         
                                  25       GND                     
                                  26       TP_GPIO4_DSRA_N         
                                  27       TP_GPIO6_CDA_N          
                                  28       TP_GPIO7_RIA_N          
                                  29       P3V3_STBY               
                                  30       FM_PI7C9X1172_A0        
                                  31       FM_PI7C9X1172_A1        
                                  32       PU_PI7C9X1172_I2C_SPI_N 
                                  33       GND                     
EU9G1            ADC128D818_SM-IC,H63642-001 1        TP_ADC128_VREF          
                                  2        SMB_SENSOR_PCH_STBY_LVC3_SDA
                                  3        SMB_SENSOR_PCH_STBY_LVC3_SCL
                                  4        GND                     
                                  5        P3V3_FB_ADC128_VCC      
                                  6        IRQ_VM_INT_R_N          
                                  7        FM_ADC128_A0            
                                  8        FM_ADC128_A1            
                                  9        A_P3V_BAT_SCALED        
                                  10       A_P5V_STBY_SCALED       
                                  11       A_P3V3_STBY_SCALED      
                                  12       A_PVNN_STBY_PCH_SENSOR  
                                  13       A_P1V05_STBY_PCH_SENSOR 
                                  14       A_P12V_STBY_SCALED      
                                  15       A_P5V_SCALED            
                                  16       A_P3V3_SCALED           
EU9M1            SLG55021_SM-IC,G56246-001 1        P5V_STBY                
                                  2        FM_ENABLE_FAN_POWER     
                                  3        P5V_STBY                
                                  4        GND                     
                                  5        P12V_STBY               
                                  6        P12V_FAN                
                                  7        P12V_FAN_SWITCH_G       
                                  8        TP_SLG55021_P12V_FAN_8  
                                  9        GND                     
EU9R1            MOSFETN_1D3S_SOT5-IC,G68777-001 1        P12V_STBY               
                                  2        P12V_STBY               
                                  3        P12V_STBY               
                                  4        A_HSC_GATE2_R           
                                  5        P12V_MB0_SW             
F1L1             FUSE_SMT-IC,H45581-001 1        P5V_STBY_DBG            
                                  2        P5V_STBY_DGB_FS         
F8B1             FUSE_SMLF-IC,C94311-006 1        P5V                     
                                  2        P5V_HDD_SATA            
F9B1             FUSE_SM-IC,C94311-016 1        P12V                    
                                  2        P12V_HDD_SATA           
FB1T1            FERRITE_SMLF-300,EMPTY,693286-A 1        P1V8_PCH_STBY           
                                  2        P1V8_BMC_STBY_PCIE      
FB1T2            FERRITE_SMLF-300,FB,693286-046 1        P3V3_STBY               
                                  2        P3V3_STBY_BMC_HPLLAV33  
FB1U1            FERRITE_SMLF-300,FB,693286-046 1        P3V3_STBY               
                                  2        P3V3_STBY_BMC_ADCAV33   
FB1U2            FERRITE_SMLF-60,FB,693286-001 1        P3V3_STBY               
                                  2        P3V3_FB_ADC128_VCC      
FB1U3            FERRITE_SMLF-30,FB,693286-021 1        A_P1V05_STBY_PCH_SENSOR 
                                  2        P1V05_PCH_STBY          
FB1U4            FERRITE_SMLF-30,FB,693286-021 1        A_PVNN_STBY_PCH_SENSOR  
                                  2        PVNN_PCH_STBY           
FB2M1            FERRITE_SM-120,FB,693286-027 1        P1V05_PCH_STBY          
                                  2        P1V05_PCH_STBY_WM20_PLL 
FB2M2            FERRITE_SM-120,FB,693286-027 1        P1V05_PCH_STBY          
                                  2        P1V05_PCH_STBY_WM26_PLL 
FB2T1            FERRITE_SMLF-300,EMPTY,693286-A 1        P1V8_PCH_STBY           
                                  2        P1V8_BMC_STBY_PCIEA     
FB2T2            FERRITE_SMLF-600,FB,656554-043 1        P3V3_STBY               
                                  2        P3V3_STBY_MNG           
FB3M1            FERRITE_SM-120,FB,693286-027 1        P1V05_PCH_STBY          
                                  2        P1V05_PCH_STBY_VCCA_PLL1
FB3M2            FERRITE_SM-120,FB,693286-027 1        P1V05_PCH_STBY          
                                  2        P1V05_PCH_STBY_VCCA_PLL0
FB3M3            FERRITE_SM-120,FB,693286-027 1        P1V05_PCH_STBY          
                                  2        P1V05_PCH_STBY_VCCA_XTAL
FB3M4            FERRITE_SM-120,FB,693286-027 1        P1V05_PCH_STBY          
                                  2        P1V05_PCH_STBY_ISCLK_PLL
FB4A1            FERRITE_SM-22,FB,656554-051 1        P12V_STBY               
                                  2        VR_FET_SW_P12V_STBY_PVPP_KLM
FB4G1            FERRITE_SM-22,FB,656554-051 1        P12V_STBY               
                                  2        VR_FET_SW_P12V_STBY_PVPP_GHJ
FB6P1            FERRITE_SMLF-600,FB,656554-043 1        P3V3                    
                                  2        P3V3_DB1200             
FB7B1            FERRITE_SM-22,FB,656554-051 1        P12V_STBY               
                                  2        VR_FET_SW_P12V_STBY_PVPP_DEF
FB7E1            FERRITE_SM-22,FB,656554-051 1        P12V_STBY               
                                  2        VR_FET_SW_P5V_STBY_PVIN 
FB7F1            FERRITE_SM-22,FB,656554-051 1        P12V_STBY               
                                  2        VR_FET_SW_P12V_STBY_PVPP_ABC
FB9E1            FERRITE_SM-22,FB,656554-051 1        P12V_STBY               
                                  2        VR_FET_SW_P12V_STBY_P3V3_STBY
FB9F1            FERRITE_SMLF-300,FB,693286-046 1        P1V26_BMC_STBY          
                                  2        P1V26_BMC_STBY_V1PLLAV12
J1A1             SCONN288_H44441004_PIP-SCONN,HA 1        P12V_NVDIMM_KLM         
                                  2        GND                     
                                  3        M_M_DQ<5>               
                                  4        GND                     
                                  5        M_M_DQ<1>               
                                  6        GND                     
                                  7        M_M_DQS_DP<9>           
                                  8        M_M_DQS_DN<9>           
                                  9        GND                     
                                  10       M_M_DQ<7>               
                                  11       GND                     
                                  12       M_M_DQ<3>               
                                  13       GND                     
                                  14       M_M_DQ<13>              
                                  15       GND                     
                                  16       M_M_DQ<9>               
                                  17       GND                     
                                  18       M_M_DQS_DP<10>          
                                  19       M_M_DQS_DN<10>          
                                  20       GND                     
                                  21       M_M_DQ<15>              
                                  22       GND                     
                                  23       M_M_DQ<11>              
                                  24       GND                     
                                  25       M_M_DQ<21>              
                                  26       GND                     
                                  27       M_M_DQ<17>              
                                  28       GND                     
                                  29       M_M_DQS_DP<11>          
                                  30       M_M_DQS_DN<11>          
                                  31       GND                     
                                  32       M_M_DQ<23>              
                                  33       GND                     
                                  34       M_M_DQ<19>              
                                  35       GND                     
                                  36       M_M_DQ<29>              
                                  37       GND                     
                                  38       M_M_DQ<25>              
                                  39       GND                     
                                  40       M_M_DQS_DP<12>          
                                  41       M_M_DQS_DN<12>          
                                  42       GND                     
                                  43       M_M_DQ<31>              
                                  44       GND                     
                                  45       M_M_DQ<27>              
                                  46       GND                     
                                  47       M_M_ECC<5>              
                                  48       GND                     
                                  49       M_M_ECC<1>              
                                  50       GND                     
                                  51       M_M_DQS_DP<17>          
                                  52       M_M_DQS_DN<17>          
                                  53       GND                     
                                  54       M_M_ECC<7>              
                                  55       GND                     
                                  56       M_M_ECC<3>              
                                  57       GND                     
                                  58       M_KLM_RST_N             
                                  59       PVDDQ_KLM               
                                  60       M_M_CKE<0>              
                                  61       PVDDQ_KLM               
                                  62       M_M_ACT_N               
                                  63       M_M_BG<0>               
                                  64       PVDDQ_KLM               
                                  65       M_M_MA<12>              
                                  66       M_M_MA<9>               
                                  67       PVDDQ_KLM               
                                  68       M_M_MA<8>               
                                  69       M_M_MA<6>               
                                  70       PVDDQ_KLM               
                                  71       M_M_MA<3>               
                                  72       M_M_MA<1>               
                                  73       PVDDQ_KLM               
                                  74       M_M_CLK_DP<0>           
                                  75       M_M_CLK_DN<0>           
                                  76       PVDDQ_KLM               
                                  77       PVTT_KLM                
                                  78       FM_DIMM_EVENT_COD_N     
                                  79       M_M_MA<0>               
                                  80       PVDDQ_KLM               
                                  81       M_M_BA<0>               
                                  82       M_M_MA<16>              
                                  83       PVDDQ_KLM               
                                  84       M_M_CS_N<0>             
                                  85       PVDDQ_KLM               
                                  86       M_M_MA<15>              
                                  87       M_M_ODT<0>              
                                  88       PVDDQ_KLM               
                                  89       M_M_CS_N<1>             
                                  90       PVDDQ_KLM               
                                  91       M_M_ODT<1>              
                                  92       PVDDQ_KLM               
                                  93       M_M_CS_N<2>             
                                  94       GND                     
                                  95       M_M_DQ<37>              
                                  96       GND                     
                                  97       M_M_DQ<33>              
                                  98       GND                     
                                  99       M_M_DQS_DP<13>          
                                  100      M_M_DQS_DN<13>          
                                  101      GND                     
                                  102      M_M_DQ<39>              
                                  103      GND                     
                                  104      M_M_DQ<35>              
                                  105      GND                     
                                  106      M_M_DQ<45>              
                                  107      GND                     
                                  108      M_M_DQ<41>              
                                  109      GND                     
                                  110      M_M_DQS_DP<14>          
                                  111      M_M_DQS_DN<14>          
                                  112      GND                     
                                  113      M_M_DQ<47>              
                                  114      GND                     
                                  115      M_M_DQ<43>              
                                  116      GND                     
                                  117      M_M_DQ<53>              
                                  118      GND                     
                                  119      M_M_DQ<49>              
                                  120      GND                     
                                  121      M_M_DQS_DP<15>          
                                  122      M_M_DQS_DN<15>          
                                  123      GND                     
                                  124      M_M_DQ<55>              
                                  125      GND                     
                                  126      M_M_DQ<51>              
                                  127      GND                     
                                  128      M_M_DQ<61>              
                                  129      GND                     
                                  130      M_M_DQ<57>              
                                  131      GND                     
                                  132      M_M_DQS_DP<16>          
                                  133      M_M_DQS_DN<16>          
                                  134      GND                     
                                  135      M_M_DQ<63>              
                                  136      GND                     
                                  137      M_M_DQ<59>              
                                  138      GND                     
                                  139      GND                     
                                  140      GND                     
                                  141      SMB_DDR_KLM_VPP_SCL     
                                  142      PVPP_KLM                
                                  143      PVPP_KLM                
                                  144      TP_CH_M_DIMM_M0_RFU_2   
                                  145      P12V_NVDIMM_KLM         
                                  146      M_M_VREF                
                                  147      GND                     
                                  148      M_M_DQ<4>               
                                  149      GND                     
                                  150      M_M_DQ<0>               
                                  151      GND                     
                                  152      M_M_DQS_DN<0>           
                                  153      M_M_DQS_DP<0>           
                                  154      GND                     
                                  155      M_M_DQ<6>               
                                  156      GND                     
                                  157      M_M_DQ<2>               
                                  158      GND                     
                                  159      M_M_DQ<12>              
                                  160      GND                     
                                  161      M_M_DQ<8>               
                                  162      GND                     
                                  163      M_M_DQS_DN<1>           
                                  164      M_M_DQS_DP<1>           
                                  165      GND                     
                                  166      M_M_DQ<14>              
                                  167      GND                     
                                  168      M_M_DQ<10>              
                                  169      GND                     
                                  170      M_M_DQ<20>              
                                  171      GND                     
                                  172      M_M_DQ<16>              
                                  173      GND                     
                                  174      M_M_DQS_DN<2>           
                                  175      M_M_DQS_DP<2>           
                                  176      GND                     
                                  177      M_M_DQ<22>              
                                  178      GND                     
                                  179      M_M_DQ<18>              
                                  180      GND                     
                                  181      M_M_DQ<28>              
                                  182      GND                     
                                  183      M_M_DQ<24>              
                                  184      GND                     
                                  185      M_M_DQS_DN<3>           
                                  186      M_M_DQS_DP<3>           
                                  187      GND                     
                                  188      M_M_DQ<30>              
                                  189      GND                     
                                  190      M_M_DQ<26>              
                                  191      GND                     
                                  192      M_M_ECC<4>              
                                  193      GND                     
                                  194      M_M_ECC<0>              
                                  195      GND                     
                                  196      M_M_DQS_DN<8>           
                                  197      M_M_DQS_DP<8>           
                                  198      GND                     
                                  199      M_M_ECC<6>              
                                  200      GND                     
                                  201      M_M_ECC<2>              
                                  202      GND                     
                                  203      M_M_CKE<1>              
                                  204      PVDDQ_KLM               
                                  205      TP_CH_M_DIMM_M0_RFU_0   
                                  206      PVDDQ_KLM               
                                  207      M_M_BG<1>               
                                  208      M_M_ALERT_N             
                                  209      PVDDQ_KLM               
                                  210      M_M_MA<11>              
                                  211      M_M_MA<7>               
                                  212      PVDDQ_KLM               
                                  213      M_M_MA<5>               
                                  214      M_M_MA<4>               
                                  215      PVDDQ_KLM               
                                  216      M_M_MA<2>               
                                  217      PVDDQ_KLM               
                                  218      M_M_CLK_DP<1>           
                                  219      M_M_CLK_DN<1>           
                                  220      PVDDQ_KLM               
                                  221      PVTT_KLM                
                                  222      M_M_PAR                 
                                  223      PVDDQ_KLM               
                                  224      M_M_BA<1>               
                                  225      M_M_MA<10>              
                                  226      PVDDQ_KLM               
                                  227      TP_CH_M_DIMM_M0_RFU_1   
                                  228      M_M_MA<14>              
                                  229      PVDDQ_KLM               
                                  230      FM_ADR_COMPLETE_KLM_N   
                                  231      PVDDQ_KLM               
                                  232      M_M_MA<13>              
                                  233      PVDDQ_KLM               
                                  234      M_M_MA<17>              
                                  235      M_M_C<2>                
                                  236      PVDDQ_KLM               
                                  237      M_M_CS_N<3>             
                                  238      PVPP_KLM                
                                  239      GND                     
                                  240      M_M_DQ<36>              
                                  241      GND                     
                                  242      M_M_DQ<32>              
                                  243      GND                     
                                  244      M_M_DQS_DN<4>           
                                  245      M_M_DQS_DP<4>           
                                  246      GND                     
                                  247      M_M_DQ<38>              
                                  248      GND                     
                                  249      M_M_DQ<34>              
                                  250      GND                     
                                  251      M_M_DQ<44>              
                                  252      GND                     
                                  253      M_M_DQ<40>              
                                  254      GND                     
                                  255      M_M_DQS_DN<5>           
                                  256      M_M_DQS_DP<5>           
                                  257      GND                     
                                  258      M_M_DQ<46>              
                                  259      GND                     
                                  260      M_M_DQ<42>              
                                  261      GND                     
                                  262      M_M_DQ<52>              
                                  263      GND                     
                                  264      M_M_DQ<48>              
                                  265      GND                     
                                  266      M_M_DQS_DN<6>           
                                  267      M_M_DQS_DP<6>           
                                  268      GND                     
                                  269      M_M_DQ<54>              
                                  270      GND                     
                                  271      M_M_DQ<50>              
                                  272      GND                     
                                  273      M_M_DQ<60>              
                                  274      GND                     
                                  275      M_M_DQ<56>              
                                  276      GND                     
                                  277      M_M_DQS_DN<7>           
                                  278      M_M_DQS_DP<7>           
                                  279      GND                     
                                  280      M_M_DQ<62>              
                                  281      GND                     
                                  282      M_M_DQ<58>              
                                  283      GND                     
                                  284      PVPP_KLM                
                                  285      SMB_DDR_KLM_VPP_SDA     
                                  286      PVPP_KLM                
                                  287      PVPP_KLM                
                                  288      PVPP_KLM                
J1A2             SCONN288_H44441004_PIP-SCONN,HA 1        P12V_NVDIMM_KLM         
                                  2        GND                     
                                  3        M_L_DQ<5>               
                                  4        GND                     
                                  5        M_L_DQ<1>               
                                  6        GND                     
                                  7        M_L_DQS_DP<9>           
                                  8        M_L_DQS_DN<9>           
                                  9        GND                     
                                  10       M_L_DQ<7>               
                                  11       GND                     
                                  12       M_L_DQ<3>               
                                  13       GND                     
                                  14       M_L_DQ<13>              
                                  15       GND                     
                                  16       M_L_DQ<9>               
                                  17       GND                     
                                  18       M_L_DQS_DP<10>          
                                  19       M_L_DQS_DN<10>          
                                  20       GND                     
                                  21       M_L_DQ<15>              
                                  22       GND                     
                                  23       M_L_DQ<11>              
                                  24       GND                     
                                  25       M_L_DQ<21>              
                                  26       GND                     
                                  27       M_L_DQ<17>              
                                  28       GND                     
                                  29       M_L_DQS_DP<11>          
                                  30       M_L_DQS_DN<11>          
                                  31       GND                     
                                  32       M_L_DQ<23>              
                                  33       GND                     
                                  34       M_L_DQ<19>              
                                  35       GND                     
                                  36       M_L_DQ<29>              
                                  37       GND                     
                                  38       M_L_DQ<25>              
                                  39       GND                     
                                  40       M_L_DQS_DP<12>          
                                  41       M_L_DQS_DN<12>          
                                  42       GND                     
                                  43       M_L_DQ<31>              
                                  44       GND                     
                                  45       M_L_DQ<27>              
                                  46       GND                     
                                  47       M_L_ECC<5>              
                                  48       GND                     
                                  49       M_L_ECC<1>              
                                  50       GND                     
                                  51       M_L_DQS_DP<17>          
                                  52       M_L_DQS_DN<17>          
                                  53       GND                     
                                  54       M_L_ECC<7>              
                                  55       GND                     
                                  56       M_L_ECC<3>              
                                  57       GND                     
                                  58       M_KLM_RST_N             
                                  59       PVDDQ_KLM               
                                  60       M_L_CKE<0>              
                                  61       PVDDQ_KLM               
                                  62       M_L_ACT_N               
                                  63       M_L_BG<0>               
                                  64       PVDDQ_KLM               
                                  65       M_L_MA<12>              
                                  66       M_L_MA<9>               
                                  67       PVDDQ_KLM               
                                  68       M_L_MA<8>               
                                  69       M_L_MA<6>               
                                  70       PVDDQ_KLM               
                                  71       M_L_MA<3>               
                                  72       M_L_MA<1>               
                                  73       PVDDQ_KLM               
                                  74       M_L_CLK_DP<0>           
                                  75       M_L_CLK_DN<0>           
                                  76       PVDDQ_KLM               
                                  77       PVTT_KLM                
                                  78       FM_DIMM_EVENT_COD_N     
                                  79       M_L_MA<0>               
                                  80       PVDDQ_KLM               
                                  81       M_L_BA<0>               
                                  82       M_L_MA<16>              
                                  83       PVDDQ_KLM               
                                  84       M_L_CS_N<0>             
                                  85       PVDDQ_KLM               
                                  86       M_L_MA<15>              
                                  87       M_L_ODT<0>              
                                  88       PVDDQ_KLM               
                                  89       M_L_CS_N<1>             
                                  90       PVDDQ_KLM               
                                  91       M_L_ODT<1>              
                                  92       PVDDQ_KLM               
                                  93       M_L_CS_N<2>             
                                  94       GND                     
                                  95       M_L_DQ<37>              
                                  96       GND                     
                                  97       M_L_DQ<33>              
                                  98       GND                     
                                  99       M_L_DQS_DP<13>          
                                  100      M_L_DQS_DN<13>          
                                  101      GND                     
                                  102      M_L_DQ<39>              
                                  103      GND                     
                                  104      M_L_DQ<35>              
                                  105      GND                     
                                  106      M_L_DQ<45>              
                                  107      GND                     
                                  108      M_L_DQ<41>              
                                  109      GND                     
                                  110      M_L_DQS_DP<14>          
                                  111      M_L_DQS_DN<14>          
                                  112      GND                     
                                  113      M_L_DQ<47>              
                                  114      GND                     
                                  115      M_L_DQ<43>              
                                  116      GND                     
                                  117      M_L_DQ<53>              
                                  118      GND                     
                                  119      M_L_DQ<49>              
                                  120      GND                     
                                  121      M_L_DQS_DP<15>          
                                  122      M_L_DQS_DN<15>          
                                  123      GND                     
                                  124      M_L_DQ<55>              
                                  125      GND                     
                                  126      M_L_DQ<51>              
                                  127      GND                     
                                  128      M_L_DQ<61>              
                                  129      GND                     
                                  130      M_L_DQ<57>              
                                  131      GND                     
                                  132      M_L_DQS_DP<16>          
                                  133      M_L_DQS_DN<16>          
                                  134      GND                     
                                  135      M_L_DQ<63>              
                                  136      GND                     
                                  137      M_L_DQ<59>              
                                  138      GND                     
                                  139      GND                     
                                  140      PVPP_KLM                
                                  141      SMB_DDR_KLM_VPP_SCL     
                                  142      PVPP_KLM                
                                  143      PVPP_KLM                
                                  144      TP_CH_L_DIMM_L0_RFU_2   
                                  145      P12V_NVDIMM_KLM         
                                  146      M_L_VREF                
                                  147      GND                     
                                  148      M_L_DQ<4>               
                                  149      GND                     
                                  150      M_L_DQ<0>               
                                  151      GND                     
                                  152      M_L_DQS_DN<0>           
                                  153      M_L_DQS_DP<0>           
                                  154      GND                     
                                  155      M_L_DQ<6>               
                                  156      GND                     
                                  157      M_L_DQ<2>               
                                  158      GND                     
                                  159      M_L_DQ<12>              
                                  160      GND                     
                                  161      M_L_DQ<8>               
                                  162      GND                     
                                  163      M_L_DQS_DN<1>           
                                  164      M_L_DQS_DP<1>           
                                  165      GND                     
                                  166      M_L_DQ<14>              
                                  167      GND                     
                                  168      M_L_DQ<10>              
                                  169      GND                     
                                  170      M_L_DQ<20>              
                                  171      GND                     
                                  172      M_L_DQ<16>              
                                  173      GND                     
                                  174      M_L_DQS_DN<2>           
                                  175      M_L_DQS_DP<2>           
                                  176      GND                     
                                  177      M_L_DQ<22>              
                                  178      GND                     
                                  179      M_L_DQ<18>              
                                  180      GND                     
                                  181      M_L_DQ<28>              
                                  182      GND                     
                                  183      M_L_DQ<24>              
                                  184      GND                     
                                  185      M_L_DQS_DN<3>           
                                  186      M_L_DQS_DP<3>           
                                  187      GND                     
                                  188      M_L_DQ<30>              
                                  189      GND                     
                                  190      M_L_DQ<26>              
                                  191      GND                     
                                  192      M_L_ECC<4>              
                                  193      GND                     
                                  194      M_L_ECC<0>              
                                  195      GND                     
                                  196      M_L_DQS_DN<8>           
                                  197      M_L_DQS_DP<8>           
                                  198      GND                     
                                  199      M_L_ECC<6>              
                                  200      GND                     
                                  201      M_L_ECC<2>              
                                  202      GND                     
                                  203      M_L_CKE<1>              
                                  204      PVDDQ_KLM               
                                  205      TP_CH_L_DIMM_L0_RFU_0   
                                  206      PVDDQ_KLM               
                                  207      M_L_BG<1>               
                                  208      M_L_ALERT_N             
                                  209      PVDDQ_KLM               
                                  210      M_L_MA<11>              
                                  211      M_L_MA<7>               
                                  212      PVDDQ_KLM               
                                  213      M_L_MA<5>               
                                  214      M_L_MA<4>               
                                  215      PVDDQ_KLM               
                                  216      M_L_MA<2>               
                                  217      PVDDQ_KLM               
                                  218      M_L_CLK_DP<1>           
                                  219      M_L_CLK_DN<1>           
                                  220      PVDDQ_KLM               
                                  221      PVTT_KLM                
                                  222      M_L_PAR                 
                                  223      PVDDQ_KLM               
                                  224      M_L_BA<1>               
                                  225      M_L_MA<10>              
                                  226      PVDDQ_KLM               
                                  227      TP_CH_L_DIMM_L0_RFU_1   
                                  228      M_L_MA<14>              
                                  229      PVDDQ_KLM               
                                  230      FM_ADR_COMPLETE_KLM_N   
                                  231      PVDDQ_KLM               
                                  232      M_L_MA<13>              
                                  233      PVDDQ_KLM               
                                  234      M_L_MA<17>              
                                  235      M_L_C<2>                
                                  236      PVDDQ_KLM               
                                  237      M_L_CS_N<3>             
                                  238      GND                     
                                  239      GND                     
                                  240      M_L_DQ<36>              
                                  241      GND                     
                                  242      M_L_DQ<32>              
                                  243      GND                     
                                  244      M_L_DQS_DN<4>           
                                  245      M_L_DQS_DP<4>           
                                  246      GND                     
                                  247      M_L_DQ<38>              
                                  248      GND                     
                                  249      M_L_DQ<34>              
                                  250      GND                     
                                  251      M_L_DQ<44>              
                                  252      GND                     
                                  253      M_L_DQ<40>              
                                  254      GND                     
                                  255      M_L_DQS_DN<5>           
                                  256      M_L_DQS_DP<5>           
                                  257      GND                     
                                  258      M_L_DQ<46>              
                                  259      GND                     
                                  260      M_L_DQ<42>              
                                  261      GND                     
                                  262      M_L_DQ<52>              
                                  263      GND                     
                                  264      M_L_DQ<48>              
                                  265      GND                     
                                  266      M_L_DQS_DN<6>           
                                  267      M_L_DQS_DP<6>           
                                  268      GND                     
                                  269      M_L_DQ<54>              
                                  270      GND                     
                                  271      M_L_DQ<50>              
                                  272      GND                     
                                  273      M_L_DQ<60>              
                                  274      GND                     
                                  275      M_L_DQ<56>              
                                  276      GND                     
                                  277      M_L_DQS_DN<7>           
                                  278      M_L_DQS_DP<7>           
                                  279      GND                     
                                  280      M_L_DQ<62>              
                                  281      GND                     
                                  282      M_L_DQ<58>              
                                  283      GND                     
                                  284      PVPP_KLM                
                                  285      SMB_DDR_KLM_VPP_SDA     
                                  286      PVPP_KLM                
                                  287      PVPP_KLM                
                                  288      PVPP_KLM                
J1B1             SCONN288_H44441004_PIP-SCONN,HA 1        P12V_NVDIMM_KLM         
                                  2        GND                     
                                  3        M_K_DQ<5>               
                                  4        GND                     
                                  5        M_K_DQ<1>               
                                  6        GND                     
                                  7        M_K_DQS_DP<9>           
                                  8        M_K_DQS_DN<9>           
                                  9        GND                     
                                  10       M_K_DQ<7>               
                                  11       GND                     
                                  12       M_K_DQ<3>               
                                  13       GND                     
                                  14       M_K_DQ<13>              
                                  15       GND                     
                                  16       M_K_DQ<9>               
                                  17       GND                     
                                  18       M_K_DQS_DP<10>          
                                  19       M_K_DQS_DN<10>          
                                  20       GND                     
                                  21       M_K_DQ<15>              
                                  22       GND                     
                                  23       M_K_DQ<11>              
                                  24       GND                     
                                  25       M_K_DQ<21>              
                                  26       GND                     
                                  27       M_K_DQ<17>              
                                  28       GND                     
                                  29       M_K_DQS_DP<11>          
                                  30       M_K_DQS_DN<11>          
                                  31       GND                     
                                  32       M_K_DQ<23>              
                                  33       GND                     
                                  34       M_K_DQ<19>              
                                  35       GND                     
                                  36       M_K_DQ<29>              
                                  37       GND                     
                                  38       M_K_DQ<25>              
                                  39       GND                     
                                  40       M_K_DQS_DP<12>          
                                  41       M_K_DQS_DN<12>          
                                  42       GND                     
                                  43       M_K_DQ<31>              
                                  44       GND                     
                                  45       M_K_DQ<27>              
                                  46       GND                     
                                  47       M_K_ECC<5>              
                                  48       GND                     
                                  49       M_K_ECC<1>              
                                  50       GND                     
                                  51       M_K_DQS_DP<17>          
                                  52       M_K_DQS_DN<17>          
                                  53       GND                     
                                  54       M_K_ECC<7>              
                                  55       GND                     
                                  56       M_K_ECC<3>              
                                  57       GND                     
                                  58       M_KLM_RST_N             
                                  59       PVDDQ_KLM               
                                  60       M_K_CKE<0>              
                                  61       PVDDQ_KLM               
                                  62       M_K_ACT_N               
                                  63       M_K_BG<0>               
                                  64       PVDDQ_KLM               
                                  65       M_K_MA<12>              
                                  66       M_K_MA<9>               
                                  67       PVDDQ_KLM               
                                  68       M_K_MA<8>               
                                  69       M_K_MA<6>               
                                  70       PVDDQ_KLM               
                                  71       M_K_MA<3>               
                                  72       M_K_MA<1>               
                                  73       PVDDQ_KLM               
                                  74       M_K_CLK_DP<0>           
                                  75       M_K_CLK_DN<0>           
                                  76       PVDDQ_KLM               
                                  77       PVTT_KLM                
                                  78       FM_DIMM_EVENT_COD_N     
                                  79       M_K_MA<0>               
                                  80       PVDDQ_KLM               
                                  81       M_K_BA<0>               
                                  82       M_K_MA<16>              
                                  83       PVDDQ_KLM               
                                  84       M_K_CS_N<0>             
                                  85       PVDDQ_KLM               
                                  86       M_K_MA<15>              
                                  87       M_K_ODT<0>              
                                  88       PVDDQ_KLM               
                                  89       M_K_CS_N<1>             
                                  90       PVDDQ_KLM               
                                  91       M_K_ODT<1>              
                                  92       PVDDQ_KLM               
                                  93       M_K_CS_N<2>             
                                  94       GND                     
                                  95       M_K_DQ<37>              
                                  96       GND                     
                                  97       M_K_DQ<33>              
                                  98       GND                     
                                  99       M_K_DQS_DP<13>          
                                  100      M_K_DQS_DN<13>          
                                  101      GND                     
                                  102      M_K_DQ<39>              
                                  103      GND                     
                                  104      M_K_DQ<35>              
                                  105      GND                     
                                  106      M_K_DQ<45>              
                                  107      GND                     
                                  108      M_K_DQ<41>              
                                  109      GND                     
                                  110      M_K_DQS_DP<14>          
                                  111      M_K_DQS_DN<14>          
                                  112      GND                     
                                  113      M_K_DQ<47>              
                                  114      GND                     
                                  115      M_K_DQ<43>              
                                  116      GND                     
                                  117      M_K_DQ<53>              
                                  118      GND                     
                                  119      M_K_DQ<49>              
                                  120      GND                     
                                  121      M_K_DQS_DP<15>          
                                  122      M_K_DQS_DN<15>          
                                  123      GND                     
                                  124      M_K_DQ<55>              
                                  125      GND                     
                                  126      M_K_DQ<51>              
                                  127      GND                     
                                  128      M_K_DQ<61>              
                                  129      GND                     
                                  130      M_K_DQ<57>              
                                  131      GND                     
                                  132      M_K_DQS_DP<16>          
                                  133      M_K_DQS_DN<16>          
                                  134      GND                     
                                  135      M_K_DQ<63>              
                                  136      GND                     
                                  137      M_K_DQ<59>              
                                  138      GND                     
                                  139      GND                     
                                  140      GND                     
                                  141      SMB_DDR_KLM_VPP_SCL     
                                  142      PVPP_KLM                
                                  143      PVPP_KLM                
                                  144      TP_CH_K_DIMM_K0_RFU_2   
                                  145      P12V_NVDIMM_KLM         
                                  146      M_K_VREF                
                                  147      GND                     
                                  148      M_K_DQ<4>               
                                  149      GND                     
                                  150      M_K_DQ<0>               
                                  151      GND                     
                                  152      M_K_DQS_DN<0>           
                                  153      M_K_DQS_DP<0>           
                                  154      GND                     
                                  155      M_K_DQ<6>               
                                  156      GND                     
                                  157      M_K_DQ<2>               
                                  158      GND                     
                                  159      M_K_DQ<12>              
                                  160      GND                     
                                  161      M_K_DQ<8>               
                                  162      GND                     
                                  163      M_K_DQS_DN<1>           
                                  164      M_K_DQS_DP<1>           
                                  165      GND                     
                                  166      M_K_DQ<14>              
                                  167      GND                     
                                  168      M_K_DQ<10>              
                                  169      GND                     
                                  170      M_K_DQ<20>              
                                  171      GND                     
                                  172      M_K_DQ<16>              
                                  173      GND                     
                                  174      M_K_DQS_DN<2>           
                                  175      M_K_DQS_DP<2>           
                                  176      GND                     
                                  177      M_K_DQ<22>              
                                  178      GND                     
                                  179      M_K_DQ<18>              
                                  180      GND                     
                                  181      M_K_DQ<28>              
                                  182      GND                     
                                  183      M_K_DQ<24>              
                                  184      GND                     
                                  185      M_K_DQS_DN<3>           
                                  186      M_K_DQS_DP<3>           
                                  187      GND                     
                                  188      M_K_DQ<30>              
                                  189      GND                     
                                  190      M_K_DQ<26>              
                                  191      GND                     
                                  192      M_K_ECC<4>              
                                  193      GND                     
                                  194      M_K_ECC<0>              
                                  195      GND                     
                                  196      M_K_DQS_DN<8>           
                                  197      M_K_DQS_DP<8>           
                                  198      GND                     
                                  199      M_K_ECC<6>              
                                  200      GND                     
                                  201      M_K_ECC<2>              
                                  202      GND                     
                                  203      M_K_CKE<1>              
                                  204      PVDDQ_KLM               
                                  205      TP_CH_K_DIMM_K0_RFU_0   
                                  206      PVDDQ_KLM               
                                  207      M_K_BG<1>               
                                  208      M_K_ALERT_N             
                                  209      PVDDQ_KLM               
                                  210      M_K_MA<11>              
                                  211      M_K_MA<7>               
                                  212      PVDDQ_KLM               
                                  213      M_K_MA<5>               
                                  214      M_K_MA<4>               
                                  215      PVDDQ_KLM               
                                  216      M_K_MA<2>               
                                  217      PVDDQ_KLM               
                                  218      M_K_CLK_DP<1>           
                                  219      M_K_CLK_DN<1>           
                                  220      PVDDQ_KLM               
                                  221      PVTT_KLM                
                                  222      M_K_PAR                 
                                  223      PVDDQ_KLM               
                                  224      M_K_BA<1>               
                                  225      M_K_MA<10>              
                                  226      PVDDQ_KLM               
                                  227      TP_CH_K_DIMM_K0_RFU_1   
                                  228      M_K_MA<14>              
                                  229      PVDDQ_KLM               
                                  230      FM_ADR_COMPLETE_KLM_N   
                                  231      PVDDQ_KLM               
                                  232      M_K_MA<13>              
                                  233      PVDDQ_KLM               
                                  234      M_K_MA<17>              
                                  235      M_K_C<2>                
                                  236      PVDDQ_KLM               
                                  237      M_K_CS_N<3>             
                                  238      GND                     
                                  239      GND                     
                                  240      M_K_DQ<36>              
                                  241      GND                     
                                  242      M_K_DQ<32>              
                                  243      GND                     
                                  244      M_K_DQS_DN<4>           
                                  245      M_K_DQS_DP<4>           
                                  246      GND                     
                                  247      M_K_DQ<38>              
                                  248      GND                     
                                  249      M_K_DQ<34>              
                                  250      GND                     
                                  251      M_K_DQ<44>              
                                  252      GND                     
                                  253      M_K_DQ<40>              
                                  254      GND                     
                                  255      M_K_DQS_DN<5>           
                                  256      M_K_DQS_DP<5>           
                                  257      GND                     
                                  258      M_K_DQ<46>              
                                  259      GND                     
                                  260      M_K_DQ<42>              
                                  261      GND                     
                                  262      M_K_DQ<52>              
                                  263      GND                     
                                  264      M_K_DQ<48>              
                                  265      GND                     
                                  266      M_K_DQS_DN<6>           
                                  267      M_K_DQS_DP<6>           
                                  268      GND                     
                                  269      M_K_DQ<54>              
                                  270      GND                     
                                  271      M_K_DQ<50>              
                                  272      GND                     
                                  273      M_K_DQ<60>              
                                  274      GND                     
                                  275      M_K_DQ<56>              
                                  276      GND                     
                                  277      M_K_DQS_DN<7>           
                                  278      M_K_DQS_DP<7>           
                                  279      GND                     
                                  280      M_K_DQ<62>              
                                  281      GND                     
                                  282      M_K_DQ<58>              
                                  283      GND                     
                                  284      PVPP_KLM                
                                  285      SMB_DDR_KLM_VPP_SDA     
                                  286      PVPP_KLM                
                                  287      PVPP_KLM                
                                  288      PVPP_KLM                
J1B2             CONN6_C74770005_PIP-HDR,C74770A 1        GND                     
                                  2        P12V_FAN                
                                  3        FAN_TACH2_CPU1_D1       
                                  4        FAN_PWM_OUT_SYS1_R      
                                  5        FAN_TACH3_CPU1_D1       
                                  6        TP_FAN_1                
J1B3             CONN3_C95678002_PIP-CONN,C9567A 1        A_HSC_HIGH_EN           
                                  2        A_HSC_OCP_SEL           
                                  3        A_HSC_LOW_EN            
J1B4             SCONN3_D53458001_SM-EMPTY,D534A 1        A_HSC_HIGH_EN           
                                  2        A_HSC_OCP_SEL           
                                  3        A_HSC_LOW_EN            
J1C1             CONN76_H22707001_THMT1-CONN,H2A A1       P3E_CPU1_PE3_MP_RXN<8>  
                                  A2       GND                     
                                  A3       P3E_CPU1_PE3_MP_RXP<14> 
                                  A4       GND                     
                                  A5       TP_IOA5                 
                                  A6       GND                     
                                  A7       P3E_CPU1_PE3_MP_C_TXN<11>
                                  A8       GND                     
                                  B1       P3E_CPU1_PE3_MP_RXP<8>  
                                  B2       P3E_CPU1_PE3_MP_RXN<11> 
                                  B3       P3E_CPU1_PE3_MP_RXN<14> 
                                  B4       TP_FM_WAKE_N            
                                  B5       IRQ_BOARD_BMC_ALERT_N   
                                  B6       SMB_PEHPCPU1_STBY_LVC3_SDA
                                  B7       P3E_CPU1_PE3_MP_C_TXP<11>
                                  B8       P3E_CPU1_PE3_MP_C_TXN<8>
                                  C1       GND                     
                                  C2       P3E_CPU1_PE3_MP_RXP<11> 
                                  C3       GND                     
                                  C4       FM_BB_BMC_MP_GPIO       
                                  C5       GND                     
                                  C6       SMB_PEHPCPU1_STBY_LVC3_SCL
                                  C7       GND                     
                                  C8       P3E_CPU1_PE3_MP_C_TXP<8>
                                  D1       P3E_CPU1_PE3_MP_RXN<9>  
                                  D2       GND                     
                                  D3       P3E_CPU1_PE3_MP_RXN<15> 
                                  D4       GND                     
                                  D5       SMB_LAN_STBY_LVC3_SDA   
                                  D6       GND                     
                                  D7       P3E_CPU1_PE3_MP_C_TXN<12>
                                  D8       GND                     
                                  E1       P3E_CPU1_PE3_MP_RXP<9>  
                                  E2       P3E_CPU1_PE3_MP_RXN<12> 
                                  E3       P3E_CPU1_PE3_MP_RXP<15> 
                                  E4       TP_IOE4                 
                                  E5       SMB_LAN_STBY_LVC3_SCL   
                                  E6       P3E_CPU1_PE3_MP_C_TXN<14>
                                  E7       P3E_CPU1_PE3_MP_C_TXP<12>
                                  E8       P3E_CPU1_PE3_MP_C_TXN<9>
                                  F1       GND                     
                                  F2       P3E_CPU1_PE3_MP_RXP<12> 
                                  F3       GND                     
                                  F4       TP_IOF4                 
                                  F5       GND                     
                                  F6       P3E_CPU1_PE3_MP_C_TXP<14>
                                  F7       GND                     
                                  F8       P3E_CPU1_PE3_MP_C_TXP<9>
                                  G1       P3E_CPU1_PE3_MP_RXP<10> 
                                  G2       GND                     
                                  G3       TP_IOG3                 
                                  G4       GND                     
                                  G5       FM_XRC_PRESENT_N        
                                  G6       GND                     
                                  G7       P3E_CPU1_PE3_MP_C_TXN<13>
                                  G8       GND                     
                                  H1       P3E_CPU1_PE3_MP_RXN<10> 
                                  H2       P3E_CPU1_PE3_MP_RXP<13> 
                                  H3       TP_IOH3                 
                                  H4       TP_IOH4                 
                                  H5       FM_XRC_READY_N          
                                  H6       P3E_CPU1_PE3_MP_C_TXN<15>
                                  H7       P3E_CPU1_PE3_MP_C_TXP<13>
                                  H8       P3E_CPU1_PE3_MP_C_TXP<10>
                                  I1       GND                     
                                  I2       P3E_CPU1_PE3_MP_RXN<13> 
                                  I3       GND                     
                                  I4       TP_IOI4                 
                                  I5       GND                     
                                  I6       P3E_CPU1_PE3_MP_C_TXP<15>
                                  I7       GND                     
                                  I8       P3E_CPU1_PE3_MP_C_TXN<10>
                                  J2       GND                     
                                  J4       GND                     
                                  J6       GND                     
                                  J8       GND                     
J1D1             CONN12_G98257001_THMT-CONN,G98A A1       P12V_PSU                
                                  A2       P12V_PSU                
                                  A3       P12V_PSU                
                                  B1       P12V_PSU                
                                  B2       P12V_PSU                
                                  B3       P12V_PSU                
                                  C1       GND                     
                                  C2       GND                     
                                  C3       GND                     
                                  D1       GND                     
                                  D2       GND                     
                                  D3       GND                     
J1E1             CONN12_G98257001_THMT-CONN,G98A A1       P12V_PSU                
                                  A2       P12V_PSU                
                                  A3       P12V_PSU                
                                  B1       P12V_PSU                
                                  B2       P12V_PSU                
                                  B3       P12V_PSU                
                                  C1       GND                     
                                  C2       GND                     
                                  C3       GND                     
                                  D1       GND                     
                                  D2       GND                     
                                  D3       GND                     
J1F1             CONN76_H22707001_THMT1-CONN,H2A A1       P3E_CPU1_PE3_MP_RXN<0>  
                                  A2       GND                     
                                  A3       P3E_CPU1_PE3_MP_RXP<6>  
                                  A4       FAN_TACH3_R             
                                  A5       NIC_MDI_MNG_TX_DP       
                                  A6       IRQ_SML1_PMBUS_ALERT_R_N
                                  A7       P3E_CPU1_PE3_MP_C_TXN<3>
                                  A8       GND                     
                                  B1       P3E_CPU1_PE3_MP_RXP<0>  
                                  B2       P3E_CPU1_PE3_MP_RXN<3>  
                                  B3       P3E_CPU1_PE3_MP_RXN<6>  
                                  B4       FAN_TACH2_R             
                                  B5       NIC_MDI_MNG_TX_DN       
                                  B6       SMB_BMC_PMBUS_STBY_LVC3_SDA
                                  B7       P3E_CPU1_PE3_MP_C_TXP<3>
                                  B8       P3E_CPU1_PE3_MP_C_TXN<0>
                                  C1       GND                     
                                  C2       P3E_CPU1_PE3_MP_RXP<3>  
                                  C3       GND                     
                                  C4       FAN_TACH1_R             
                                  C5       GND                     
                                  C6       SMB_BMC_PMBUS_STBY_LVC3_SCL
                                  C7       GND                     
                                  C8       P3E_CPU1_PE3_MP_C_TXP<0>
                                  D1       P3E_CPU1_PE3_MP_RXN<1>  
                                  D2       GND                     
                                  D3       P3E_CPU1_PE3_MP_RXN<7>  
                                  D4       FAN_TACH0_R             
                                  D5       NIC_MDI_MNG_RX_DP       
                                  D6       GND                     
                                  D7       P3E_CPU1_PE3_MP_C_TXN<4>
                                  D8       GND                     
                                  E1       P3E_CPU1_PE3_MP_RXP<1>  
                                  E2       P3E_CPU1_PE3_MP_RXN<4>  
                                  E3       P3E_CPU1_PE3_MP_RXP<7>  
                                  E4       FM_MATED_IN_N           
                                  E5       NIC_MDI_MNG_RX_DN       
                                  E6       P3E_CPU1_PE3_MP_C_TXN<6>
                                  E7       P3E_CPU1_PE3_MP_C_TXP<4>
                                  E8       P3E_CPU1_PE3_MP_C_TXN<1>
                                  F1       GND                     
                                  F2       P3E_CPU1_PE3_MP_RXP<4>  
                                  F3       GND                     
                                  F4       FAN_PWM_OUT_SYS0_R1     
                                  F5       FM_MB_SLOT_ID0          
                                  F6       P3E_CPU1_PE3_MP_C_TXP<6>
                                  F7       GND                     
                                  F8       P3E_CPU1_PE3_MP_C_TXP<1>
                                  G1       P3E_CPU1_PE3_MP_RXP<2>  
                                  G2       GND                     
                                  G3       SPA_MID_DBG_TX_R        
                                  G4       GND                     
                                  G5       FM_MB_SLOT_ID1          
                                  G6       GND                     
                                  G7       P3E_CPU1_PE3_MP_C_TXP<5>
                                  G8       GND                     
                                  H1       P3E_CPU1_PE3_MP_RXN<2>  
                                  H2       P3E_CPU1_PE3_MP_RXP<5>  
                                  H3       SPA_MID_DBG_RX_R        
                                  H4       CLK_100M_AIRMAX8_PE1_DP 
                                  H5       FM_MB_SLOT_ID2          
                                  H6       P3E_CPU1_PE3_MP_C_TXP<7>
                                  H7       P3E_CPU1_PE3_MP_C_TXN<5>
                                  H8       P3E_CPU1_PE3_MP_C_TXN<2>
                                  I1       GND                     
                                  I2       P3E_CPU1_PE3_MP_RXN<5>  
                                  I3       FM_ENABLE_FAN_POWER     
                                  I4       CLK_100M_AIRMAX8_PE1_DN 
                                  I5       RST_PCIE_MIDPLANE_N     
                                  I6       P3E_CPU1_PE3_MP_C_TXN<7>
                                  I7       GND                     
                                  I8       P3E_CPU1_PE3_MP_C_TXP<2>
                                  J2       GND                     
                                  J4       GND                     
                                  J6       GND                     
                                  J8       GND                     
J1F2             CONN6_C74770005_PIP-HDR,C74770A 1        GND                     
                                  2        P12V_FAN                
                                  3        FAN_TACH0_CPU0_D1       
                                  4        FAN_PWM_OUT_SYS0_R      
                                  5        FAN_TACH1_CPU1_D1       
                                  6        TP_FAN_0                
J1F3             CONN8_H62179001_PIP-CONN,H6217A 1        P3V3_STBY               
                                  2        FM_MP_PS_REDUNDANT_LOST_N
                                  3        FM_MP_PS_FAIL_N         
                                  4        FM_MATED_IN_N           
                                  5        IRQ_SML1_PMBUS_ALERT_R_N
                                  6        SMB_BMC_PMBUS_STBY_LVC3_SDA
                                  7        SMB_BMC_PMBUS_STBY_LVC3_SCL
                                  8        GND                     
J1G1             SCONN288_H44441004_PIP-SCONN,HA 1        P12V_NVDIMM_GHJ         
                                  2        GND                     
                                  3        M_G_DQ<5>               
                                  4        GND                     
                                  5        M_G_DQ<1>               
                                  6        GND                     
                                  7        M_G_DQS_DP<9>           
                                  8        M_G_DQS_DN<9>           
                                  9        GND                     
                                  10       M_G_DQ<7>               
                                  11       GND                     
                                  12       M_G_DQ<3>               
                                  13       GND                     
                                  14       M_G_DQ<13>              
                                  15       GND                     
                                  16       M_G_DQ<9>               
                                  17       GND                     
                                  18       M_G_DQS_DP<10>          
                                  19       M_G_DQS_DN<10>          
                                  20       GND                     
                                  21       M_G_DQ<15>              
                                  22       GND                     
                                  23       M_G_DQ<11>              
                                  24       GND                     
                                  25       M_G_DQ<21>              
                                  26       GND                     
                                  27       M_G_DQ<17>              
                                  28       GND                     
                                  29       M_G_DQS_DP<11>          
                                  30       M_G_DQS_DN<11>          
                                  31       GND                     
                                  32       M_G_DQ<23>              
                                  33       GND                     
                                  34       M_G_DQ<19>              
                                  35       GND                     
                                  36       M_G_DQ<29>              
                                  37       GND                     
                                  38       M_G_DQ<25>              
                                  39       GND                     
                                  40       M_G_DQS_DP<12>          
                                  41       M_G_DQS_DN<12>          
                                  42       GND                     
                                  43       M_G_DQ<31>              
                                  44       GND                     
                                  45       M_G_DQ<27>              
                                  46       GND                     
                                  47       M_G_ECC<5>              
                                  48       GND                     
                                  49       M_G_ECC<1>              
                                  50       GND                     
                                  51       M_G_DQS_DP<17>          
                                  52       M_G_DQS_DN<17>          
                                  53       GND                     
                                  54       M_G_ECC<7>              
                                  55       GND                     
                                  56       M_G_ECC<3>              
                                  57       GND                     
                                  58       M_GHJ_RST_N             
                                  59       PVDDQ_GHJ               
                                  60       M_G_CKE<0>              
                                  61       PVDDQ_GHJ               
                                  62       M_G_ACT_N               
                                  63       M_G_BG<0>               
                                  64       PVDDQ_GHJ               
                                  65       M_G_MA<12>              
                                  66       M_G_MA<9>               
                                  67       PVDDQ_GHJ               
                                  68       M_G_MA<8>               
                                  69       M_G_MA<6>               
                                  70       PVDDQ_GHJ               
                                  71       M_G_MA<3>               
                                  72       M_G_MA<1>               
                                  73       PVDDQ_GHJ               
                                  74       M_G_CLK_DP<0>           
                                  75       M_G_CLK_DN<0>           
                                  76       PVDDQ_GHJ               
                                  77       PVTT_GHJ                
                                  78       FM_DIMM_EVENT_COD_N     
                                  79       M_G_MA<0>               
                                  80       PVDDQ_GHJ               
                                  81       M_G_BA<0>               
                                  82       M_G_MA<16>              
                                  83       PVDDQ_GHJ               
                                  84       M_G_CS_N<0>             
                                  85       PVDDQ_GHJ               
                                  86       M_G_MA<15>              
                                  87       M_G_ODT<0>              
                                  88       PVDDQ_GHJ               
                                  89       M_G_CS_N<1>             
                                  90       PVDDQ_GHJ               
                                  91       M_G_ODT<1>              
                                  92       PVDDQ_GHJ               
                                  93       M_G_CS_N<2>             
                                  94       GND                     
                                  95       M_G_DQ<37>              
                                  96       GND                     
                                  97       M_G_DQ<33>              
                                  98       GND                     
                                  99       M_G_DQS_DP<13>          
                                  100      M_G_DQS_DN<13>          
                                  101      GND                     
                                  102      M_G_DQ<39>              
                                  103      GND                     
                                  104      M_G_DQ<35>              
                                  105      GND                     
                                  106      M_G_DQ<45>              
                                  107      GND                     
                                  108      M_G_DQ<41>              
                                  109      GND                     
                                  110      M_G_DQS_DP<14>          
                                  111      M_G_DQS_DN<14>          
                                  112      GND                     
                                  113      M_G_DQ<47>              
                                  114      GND                     
                                  115      M_G_DQ<43>              
                                  116      GND                     
                                  117      M_G_DQ<53>              
                                  118      GND                     
                                  119      M_G_DQ<49>              
                                  120      GND                     
                                  121      M_G_DQS_DP<15>          
                                  122      M_G_DQS_DN<15>          
                                  123      GND                     
                                  124      M_G_DQ<55>              
                                  125      GND                     
                                  126      M_G_DQ<51>              
                                  127      GND                     
                                  128      M_G_DQ<61>              
                                  129      GND                     
                                  130      M_G_DQ<57>              
                                  131      GND                     
                                  132      M_G_DQS_DP<16>          
                                  133      M_G_DQS_DN<16>          
                                  134      GND                     
                                  135      M_G_DQ<63>              
                                  136      GND                     
                                  137      M_G_DQ<59>              
                                  138      GND                     
                                  139      GND                     
                                  140      GND                     
                                  141      SMB_DDR_GHJ_VPP_SCL     
                                  142      PVPP_GHJ                
                                  143      PVPP_GHJ                
                                  144      TP_CH_G_DIMM_G0_RFU_2   
                                  145      P12V_NVDIMM_GHJ         
                                  146      M_G_VREF                
                                  147      GND                     
                                  148      M_G_DQ<4>               
                                  149      GND                     
                                  150      M_G_DQ<0>               
                                  151      GND                     
                                  152      M_G_DQS_DN<0>           
                                  153      M_G_DQS_DP<0>           
                                  154      GND                     
                                  155      M_G_DQ<6>               
                                  156      GND                     
                                  157      M_G_DQ<2>               
                                  158      GND                     
                                  159      M_G_DQ<12>              
                                  160      GND                     
                                  161      M_G_DQ<8>               
                                  162      GND                     
                                  163      M_G_DQS_DN<1>           
                                  164      M_G_DQS_DP<1>           
                                  165      GND                     
                                  166      M_G_DQ<14>              
                                  167      GND                     
                                  168      M_G_DQ<10>              
                                  169      GND                     
                                  170      M_G_DQ<20>              
                                  171      GND                     
                                  172      M_G_DQ<16>              
                                  173      GND                     
                                  174      M_G_DQS_DN<2>           
                                  175      M_G_DQS_DP<2>           
                                  176      GND                     
                                  177      M_G_DQ<22>              
                                  178      GND                     
                                  179      M_G_DQ<18>              
                                  180      GND                     
                                  181      M_G_DQ<28>              
                                  182      GND                     
                                  183      M_G_DQ<24>              
                                  184      GND                     
                                  185      M_G_DQS_DN<3>           
                                  186      M_G_DQS_DP<3>           
                                  187      GND                     
                                  188      M_G_DQ<30>              
                                  189      GND                     
                                  190      M_G_DQ<26>              
                                  191      GND                     
                                  192      M_G_ECC<4>              
                                  193      GND                     
                                  194      M_G_ECC<0>              
                                  195      GND                     
                                  196      M_G_DQS_DN<8>           
                                  197      M_G_DQS_DP<8>           
                                  198      GND                     
                                  199      M_G_ECC<6>              
                                  200      GND                     
                                  201      M_G_ECC<2>              
                                  202      GND                     
                                  203      M_G_CKE<1>              
                                  204      PVDDQ_GHJ               
                                  205      TP_CH_G_DIMM_G0_RFU_0   
                                  206      PVDDQ_GHJ               
                                  207      M_G_BG<1>               
                                  208      M_G_ALERT_N             
                                  209      PVDDQ_GHJ               
                                  210      M_G_MA<11>              
                                  211      M_G_MA<7>               
                                  212      PVDDQ_GHJ               
                                  213      M_G_MA<5>               
                                  214      M_G_MA<4>               
                                  215      PVDDQ_GHJ               
                                  216      M_G_MA<2>               
                                  217      PVDDQ_GHJ               
                                  218      M_G_CLK_DP<1>           
                                  219      M_G_CLK_DN<1>           
                                  220      PVDDQ_GHJ               
                                  221      PVTT_GHJ                
                                  222      M_G_PAR                 
                                  223      PVDDQ_GHJ               
                                  224      M_G_BA<1>               
                                  225      M_G_MA<10>              
                                  226      PVDDQ_GHJ               
                                  227      TP_CH_G_DIMM_G0_RFU_1   
                                  228      M_G_MA<14>              
                                  229      PVDDQ_GHJ               
                                  230      FM_ADR_COMPLETE_GHJ_N   
                                  231      PVDDQ_GHJ               
                                  232      M_G_MA<13>              
                                  233      PVDDQ_GHJ               
                                  234      M_G_MA<17>              
                                  235      M_G_C<2>                
                                  236      PVDDQ_GHJ               
                                  237      M_G_CS_N<3>             
                                  238      GND                     
                                  239      GND                     
                                  240      M_G_DQ<36>              
                                  241      GND                     
                                  242      M_G_DQ<32>              
                                  243      GND                     
                                  244      M_G_DQS_DN<4>           
                                  245      M_G_DQS_DP<4>           
                                  246      GND                     
                                  247      M_G_DQ<38>              
                                  248      GND                     
                                  249      M_G_DQ<34>              
                                  250      GND                     
                                  251      M_G_DQ<44>              
                                  252      GND                     
                                  253      M_G_DQ<40>              
                                  254      GND                     
                                  255      M_G_DQS_DN<5>           
                                  256      M_G_DQS_DP<5>           
                                  257      GND                     
                                  258      M_G_DQ<46>              
                                  259      GND                     
                                  260      M_G_DQ<42>              
                                  261      GND                     
                                  262      M_G_DQ<52>              
                                  263      GND                     
                                  264      M_G_DQ<48>              
                                  265      GND                     
                                  266      M_G_DQS_DN<6>           
                                  267      M_G_DQS_DP<6>           
                                  268      GND                     
                                  269      M_G_DQ<54>              
                                  270      GND                     
                                  271      M_G_DQ<50>              
                                  272      GND                     
                                  273      M_G_DQ<60>              
                                  274      GND                     
                                  275      M_G_DQ<56>              
                                  276      GND                     
                                  277      M_G_DQS_DN<7>           
                                  278      M_G_DQS_DP<7>           
                                  279      GND                     
                                  280      M_G_DQ<62>              
                                  281      GND                     
                                  282      M_G_DQ<58>              
                                  283      GND                     
                                  284      PVPP_GHJ                
                                  285      SMB_DDR_GHJ_VPP_SDA     
                                  286      PVPP_GHJ                
                                  287      PVPP_GHJ                
                                  288      PVPP_GHJ                
J1G2             SCONN288_H44441004_PIP-SCONN,HA 1        P12V_NVDIMM_GHJ         
                                  2        GND                     
                                  3        M_H_DQ<5>               
                                  4        GND                     
                                  5        M_H_DQ<1>               
                                  6        GND                     
                                  7        M_H_DQS_DP<9>           
                                  8        M_H_DQS_DN<9>           
                                  9        GND                     
                                  10       M_H_DQ<7>               
                                  11       GND                     
                                  12       M_H_DQ<3>               
                                  13       GND                     
                                  14       M_H_DQ<13>              
                                  15       GND                     
                                  16       M_H_DQ<9>               
                                  17       GND                     
                                  18       M_H_DQS_DP<10>          
                                  19       M_H_DQS_DN<10>          
                                  20       GND                     
                                  21       M_H_DQ<15>              
                                  22       GND                     
                                  23       M_H_DQ<11>              
                                  24       GND                     
                                  25       M_H_DQ<21>              
                                  26       GND                     
                                  27       M_H_DQ<17>              
                                  28       GND                     
                                  29       M_H_DQS_DP<11>          
                                  30       M_H_DQS_DN<11>          
                                  31       GND                     
                                  32       M_H_DQ<23>              
                                  33       GND                     
                                  34       M_H_DQ<19>              
                                  35       GND                     
                                  36       M_H_DQ<29>              
                                  37       GND                     
                                  38       M_H_DQ<25>              
                                  39       GND                     
                                  40       M_H_DQS_DP<12>          
                                  41       M_H_DQS_DN<12>          
                                  42       GND                     
                                  43       M_H_DQ<31>              
                                  44       GND                     
                                  45       M_H_DQ<27>              
                                  46       GND                     
                                  47       M_H_ECC<5>              
                                  48       GND                     
                                  49       M_H_ECC<1>              
                                  50       GND                     
                                  51       M_H_DQS_DP<17>          
                                  52       M_H_DQS_DN<17>          
                                  53       GND                     
                                  54       M_H_ECC<7>              
                                  55       GND                     
                                  56       M_H_ECC<3>              
                                  57       GND                     
                                  58       M_GHJ_RST_N             
                                  59       PVDDQ_GHJ               
                                  60       M_H_CKE<0>              
                                  61       PVDDQ_GHJ               
                                  62       M_H_ACT_N               
                                  63       M_H_BG<0>               
                                  64       PVDDQ_GHJ               
                                  65       M_H_MA<12>              
                                  66       M_H_MA<9>               
                                  67       PVDDQ_GHJ               
                                  68       M_H_MA<8>               
                                  69       M_H_MA<6>               
                                  70       PVDDQ_GHJ               
                                  71       M_H_MA<3>               
                                  72       M_H_MA<1>               
                                  73       PVDDQ_GHJ               
                                  74       M_H_CLK_DP<0>           
                                  75       M_H_CLK_DN<0>           
                                  76       PVDDQ_GHJ               
                                  77       PVTT_GHJ                
                                  78       FM_DIMM_EVENT_COD_N     
                                  79       M_H_MA<0>               
                                  80       PVDDQ_GHJ               
                                  81       M_H_BA<0>               
                                  82       M_H_MA<16>              
                                  83       PVDDQ_GHJ               
                                  84       M_H_CS_N<0>             
                                  85       PVDDQ_GHJ               
                                  86       M_H_MA<15>              
                                  87       M_H_ODT<0>              
                                  88       PVDDQ_GHJ               
                                  89       M_H_CS_N<1>             
                                  90       PVDDQ_GHJ               
                                  91       M_H_ODT<1>              
                                  92       PVDDQ_GHJ               
                                  93       M_H_CS_N<2>             
                                  94       GND                     
                                  95       M_H_DQ<37>              
                                  96       GND                     
                                  97       M_H_DQ<33>              
                                  98       GND                     
                                  99       M_H_DQS_DP<13>          
                                  100      M_H_DQS_DN<13>          
                                  101      GND                     
                                  102      M_H_DQ<39>              
                                  103      GND                     
                                  104      M_H_DQ<35>              
                                  105      GND                     
                                  106      M_H_DQ<45>              
                                  107      GND                     
                                  108      M_H_DQ<41>              
                                  109      GND                     
                                  110      M_H_DQS_DP<14>          
                                  111      M_H_DQS_DN<14>          
                                  112      GND                     
                                  113      M_H_DQ<47>              
                                  114      GND                     
                                  115      M_H_DQ<43>              
                                  116      GND                     
                                  117      M_H_DQ<53>              
                                  118      GND                     
                                  119      M_H_DQ<49>              
                                  120      GND                     
                                  121      M_H_DQS_DP<15>          
                                  122      M_H_DQS_DN<15>          
                                  123      GND                     
                                  124      M_H_DQ<55>              
                                  125      GND                     
                                  126      M_H_DQ<51>              
                                  127      GND                     
                                  128      M_H_DQ<61>              
                                  129      GND                     
                                  130      M_H_DQ<57>              
                                  131      GND                     
                                  132      M_H_DQS_DP<16>          
                                  133      M_H_DQS_DN<16>          
                                  134      GND                     
                                  135      M_H_DQ<63>              
                                  136      GND                     
                                  137      M_H_DQ<59>              
                                  138      GND                     
                                  139      GND                     
                                  140      PVPP_GHJ                
                                  141      SMB_DDR_GHJ_VPP_SCL     
                                  142      PVPP_GHJ                
                                  143      PVPP_GHJ                
                                  144      TP_CH_H_DIMM_H0_RFU_2   
                                  145      P12V_NVDIMM_GHJ         
                                  146      M_H_VREF                
                                  147      GND                     
                                  148      M_H_DQ<4>               
                                  149      GND                     
                                  150      M_H_DQ<0>               
                                  151      GND                     
                                  152      M_H_DQS_DN<0>           
                                  153      M_H_DQS_DP<0>           
                                  154      GND                     
                                  155      M_H_DQ<6>               
                                  156      GND                     
                                  157      M_H_DQ<2>               
                                  158      GND                     
                                  159      M_H_DQ<12>              
                                  160      GND                     
                                  161      M_H_DQ<8>               
                                  162      GND                     
                                  163      M_H_DQS_DN<1>           
                                  164      M_H_DQS_DP<1>           
                                  165      GND                     
                                  166      M_H_DQ<14>              
                                  167      GND                     
                                  168      M_H_DQ<10>              
                                  169      GND                     
                                  170      M_H_DQ<20>              
                                  171      GND                     
                                  172      M_H_DQ<16>              
                                  173      GND                     
                                  174      M_H_DQS_DN<2>           
                                  175      M_H_DQS_DP<2>           
                                  176      GND                     
                                  177      M_H_DQ<22>              
                                  178      GND                     
                                  179      M_H_DQ<18>              
                                  180      GND                     
                                  181      M_H_DQ<28>              
                                  182      GND                     
                                  183      M_H_DQ<24>              
                                  184      GND                     
                                  185      M_H_DQS_DN<3>           
                                  186      M_H_DQS_DP<3>           
                                  187      GND                     
                                  188      M_H_DQ<30>              
                                  189      GND                     
                                  190      M_H_DQ<26>              
                                  191      GND                     
                                  192      M_H_ECC<4>              
                                  193      GND                     
                                  194      M_H_ECC<0>              
                                  195      GND                     
                                  196      M_H_DQS_DN<8>           
                                  197      M_H_DQS_DP<8>           
                                  198      GND                     
                                  199      M_H_ECC<6>              
                                  200      GND                     
                                  201      M_H_ECC<2>              
                                  202      GND                     
                                  203      M_H_CKE<1>              
                                  204      PVDDQ_GHJ               
                                  205      TP_CH_H_DIMM_H0_RFU_0   
                                  206      PVDDQ_GHJ               
                                  207      M_H_BG<1>               
                                  208      M_H_ALERT_N             
                                  209      PVDDQ_GHJ               
                                  210      M_H_MA<11>              
                                  211      M_H_MA<7>               
                                  212      PVDDQ_GHJ               
                                  213      M_H_MA<5>               
                                  214      M_H_MA<4>               
                                  215      PVDDQ_GHJ               
                                  216      M_H_MA<2>               
                                  217      PVDDQ_GHJ               
                                  218      M_H_CLK_DP<1>           
                                  219      M_H_CLK_DN<1>           
                                  220      PVDDQ_GHJ               
                                  221      PVTT_GHJ                
                                  222      M_H_PAR                 
                                  223      PVDDQ_GHJ               
                                  224      M_H_BA<1>               
                                  225      M_H_MA<10>              
                                  226      PVDDQ_GHJ               
                                  227      TP_CH_H_DIMM_H0_RFU_1   
                                  228      M_H_MA<14>              
                                  229      PVDDQ_GHJ               
                                  230      FM_ADR_COMPLETE_GHJ_N   
                                  231      PVDDQ_GHJ               
                                  232      M_H_MA<13>              
                                  233      PVDDQ_GHJ               
                                  234      M_H_MA<17>              
                                  235      M_H_C<2>                
                                  236      PVDDQ_GHJ               
                                  237      M_H_CS_N<3>             
                                  238      GND                     
                                  239      GND                     
                                  240      M_H_DQ<36>              
                                  241      GND                     
                                  242      M_H_DQ<32>              
                                  243      GND                     
                                  244      M_H_DQS_DN<4>           
                                  245      M_H_DQS_DP<4>           
                                  246      GND                     
                                  247      M_H_DQ<38>              
                                  248      GND                     
                                  249      M_H_DQ<34>              
                                  250      GND                     
                                  251      M_H_DQ<44>              
                                  252      GND                     
                                  253      M_H_DQ<40>              
                                  254      GND                     
                                  255      M_H_DQS_DN<5>           
                                  256      M_H_DQS_DP<5>           
                                  257      GND                     
                                  258      M_H_DQ<46>              
                                  259      GND                     
                                  260      M_H_DQ<42>              
                                  261      GND                     
                                  262      M_H_DQ<52>              
                                  263      GND                     
                                  264      M_H_DQ<48>              
                                  265      GND                     
                                  266      M_H_DQS_DN<6>           
                                  267      M_H_DQS_DP<6>           
                                  268      GND                     
                                  269      M_H_DQ<54>              
                                  270      GND                     
                                  271      M_H_DQ<50>              
                                  272      GND                     
                                  273      M_H_DQ<60>              
                                  274      GND                     
                                  275      M_H_DQ<56>              
                                  276      GND                     
                                  277      M_H_DQS_DN<7>           
                                  278      M_H_DQS_DP<7>           
                                  279      GND                     
                                  280      M_H_DQ<62>              
                                  281      GND                     
                                  282      M_H_DQ<58>              
                                  283      GND                     
                                  284      PVPP_GHJ                
                                  285      SMB_DDR_GHJ_VPP_SDA     
                                  286      PVPP_GHJ                
                                  287      PVPP_GHJ                
                                  288      PVPP_GHJ                
J1G3             SCONN288_H44441004_PIP-SCONN,HA 1        P12V_NVDIMM_GHJ         
                                  2        GND                     
                                  3        M_J_DQ<5>               
                                  4        GND                     
                                  5        M_J_DQ<1>               
                                  6        GND                     
                                  7        M_J_DQS_DP<9>           
                                  8        M_J_DQS_DN<9>           
                                  9        GND                     
                                  10       M_J_DQ<7>               
                                  11       GND                     
                                  12       M_J_DQ<3>               
                                  13       GND                     
                                  14       M_J_DQ<13>              
                                  15       GND                     
                                  16       M_J_DQ<9>               
                                  17       GND                     
                                  18       M_J_DQS_DP<10>          
                                  19       M_J_DQS_DN<10>          
                                  20       GND                     
                                  21       M_J_DQ<15>              
                                  22       GND                     
                                  23       M_J_DQ<11>              
                                  24       GND                     
                                  25       M_J_DQ<21>              
                                  26       GND                     
                                  27       M_J_DQ<17>              
                                  28       GND                     
                                  29       M_J_DQS_DP<11>          
                                  30       M_J_DQS_DN<11>          
                                  31       GND                     
                                  32       M_J_DQ<23>              
                                  33       GND                     
                                  34       M_J_DQ<19>              
                                  35       GND                     
                                  36       M_J_DQ<29>              
                                  37       GND                     
                                  38       M_J_DQ<25>              
                                  39       GND                     
                                  40       M_J_DQS_DP<12>          
                                  41       M_J_DQS_DN<12>          
                                  42       GND                     
                                  43       M_J_DQ<31>              
                                  44       GND                     
                                  45       M_J_DQ<27>              
                                  46       GND                     
                                  47       M_J_ECC<5>              
                                  48       GND                     
                                  49       M_J_ECC<1>              
                                  50       GND                     
                                  51       M_J_DQS_DP<17>          
                                  52       M_J_DQS_DN<17>          
                                  53       GND                     
                                  54       M_J_ECC<7>              
                                  55       GND                     
                                  56       M_J_ECC<3>              
                                  57       GND                     
                                  58       M_GHJ_RST_N             
                                  59       PVDDQ_GHJ               
                                  60       M_J_CKE<0>              
                                  61       PVDDQ_GHJ               
                                  62       M_J_ACT_N               
                                  63       M_J_BG<0>               
                                  64       PVDDQ_GHJ               
                                  65       M_J_MA<12>              
                                  66       M_J_MA<9>               
                                  67       PVDDQ_GHJ               
                                  68       M_J_MA<8>               
                                  69       M_J_MA<6>               
                                  70       PVDDQ_GHJ               
                                  71       M_J_MA<3>               
                                  72       M_J_MA<1>               
                                  73       PVDDQ_GHJ               
                                  74       M_J_CLK_DP<0>           
                                  75       M_J_CLK_DN<0>           
                                  76       PVDDQ_GHJ               
                                  77       PVTT_GHJ                
                                  78       FM_DIMM_EVENT_COD_N     
                                  79       M_J_MA<0>               
                                  80       PVDDQ_GHJ               
                                  81       M_J_BA<0>               
                                  82       M_J_MA<16>              
                                  83       PVDDQ_GHJ               
                                  84       M_J_CS_N<0>             
                                  85       PVDDQ_GHJ               
                                  86       M_J_MA<15>              
                                  87       M_J_ODT<0>              
                                  88       PVDDQ_GHJ               
                                  89       M_J_CS_N<1>             
                                  90       PVDDQ_GHJ               
                                  91       M_J_ODT<1>              
                                  92       PVDDQ_GHJ               
                                  93       M_J_CS_N<2>             
                                  94       GND                     
                                  95       M_J_DQ<37>              
                                  96       GND                     
                                  97       M_J_DQ<33>              
                                  98       GND                     
                                  99       M_J_DQS_DP<13>          
                                  100      M_J_DQS_DN<13>          
                                  101      GND                     
                                  102      M_J_DQ<39>              
                                  103      GND                     
                                  104      M_J_DQ<35>              
                                  105      GND                     
                                  106      M_J_DQ<45>              
                                  107      GND                     
                                  108      M_J_DQ<41>              
                                  109      GND                     
                                  110      M_J_DQS_DP<14>          
                                  111      M_J_DQS_DN<14>          
                                  112      GND                     
                                  113      M_J_DQ<47>              
                                  114      GND                     
                                  115      M_J_DQ<43>              
                                  116      GND                     
                                  117      M_J_DQ<53>              
                                  118      GND                     
                                  119      M_J_DQ<49>              
                                  120      GND                     
                                  121      M_J_DQS_DP<15>          
                                  122      M_J_DQS_DN<15>          
                                  123      GND                     
                                  124      M_J_DQ<55>              
                                  125      GND                     
                                  126      M_J_DQ<51>              
                                  127      GND                     
                                  128      M_J_DQ<61>              
                                  129      GND                     
                                  130      M_J_DQ<57>              
                                  131      GND                     
                                  132      M_J_DQS_DP<16>          
                                  133      M_J_DQS_DN<16>          
                                  134      GND                     
                                  135      M_J_DQ<63>              
                                  136      GND                     
                                  137      M_J_DQ<59>              
                                  138      GND                     
                                  139      GND                     
                                  140      GND                     
                                  141      SMB_DDR_GHJ_VPP_SCL     
                                  142      PVPP_GHJ                
                                  143      PVPP_GHJ                
                                  144      TP_CH_J_DIMM_J0_RFU_2   
                                  145      P12V_NVDIMM_GHJ         
                                  146      M_J_VREF                
                                  147      GND                     
                                  148      M_J_DQ<4>               
                                  149      GND                     
                                  150      M_J_DQ<0>               
                                  151      GND                     
                                  152      M_J_DQS_DN<0>           
                                  153      M_J_DQS_DP<0>           
                                  154      GND                     
                                  155      M_J_DQ<6>               
                                  156      GND                     
                                  157      M_J_DQ<2>               
                                  158      GND                     
                                  159      M_J_DQ<12>              
                                  160      GND                     
                                  161      M_J_DQ<8>               
                                  162      GND                     
                                  163      M_J_DQS_DN<1>           
                                  164      M_J_DQS_DP<1>           
                                  165      GND                     
                                  166      M_J_DQ<14>              
                                  167      GND                     
                                  168      M_J_DQ<10>              
                                  169      GND                     
                                  170      M_J_DQ<20>              
                                  171      GND                     
                                  172      M_J_DQ<16>              
                                  173      GND                     
                                  174      M_J_DQS_DN<2>           
                                  175      M_J_DQS_DP<2>           
                                  176      GND                     
                                  177      M_J_DQ<22>              
                                  178      GND                     
                                  179      M_J_DQ<18>              
                                  180      GND                     
                                  181      M_J_DQ<28>              
                                  182      GND                     
                                  183      M_J_DQ<24>              
                                  184      GND                     
                                  185      M_J_DQS_DN<3>           
                                  186      M_J_DQS_DP<3>           
                                  187      GND                     
                                  188      M_J_DQ<30>              
                                  189      GND                     
                                  190      M_J_DQ<26>              
                                  191      GND                     
                                  192      M_J_ECC<4>              
                                  193      GND                     
                                  194      M_J_ECC<0>              
                                  195      GND                     
                                  196      M_J_DQS_DN<8>           
                                  197      M_J_DQS_DP<8>           
                                  198      GND                     
                                  199      M_J_ECC<6>              
                                  200      GND                     
                                  201      M_J_ECC<2>              
                                  202      GND                     
                                  203      M_J_CKE<1>              
                                  204      PVDDQ_GHJ               
                                  205      TP_CH_J_DIMM_J0_RFU_0   
                                  206      PVDDQ_GHJ               
                                  207      M_J_BG<1>               
                                  208      M_J_ALERT_N             
                                  209      PVDDQ_GHJ               
                                  210      M_J_MA<11>              
                                  211      M_J_MA<7>               
                                  212      PVDDQ_GHJ               
                                  213      M_J_MA<5>               
                                  214      M_J_MA<4>               
                                  215      PVDDQ_GHJ               
                                  216      M_J_MA<2>               
                                  217      PVDDQ_GHJ               
                                  218      M_J_CLK_DP<1>           
                                  219      M_J_CLK_DN<1>           
                                  220      PVDDQ_GHJ               
                                  221      PVTT_GHJ                
                                  222      M_J_PAR                 
                                  223      PVDDQ_GHJ               
                                  224      M_J_BA<1>               
                                  225      M_J_MA<10>              
                                  226      PVDDQ_GHJ               
                                  227      TP_CH_J_DIMM_J0_RFU_1   
                                  228      M_J_MA<14>              
                                  229      PVDDQ_GHJ               
                                  230      FM_ADR_COMPLETE_GHJ_N   
                                  231      PVDDQ_GHJ               
                                  232      M_J_MA<13>              
                                  233      PVDDQ_GHJ               
                                  234      M_J_MA<17>              
                                  235      M_J_C<2>                
                                  236      PVDDQ_GHJ               
                                  237      M_J_CS_N<3>             
                                  238      PVPP_GHJ                
                                  239      GND                     
                                  240      M_J_DQ<36>              
                                  241      GND                     
                                  242      M_J_DQ<32>              
                                  243      GND                     
                                  244      M_J_DQS_DN<4>           
                                  245      M_J_DQS_DP<4>           
                                  246      GND                     
                                  247      M_J_DQ<38>              
                                  248      GND                     
                                  249      M_J_DQ<34>              
                                  250      GND                     
                                  251      M_J_DQ<44>              
                                  252      GND                     
                                  253      M_J_DQ<40>              
                                  254      GND                     
                                  255      M_J_DQS_DN<5>           
                                  256      M_J_DQS_DP<5>           
                                  257      GND                     
                                  258      M_J_DQ<46>              
                                  259      GND                     
                                  260      M_J_DQ<42>              
                                  261      GND                     
                                  262      M_J_DQ<52>              
                                  263      GND                     
                                  264      M_J_DQ<48>              
                                  265      GND                     
                                  266      M_J_DQS_DN<6>           
                                  267      M_J_DQS_DP<6>           
                                  268      GND                     
                                  269      M_J_DQ<54>              
                                  270      GND                     
                                  271      M_J_DQ<50>              
                                  272      GND                     
                                  273      M_J_DQ<60>              
                                  274      GND                     
                                  275      M_J_DQ<56>              
                                  276      GND                     
                                  277      M_J_DQS_DN<7>           
                                  278      M_J_DQS_DP<7>           
                                  279      GND                     
                                  280      M_J_DQ<62>              
                                  281      GND                     
                                  282      M_J_DQ<58>              
                                  283      GND                     
                                  284      PVPP_GHJ                
                                  285      SMB_DDR_GHJ_VPP_SDA     
                                  286      PVPP_GHJ                
                                  287      PVPP_GHJ                
                                  288      PVPP_GHJ                
J2L1             CONN4_H73295001_PIP-CONN,H7329A 1        P5V_HDD_SATA            
                                  2        GND                     
                                  3        GND                     
                                  4        P12V_HDD_SATA           
J2M1             CONN7_E82125014_PIP_TH-CONN,E8A 1        GND                     
                                  2        SATA6G_S1_TX_C_DP       
                                  3        SATA6G_S1_TX_C_DN       
                                  4        GND                     
                                  5        SATA6G_S1_RX_C_DN       
                                  6        SATA6G_S1_RX_C_DP       
                                  7        GND                     
                                  MH1      GND                     
                                  MH2      GND                     
J4A1             SCONN288_H44441004_PIP-SCONN,HA 1        P12V_NVDIMM_DEF         
                                  2        GND                     
                                  3        M_F_DQ<5>               
                                  4        GND                     
                                  5        M_F_DQ<1>               
                                  6        GND                     
                                  7        M_F_DQS_DP<9>           
                                  8        M_F_DQS_DN<9>           
                                  9        GND                     
                                  10       M_F_DQ<7>               
                                  11       GND                     
                                  12       M_F_DQ<3>               
                                  13       GND                     
                                  14       M_F_DQ<13>              
                                  15       GND                     
                                  16       M_F_DQ<9>               
                                  17       GND                     
                                  18       M_F_DQS_DP<10>          
                                  19       M_F_DQS_DN<10>          
                                  20       GND                     
                                  21       M_F_DQ<15>              
                                  22       GND                     
                                  23       M_F_DQ<11>              
                                  24       GND                     
                                  25       M_F_DQ<21>              
                                  26       GND                     
                                  27       M_F_DQ<17>              
                                  28       GND                     
                                  29       M_F_DQS_DP<11>          
                                  30       M_F_DQS_DN<11>          
                                  31       GND                     
                                  32       M_F_DQ<23>              
                                  33       GND                     
                                  34       M_F_DQ<19>              
                                  35       GND                     
                                  36       M_F_DQ<29>              
                                  37       GND                     
                                  38       M_F_DQ<25>              
                                  39       GND                     
                                  40       M_F_DQS_DP<12>          
                                  41       M_F_DQS_DN<12>          
                                  42       GND                     
                                  43       M_F_DQ<31>              
                                  44       GND                     
                                  45       M_F_DQ<27>              
                                  46       GND                     
                                  47       M_F_ECC<5>              
                                  48       GND                     
                                  49       M_F_ECC<1>              
                                  50       GND                     
                                  51       M_F_DQS_DP<17>          
                                  52       M_F_DQS_DN<17>          
                                  53       GND                     
                                  54       M_F_ECC<7>              
                                  55       GND                     
                                  56       M_F_ECC<3>              
                                  57       GND                     
                                  58       M_DEF_RST_N             
                                  59       PVDDQ_DEF               
                                  60       M_F_CKE<0>              
                                  61       PVDDQ_DEF               
                                  62       M_F_ACT_N               
                                  63       M_F_BG<0>               
                                  64       PVDDQ_DEF               
                                  65       M_F_MA<12>              
                                  66       M_F_MA<9>               
                                  67       PVDDQ_DEF               
                                  68       M_F_MA<8>               
                                  69       M_F_MA<6>               
                                  70       PVDDQ_DEF               
                                  71       M_F_MA<3>               
                                  72       M_F_MA<1>               
                                  73       PVDDQ_DEF               
                                  74       M_F_CLK_DP<0>           
                                  75       M_F_CLK_DN<0>           
                                  76       PVDDQ_DEF               
                                  77       PVTT_DEF                
                                  78       FM_DIMM_EVENT_COD_N     
                                  79       M_F_MA<0>               
                                  80       PVDDQ_DEF               
                                  81       M_F_BA<0>               
                                  82       M_F_MA<16>              
                                  83       PVDDQ_DEF               
                                  84       M_F_CS_N<0>             
                                  85       PVDDQ_DEF               
                                  86       M_F_MA<15>              
                                  87       M_F_ODT<0>              
                                  88       PVDDQ_DEF               
                                  89       M_F_CS_N<1>             
                                  90       PVDDQ_DEF               
                                  91       M_F_ODT<1>              
                                  92       PVDDQ_DEF               
                                  93       M_F_CS_N<2>             
                                  94       GND                     
                                  95       M_F_DQ<37>              
                                  96       GND                     
                                  97       M_F_DQ<33>              
                                  98       GND                     
                                  99       M_F_DQS_DP<13>          
                                  100      M_F_DQS_DN<13>          
                                  101      GND                     
                                  102      M_F_DQ<39>              
                                  103      GND                     
                                  104      M_F_DQ<35>              
                                  105      GND                     
                                  106      M_F_DQ<45>              
                                  107      GND                     
                                  108      M_F_DQ<41>              
                                  109      GND                     
                                  110      M_F_DQS_DP<14>          
                                  111      M_F_DQS_DN<14>          
                                  112      GND                     
                                  113      M_F_DQ<47>              
                                  114      GND                     
                                  115      M_F_DQ<43>              
                                  116      GND                     
                                  117      M_F_DQ<53>              
                                  118      GND                     
                                  119      M_F_DQ<49>              
                                  120      GND                     
                                  121      M_F_DQS_DP<15>          
                                  122      M_F_DQS_DN<15>          
                                  123      GND                     
                                  124      M_F_DQ<55>              
                                  125      GND                     
                                  126      M_F_DQ<51>              
                                  127      GND                     
                                  128      M_F_DQ<61>              
                                  129      GND                     
                                  130      M_F_DQ<57>              
                                  131      GND                     
                                  132      M_F_DQS_DP<16>          
                                  133      M_F_DQS_DN<16>          
                                  134      GND                     
                                  135      M_F_DQ<63>              
                                  136      GND                     
                                  137      M_F_DQ<59>              
                                  138      GND                     
                                  139      GND                     
                                  140      GND                     
                                  141      SMB_DDR_DEF_VPP_SCL     
                                  142      PVPP_DEF                
                                  143      PVPP_DEF                
                                  144      TP_CH_F_DIMM_F0_RFU_2   
                                  145      P12V_NVDIMM_DEF         
                                  146      M_F_VREF                
                                  147      GND                     
                                  148      M_F_DQ<4>               
                                  149      GND                     
                                  150      M_F_DQ<0>               
                                  151      GND                     
                                  152      M_F_DQS_DN<0>           
                                  153      M_F_DQS_DP<0>           
                                  154      GND                     
                                  155      M_F_DQ<6>               
                                  156      GND                     
                                  157      M_F_DQ<2>               
                                  158      GND                     
                                  159      M_F_DQ<12>              
                                  160      GND                     
                                  161      M_F_DQ<8>               
                                  162      GND                     
                                  163      M_F_DQS_DN<1>           
                                  164      M_F_DQS_DP<1>           
                                  165      GND                     
                                  166      M_F_DQ<14>              
                                  167      GND                     
                                  168      M_F_DQ<10>              
                                  169      GND                     
                                  170      M_F_DQ<20>              
                                  171      GND                     
                                  172      M_F_DQ<16>              
                                  173      GND                     
                                  174      M_F_DQS_DN<2>           
                                  175      M_F_DQS_DP<2>           
                                  176      GND                     
                                  177      M_F_DQ<22>              
                                  178      GND                     
                                  179      M_F_DQ<18>              
                                  180      GND                     
                                  181      M_F_DQ<28>              
                                  182      GND                     
                                  183      M_F_DQ<24>              
                                  184      GND                     
                                  185      M_F_DQS_DN<3>           
                                  186      M_F_DQS_DP<3>           
                                  187      GND                     
                                  188      M_F_DQ<30>              
                                  189      GND                     
                                  190      M_F_DQ<26>              
                                  191      GND                     
                                  192      M_F_ECC<4>              
                                  193      GND                     
                                  194      M_F_ECC<0>              
                                  195      GND                     
                                  196      M_F_DQS_DN<8>           
                                  197      M_F_DQS_DP<8>           
                                  198      GND                     
                                  199      M_F_ECC<6>              
                                  200      GND                     
                                  201      M_F_ECC<2>              
                                  202      GND                     
                                  203      M_F_CKE<1>              
                                  204      PVDDQ_DEF               
                                  205      TP_CH_F_DIMM_F0_RFU_0   
                                  206      PVDDQ_DEF               
                                  207      M_F_BG<1>               
                                  208      M_F_ALERT_N             
                                  209      PVDDQ_DEF               
                                  210      M_F_MA<11>              
                                  211      M_F_MA<7>               
                                  212      PVDDQ_DEF               
                                  213      M_F_MA<5>               
                                  214      M_F_MA<4>               
                                  215      PVDDQ_DEF               
                                  216      M_F_MA<2>               
                                  217      PVDDQ_DEF               
                                  218      M_F_CLK_DP<1>           
                                  219      M_F_CLK_DN<1>           
                                  220      PVDDQ_DEF               
                                  221      PVTT_DEF                
                                  222      M_F_PAR                 
                                  223      PVDDQ_DEF               
                                  224      M_F_BA<1>               
                                  225      M_F_MA<10>              
                                  226      PVDDQ_DEF               
                                  227      TP_CH_F_DIMM_F0_RFU_1   
                                  228      M_F_MA<14>              
                                  229      PVDDQ_DEF               
                                  230      FM_ADR_COMPLETE_DEF_N   
                                  231      PVDDQ_DEF               
                                  232      M_F_MA<13>              
                                  233      PVDDQ_DEF               
                                  234      M_F_MA<17>              
                                  235      M_F_C<2>                
                                  236      PVDDQ_DEF               
                                  237      M_F_CS_N<3>             
                                  238      PVPP_DEF                
                                  239      GND                     
                                  240      M_F_DQ<36>              
                                  241      GND                     
                                  242      M_F_DQ<32>              
                                  243      GND                     
                                  244      M_F_DQS_DN<4>           
                                  245      M_F_DQS_DP<4>           
                                  246      GND                     
                                  247      M_F_DQ<38>              
                                  248      GND                     
                                  249      M_F_DQ<34>              
                                  250      GND                     
                                  251      M_F_DQ<44>              
                                  252      GND                     
                                  253      M_F_DQ<40>              
                                  254      GND                     
                                  255      M_F_DQS_DN<5>           
                                  256      M_F_DQS_DP<5>           
                                  257      GND                     
                                  258      M_F_DQ<46>              
                                  259      GND                     
                                  260      M_F_DQ<42>              
                                  261      GND                     
                                  262      M_F_DQ<52>              
                                  263      GND                     
                                  264      M_F_DQ<48>              
                                  265      GND                     
                                  266      M_F_DQS_DN<6>           
                                  267      M_F_DQS_DP<6>           
                                  268      GND                     
                                  269      M_F_DQ<54>              
                                  270      GND                     
                                  271      M_F_DQ<50>              
                                  272      GND                     
                                  273      M_F_DQ<60>              
                                  274      GND                     
                                  275      M_F_DQ<56>              
                                  276      GND                     
                                  277      M_F_DQS_DN<7>           
                                  278      M_F_DQS_DP<7>           
                                  279      GND                     
                                  280      M_F_DQ<62>              
                                  281      GND                     
                                  282      M_F_DQ<58>              
                                  283      GND                     
                                  284      PVPP_DEF                
                                  285      SMB_DDR_DEF_VPP_SDA     
                                  286      PVPP_DEF                
                                  287      PVPP_DEF                
                                  288      PVPP_DEF                
J4A2             SCONN288_H44441004_PIP-SCONN,HA 1        P12V_NVDIMM_DEF         
                                  2        GND                     
                                  3        M_E_DQ<5>               
                                  4        GND                     
                                  5        M_E_DQ<1>               
                                  6        GND                     
                                  7        M_E_DQS_DP<9>           
                                  8        M_E_DQS_DN<9>           
                                  9        GND                     
                                  10       M_E_DQ<7>               
                                  11       GND                     
                                  12       M_E_DQ<3>               
                                  13       GND                     
                                  14       M_E_DQ<13>              
                                  15       GND                     
                                  16       M_E_DQ<9>               
                                  17       GND                     
                                  18       M_E_DQS_DP<10>          
                                  19       M_E_DQS_DN<10>          
                                  20       GND                     
                                  21       M_E_DQ<15>              
                                  22       GND                     
                                  23       M_E_DQ<11>              
                                  24       GND                     
                                  25       M_E_DQ<21>              
                                  26       GND                     
                                  27       M_E_DQ<17>              
                                  28       GND                     
                                  29       M_E_DQS_DP<11>          
                                  30       M_E_DQS_DN<11>          
                                  31       GND                     
                                  32       M_E_DQ<23>              
                                  33       GND                     
                                  34       M_E_DQ<19>              
                                  35       GND                     
                                  36       M_E_DQ<29>              
                                  37       GND                     
                                  38       M_E_DQ<25>              
                                  39       GND                     
                                  40       M_E_DQS_DP<12>          
                                  41       M_E_DQS_DN<12>          
                                  42       GND                     
                                  43       M_E_DQ<31>              
                                  44       GND                     
                                  45       M_E_DQ<27>              
                                  46       GND                     
                                  47       M_E_ECC<5>              
                                  48       GND                     
                                  49       M_E_ECC<1>              
                                  50       GND                     
                                  51       M_E_DQS_DP<17>          
                                  52       M_E_DQS_DN<17>          
                                  53       GND                     
                                  54       M_E_ECC<7>              
                                  55       GND                     
                                  56       M_E_ECC<3>              
                                  57       GND                     
                                  58       M_DEF_RST_N             
                                  59       PVDDQ_DEF               
                                  60       M_E_CKE<0>              
                                  61       PVDDQ_DEF               
                                  62       M_E_ACT_N               
                                  63       M_E_BG<0>               
                                  64       PVDDQ_DEF               
                                  65       M_E_MA<12>              
                                  66       M_E_MA<9>               
                                  67       PVDDQ_DEF               
                                  68       M_E_MA<8>               
                                  69       M_E_MA<6>               
                                  70       PVDDQ_DEF               
                                  71       M_E_MA<3>               
                                  72       M_E_MA<1>               
                                  73       PVDDQ_DEF               
                                  74       M_E_CLK_DP<0>           
                                  75       M_E_CLK_DN<0>           
                                  76       PVDDQ_DEF               
                                  77       PVTT_DEF                
                                  78       FM_DIMM_EVENT_COD_N     
                                  79       M_E_MA<0>               
                                  80       PVDDQ_DEF               
                                  81       M_E_BA<0>               
                                  82       M_E_MA<16>              
                                  83       PVDDQ_DEF               
                                  84       M_E_CS_N<0>             
                                  85       PVDDQ_DEF               
                                  86       M_E_MA<15>              
                                  87       M_E_ODT<0>              
                                  88       PVDDQ_DEF               
                                  89       M_E_CS_N<1>             
                                  90       PVDDQ_DEF               
                                  91       M_E_ODT<1>              
                                  92       PVDDQ_DEF               
                                  93       M_E_CS_N<2>             
                                  94       GND                     
                                  95       M_E_DQ<37>              
                                  96       GND                     
                                  97       M_E_DQ<33>              
                                  98       GND                     
                                  99       M_E_DQS_DP<13>          
                                  100      M_E_DQS_DN<13>          
                                  101      GND                     
                                  102      M_E_DQ<39>              
                                  103      GND                     
                                  104      M_E_DQ<35>              
                                  105      GND                     
                                  106      M_E_DQ<45>              
                                  107      GND                     
                                  108      M_E_DQ<41>              
                                  109      GND                     
                                  110      M_E_DQS_DP<14>          
                                  111      M_E_DQS_DN<14>          
                                  112      GND                     
                                  113      M_E_DQ<47>              
                                  114      GND                     
                                  115      M_E_DQ<43>              
                                  116      GND                     
                                  117      M_E_DQ<53>              
                                  118      GND                     
                                  119      M_E_DQ<49>              
                                  120      GND                     
                                  121      M_E_DQS_DP<15>          
                                  122      M_E_DQS_DN<15>          
                                  123      GND                     
                                  124      M_E_DQ<55>              
                                  125      GND                     
                                  126      M_E_DQ<51>              
                                  127      GND                     
                                  128      M_E_DQ<61>              
                                  129      GND                     
                                  130      M_E_DQ<57>              
                                  131      GND                     
                                  132      M_E_DQS_DP<16>          
                                  133      M_E_DQS_DN<16>          
                                  134      GND                     
                                  135      M_E_DQ<63>              
                                  136      GND                     
                                  137      M_E_DQ<59>              
                                  138      GND                     
                                  139      GND                     
                                  140      PVPP_DEF                
                                  141      SMB_DDR_DEF_VPP_SCL     
                                  142      PVPP_DEF                
                                  143      PVPP_DEF                
                                  144      TP_CH_E_DIMM_E0_RFU_2   
                                  145      P12V_NVDIMM_DEF         
                                  146      M_E_VREF                
                                  147      GND                     
                                  148      M_E_DQ<4>               
                                  149      GND                     
                                  150      M_E_DQ<0>               
                                  151      GND                     
                                  152      M_E_DQS_DN<0>           
                                  153      M_E_DQS_DP<0>           
                                  154      GND                     
                                  155      M_E_DQ<6>               
                                  156      GND                     
                                  157      M_E_DQ<2>               
                                  158      GND                     
                                  159      M_E_DQ<12>              
                                  160      GND                     
                                  161      M_E_DQ<8>               
                                  162      GND                     
                                  163      M_E_DQS_DN<1>           
                                  164      M_E_DQS_DP<1>           
                                  165      GND                     
                                  166      M_E_DQ<14>              
                                  167      GND                     
                                  168      M_E_DQ<10>              
                                  169      GND                     
                                  170      M_E_DQ<20>              
                                  171      GND                     
                                  172      M_E_DQ<16>              
                                  173      GND                     
                                  174      M_E_DQS_DN<2>           
                                  175      M_E_DQS_DP<2>           
                                  176      GND                     
                                  177      M_E_DQ<22>              
                                  178      GND                     
                                  179      M_E_DQ<18>              
                                  180      GND                     
                                  181      M_E_DQ<28>              
                                  182      GND                     
                                  183      M_E_DQ<24>              
                                  184      GND                     
                                  185      M_E_DQS_DN<3>           
                                  186      M_E_DQS_DP<3>           
                                  187      GND                     
                                  188      M_E_DQ<30>              
                                  189      GND                     
                                  190      M_E_DQ<26>              
                                  191      GND                     
                                  192      M_E_ECC<4>              
                                  193      GND                     
                                  194      M_E_ECC<0>              
                                  195      GND                     
                                  196      M_E_DQS_DN<8>           
                                  197      M_E_DQS_DP<8>           
                                  198      GND                     
                                  199      M_E_ECC<6>              
                                  200      GND                     
                                  201      M_E_ECC<2>              
                                  202      GND                     
                                  203      M_E_CKE<1>              
                                  204      PVDDQ_DEF               
                                  205      TP_CH_E_DIMM_E0_RFU_0   
                                  206      PVDDQ_DEF               
                                  207      M_E_BG<1>               
                                  208      M_E_ALERT_N             
                                  209      PVDDQ_DEF               
                                  210      M_E_MA<11>              
                                  211      M_E_MA<7>               
                                  212      PVDDQ_DEF               
                                  213      M_E_MA<5>               
                                  214      M_E_MA<4>               
                                  215      PVDDQ_DEF               
                                  216      M_E_MA<2>               
                                  217      PVDDQ_DEF               
                                  218      M_E_CLK_DP<1>           
                                  219      M_E_CLK_DN<1>           
                                  220      PVDDQ_DEF               
                                  221      PVTT_DEF                
                                  222      M_E_PAR                 
                                  223      PVDDQ_DEF               
                                  224      M_E_BA<1>               
                                  225      M_E_MA<10>              
                                  226      PVDDQ_DEF               
                                  227      TP_CH_E_DIMM_E0_RFU_1   
                                  228      M_E_MA<14>              
                                  229      PVDDQ_DEF               
                                  230      FM_ADR_COMPLETE_DEF_N   
                                  231      PVDDQ_DEF               
                                  232      M_E_MA<13>              
                                  233      PVDDQ_DEF               
                                  234      M_E_MA<17>              
                                  235      M_E_C<2>                
                                  236      PVDDQ_DEF               
                                  237      M_E_CS_N<3>             
                                  238      GND                     
                                  239      GND                     
                                  240      M_E_DQ<36>              
                                  241      GND                     
                                  242      M_E_DQ<32>              
                                  243      GND                     
                                  244      M_E_DQS_DN<4>           
                                  245      M_E_DQS_DP<4>           
                                  246      GND                     
                                  247      M_E_DQ<38>              
                                  248      GND                     
                                  249      M_E_DQ<34>              
                                  250      GND                     
                                  251      M_E_DQ<44>              
                                  252      GND                     
                                  253      M_E_DQ<40>              
                                  254      GND                     
                                  255      M_E_DQS_DN<5>           
                                  256      M_E_DQS_DP<5>           
                                  257      GND                     
                                  258      M_E_DQ<46>              
                                  259      GND                     
                                  260      M_E_DQ<42>              
                                  261      GND                     
                                  262      M_E_DQ<52>              
                                  263      GND                     
                                  264      M_E_DQ<48>              
                                  265      GND                     
                                  266      M_E_DQS_DN<6>           
                                  267      M_E_DQS_DP<6>           
                                  268      GND                     
                                  269      M_E_DQ<54>              
                                  270      GND                     
                                  271      M_E_DQ<50>              
                                  272      GND                     
                                  273      M_E_DQ<60>              
                                  274      GND                     
                                  275      M_E_DQ<56>              
                                  276      GND                     
                                  277      M_E_DQS_DN<7>           
                                  278      M_E_DQS_DP<7>           
                                  279      GND                     
                                  280      M_E_DQ<62>              
                                  281      GND                     
                                  282      M_E_DQ<58>              
                                  283      GND                     
                                  284      PVPP_DEF                
                                  285      SMB_DDR_DEF_VPP_SDA     
                                  286      PVPP_DEF                
                                  287      PVPP_DEF                
                                  288      PVPP_DEF                
J4B1             SCONN288_H44441004_PIP-SCONN,HA 1        P12V_NVDIMM_DEF         
                                  2        GND                     
                                  3        M_D_DQ<5>               
                                  4        GND                     
                                  5        M_D_DQ<1>               
                                  6        GND                     
                                  7        M_D_DQS_DP<9>           
                                  8        M_D_DQS_DN<9>           
                                  9        GND                     
                                  10       M_D_DQ<7>               
                                  11       GND                     
                                  12       M_D_DQ<3>               
                                  13       GND                     
                                  14       M_D_DQ<13>              
                                  15       GND                     
                                  16       M_D_DQ<9>               
                                  17       GND                     
                                  18       M_D_DQS_DP<10>          
                                  19       M_D_DQS_DN<10>          
                                  20       GND                     
                                  21       M_D_DQ<15>              
                                  22       GND                     
                                  23       M_D_DQ<11>              
                                  24       GND                     
                                  25       M_D_DQ<21>              
                                  26       GND                     
                                  27       M_D_DQ<17>              
                                  28       GND                     
                                  29       M_D_DQS_DP<11>          
                                  30       M_D_DQS_DN<11>          
                                  31       GND                     
                                  32       M_D_DQ<23>              
                                  33       GND                     
                                  34       M_D_DQ<19>              
                                  35       GND                     
                                  36       M_D_DQ<29>              
                                  37       GND                     
                                  38       M_D_DQ<25>              
                                  39       GND                     
                                  40       M_D_DQS_DP<12>          
                                  41       M_D_DQS_DN<12>          
                                  42       GND                     
                                  43       M_D_DQ<31>              
                                  44       GND                     
                                  45       M_D_DQ<27>              
                                  46       GND                     
                                  47       M_D_ECC<5>              
                                  48       GND                     
                                  49       M_D_ECC<1>              
                                  50       GND                     
                                  51       M_D_DQS_DP<17>          
                                  52       M_D_DQS_DN<17>          
                                  53       GND                     
                                  54       M_D_ECC<7>              
                                  55       GND                     
                                  56       M_D_ECC<3>              
                                  57       GND                     
                                  58       M_DEF_RST_N             
                                  59       PVDDQ_DEF               
                                  60       M_D_CKE<0>              
                                  61       PVDDQ_DEF               
                                  62       M_D_ACT_N               
                                  63       M_D_BG<0>               
                                  64       PVDDQ_DEF               
                                  65       M_D_MA<12>              
                                  66       M_D_MA<9>               
                                  67       PVDDQ_DEF               
                                  68       M_D_MA<8>               
                                  69       M_D_MA<6>               
                                  70       PVDDQ_DEF               
                                  71       M_D_MA<3>               
                                  72       M_D_MA<1>               
                                  73       PVDDQ_DEF               
                                  74       M_D_CLK_DP<0>           
                                  75       M_D_CLK_DN<0>           
                                  76       PVDDQ_DEF               
                                  77       PVTT_DEF                
                                  78       FM_DIMM_EVENT_COD_N     
                                  79       M_D_MA<0>               
                                  80       PVDDQ_DEF               
                                  81       M_D_BA<0>               
                                  82       M_D_MA<16>              
                                  83       PVDDQ_DEF               
                                  84       M_D_CS_N<0>             
                                  85       PVDDQ_DEF               
                                  86       M_D_MA<15>              
                                  87       M_D_ODT<0>              
                                  88       PVDDQ_DEF               
                                  89       M_D_CS_N<1>             
                                  90       PVDDQ_DEF               
                                  91       M_D_ODT<1>              
                                  92       PVDDQ_DEF               
                                  93       M_D_CS_N<2>             
                                  94       GND                     
                                  95       M_D_DQ<37>              
                                  96       GND                     
                                  97       M_D_DQ<33>              
                                  98       GND                     
                                  99       M_D_DQS_DP<13>          
                                  100      M_D_DQS_DN<13>          
                                  101      GND                     
                                  102      M_D_DQ<39>              
                                  103      GND                     
                                  104      M_D_DQ<35>              
                                  105      GND                     
                                  106      M_D_DQ<45>              
                                  107      GND                     
                                  108      M_D_DQ<41>              
                                  109      GND                     
                                  110      M_D_DQS_DP<14>          
                                  111      M_D_DQS_DN<14>          
                                  112      GND                     
                                  113      M_D_DQ<47>              
                                  114      GND                     
                                  115      M_D_DQ<43>              
                                  116      GND                     
                                  117      M_D_DQ<53>              
                                  118      GND                     
                                  119      M_D_DQ<49>              
                                  120      GND                     
                                  121      M_D_DQS_DP<15>          
                                  122      M_D_DQS_DN<15>          
                                  123      GND                     
                                  124      M_D_DQ<55>              
                                  125      GND                     
                                  126      M_D_DQ<51>              
                                  127      GND                     
                                  128      M_D_DQ<61>              
                                  129      GND                     
                                  130      M_D_DQ<57>              
                                  131      GND                     
                                  132      M_D_DQS_DP<16>          
                                  133      M_D_DQS_DN<16>          
                                  134      GND                     
                                  135      M_D_DQ<63>              
                                  136      GND                     
                                  137      M_D_DQ<59>              
                                  138      GND                     
                                  139      GND                     
                                  140      GND                     
                                  141      SMB_DDR_DEF_VPP_SCL     
                                  142      PVPP_DEF                
                                  143      PVPP_DEF                
                                  144      TP_CH_D_DIMM_D0_RFU_2   
                                  145      P12V_NVDIMM_DEF         
                                  146      M_D_VREF                
                                  147      GND                     
                                  148      M_D_DQ<4>               
                                  149      GND                     
                                  150      M_D_DQ<0>               
                                  151      GND                     
                                  152      M_D_DQS_DN<0>           
                                  153      M_D_DQS_DP<0>           
                                  154      GND                     
                                  155      M_D_DQ<6>               
                                  156      GND                     
                                  157      M_D_DQ<2>               
                                  158      GND                     
                                  159      M_D_DQ<12>              
                                  160      GND                     
                                  161      M_D_DQ<8>               
                                  162      GND                     
                                  163      M_D_DQS_DN<1>           
                                  164      M_D_DQS_DP<1>           
                                  165      GND                     
                                  166      M_D_DQ<14>              
                                  167      GND                     
                                  168      M_D_DQ<10>              
                                  169      GND                     
                                  170      M_D_DQ<20>              
                                  171      GND                     
                                  172      M_D_DQ<16>              
                                  173      GND                     
                                  174      M_D_DQS_DN<2>           
                                  175      M_D_DQS_DP<2>           
                                  176      GND                     
                                  177      M_D_DQ<22>              
                                  178      GND                     
                                  179      M_D_DQ<18>              
                                  180      GND                     
                                  181      M_D_DQ<28>              
                                  182      GND                     
                                  183      M_D_DQ<24>              
                                  184      GND                     
                                  185      M_D_DQS_DN<3>           
                                  186      M_D_DQS_DP<3>           
                                  187      GND                     
                                  188      M_D_DQ<30>              
                                  189      GND                     
                                  190      M_D_DQ<26>              
                                  191      GND                     
                                  192      M_D_ECC<4>              
                                  193      GND                     
                                  194      M_D_ECC<0>              
                                  195      GND                     
                                  196      M_D_DQS_DN<8>           
                                  197      M_D_DQS_DP<8>           
                                  198      GND                     
                                  199      M_D_ECC<6>              
                                  200      GND                     
                                  201      M_D_ECC<2>              
                                  202      GND                     
                                  203      M_D_CKE<1>              
                                  204      PVDDQ_DEF               
                                  205      TP_CH_D_DIMM_D0_RFU_0   
                                  206      PVDDQ_DEF               
                                  207      M_D_BG<1>               
                                  208      M_D_ALERT_N             
                                  209      PVDDQ_DEF               
                                  210      M_D_MA<11>              
                                  211      M_D_MA<7>               
                                  212      PVDDQ_DEF               
                                  213      M_D_MA<5>               
                                  214      M_D_MA<4>               
                                  215      PVDDQ_DEF               
                                  216      M_D_MA<2>               
                                  217      PVDDQ_DEF               
                                  218      M_D_CLK_DP<1>           
                                  219      M_D_CLK_DN<1>           
                                  220      PVDDQ_DEF               
                                  221      PVTT_DEF                
                                  222      M_D_PAR                 
                                  223      PVDDQ_DEF               
                                  224      M_D_BA<1>               
                                  225      M_D_MA<10>              
                                  226      PVDDQ_DEF               
                                  227      TP_CH_D_DIMM_D0_RFU_1   
                                  228      M_D_MA<14>              
                                  229      PVDDQ_DEF               
                                  230      FM_ADR_COMPLETE_DEF_N   
                                  231      PVDDQ_DEF               
                                  232      M_D_MA<13>              
                                  233      PVDDQ_DEF               
                                  234      M_D_MA<17>              
                                  235      M_D_C<2>                
                                  236      PVDDQ_DEF               
                                  237      M_D_CS_N<3>             
                                  238      GND                     
                                  239      GND                     
                                  240      M_D_DQ<36>              
                                  241      GND                     
                                  242      M_D_DQ<32>              
                                  243      GND                     
                                  244      M_D_DQS_DN<4>           
                                  245      M_D_DQS_DP<4>           
                                  246      GND                     
                                  247      M_D_DQ<38>              
                                  248      GND                     
                                  249      M_D_DQ<34>              
                                  250      GND                     
                                  251      M_D_DQ<44>              
                                  252      GND                     
                                  253      M_D_DQ<40>              
                                  254      GND                     
                                  255      M_D_DQS_DN<5>           
                                  256      M_D_DQS_DP<5>           
                                  257      GND                     
                                  258      M_D_DQ<46>              
                                  259      GND                     
                                  260      M_D_DQ<42>              
                                  261      GND                     
                                  262      M_D_DQ<52>              
                                  263      GND                     
                                  264      M_D_DQ<48>              
                                  265      GND                     
                                  266      M_D_DQS_DN<6>           
                                  267      M_D_DQS_DP<6>           
                                  268      GND                     
                                  269      M_D_DQ<54>              
                                  270      GND                     
                                  271      M_D_DQ<50>              
                                  272      GND                     
                                  273      M_D_DQ<60>              
                                  274      GND                     
                                  275      M_D_DQ<56>              
                                  276      GND                     
                                  277      M_D_DQS_DN<7>           
                                  278      M_D_DQS_DP<7>           
                                  279      GND                     
                                  280      M_D_DQ<62>              
                                  281      GND                     
                                  282      M_D_DQ<58>              
                                  283      GND                     
                                  284      PVPP_DEF                
                                  285      SMB_DDR_DEF_VPP_SDA     
                                  286      PVPP_DEF                
                                  287      PVPP_DEF                
                                  288      PVPP_DEF                
J4B2             SCONN120_H61426002_SM-CONN,H61A A1       P12V_STBY               
                                  A2       P12V_STBY               
                                  A3       P12V_STBY               
                                  A4       P12V_STBY               
                                  A5       P12V_STBY               
                                  A6       P12V_STBY               
                                  A7       P12V_STBY               
                                  A8       P12V_STBY               
                                  A9       GND                     
                                  A10      GND                     
                                  A11      P3V3_STBY               
                                  A12      GND                     
                                  A13      P5V_STBY                
                                  A14      GND                     
                                  A15      FM_P1V8MCP_CPU1_EN      
                                  A16      FM_PVCCIOMCP_CPU1_EN    
                                  A17      GND                     
                                  A18      SMB_VR_STBY_LVC3_SCL    
                                  A19      SVID_ALERT0_CPU1_R_N    
                                  A20      SVID_CLK0_CPU1_R        
                                  B1       P12V_STBY               
                                  B2       P12V_STBY               
                                  B3       P12V_STBY               
                                  B4       P12V_STBY               
                                  B5       P12V_STBY               
                                  B6       P12V_STBY               
                                  B7       P12V_STBY               
                                  B8       P12V_STBY               
                                  B9       GND                     
                                  B10      GND                     
                                  B11      P3V3_STBY               
                                  B12      GND                     
                                  B13      P5V_STBY                
                                  B14      GND                     
                                  B15      PWRGD_P1V8MCP_CPU1      
                                  B16      PWRGD_PVCCIOMCP_CPU1    
                                  B17      GND                     
                                  B18      SMB_VR_STBY_LVC3_SDA    
                                  B19      SVID_ALERT1_CPU1_R_N    
                                  B20      SVID_DIO0_CPU1_R        
                                  C1       GND                     
                                  C2       GND                     
                                  C3       GND                     
                                  C4       GND                     
                                  C5       GND                     
                                  C6       GND                     
                                  C7       GND                     
                                  C8       GND                     
                                  C9       GND                     
                                  C10      GND                     
                                  C11      P3V3_STBY               
                                  C12      GND                     
                                  C13      P5V_STBY                
                                  C14      GND                     
                                  C15      GND                     
                                  C16      GND                     
                                  C17      PVCCIOMCP_CPU1          
                                  C18      PVCCIOMCP_CPU1          
                                  C19      PVCCIOMCP_CPU1          
                                  C20      FM_PVCCMCP_CPU1_EN      
                                  D1       P3V3                    
                                  D2       GND                     
                                  D3       GND                     
                                  D4       GND                     
                                  D5       GND                     
                                  D6       GND                     
                                  D7       GND                     
                                  D8       GND                     
                                  D9       GND                     
                                  D10      GND                     
                                  D11      GND                     
                                  D12      GND                     
                                  D13      GND                     
                                  D14      GND                     
                                  D15      PVCCIOMCP_CPU1          
                                  D16      PVCCIOMCP_CPU1          
                                  D17      PVCCIOMCP_CPU1          
                                  D18      PVCCIOMCP_CPU1          
                                  D19      PVCCIOMCP_CPU1          
                                  D20      PWRGD_PVCCMCP_CPU1      
                                  E1       FM_CPU1_VRM_322M_156M_OSC_EN
                                  E2       GND                     
                                  E3       GND                     
                                  E4       GND                     
                                  E5       GND                     
                                  E6       GND                     
                                  E7       GND                     
                                  E8       VSENSE_PVCCIOMCP_CPU1_SKT_VSEN
                                  E9       GND                     
                                  E10      VR_PVCCIOMCP_CPU1_XADDR1
                                  E11      GND                     
                                  E12      GND                     
                                  E13      GND                     
                                  E14      GND                     
                                  E15      PVCCIOMCP_CPU1          
                                  E16      PVCCIOMCP_CPU1          
                                  E17      PVCCIOMCP_CPU1          
                                  E18      PVCCIOMCP_CPU1          
                                  E19      PVCCIOMCP_CPU1          
                                  E20      SVID_CLK1_CPU1_R        
                                  F1       PVCCIO_CPU1             
                                  F2       GND                     
                                  F3       GND                     
                                  F4       GND                     
                                  F5       GND                     
                                  F6       GND                     
                                  F7       GND                     
                                  F8       VSENSE_PVCCIOMCP_CPU1_SKT_VRTN
                                  F9       GND                     
                                  F10      VR_PVCCMCP_CPU1_XADDR2  
                                  F11      GND                     
                                  F12      GND                     
                                  F13      GND                     
                                  F14      GND                     
                                  F15      PVCCIOMCP_CPU1          
                                  F16      PVCCIOMCP_CPU1          
                                  F17      PVCCIOMCP_CPU1          
                                  F18      PVCCIOMCP_CPU1          
                                  F19      PVCCIOMCP_CPU1          
                                  F20      SVID_DIO1_CPU1_R        
J4E1             SCONN120_H61426002_SM-CONN,H61A A1       PVCCMCP_CPU1            
                                  A2       PVCCMCP_CPU1            
                                  A3       PVCCMCP_CPU1            
                                  A4       VSENSE_PVCCMCP_CPU1_SKT_VSEN
                                  A5       PVCCMCP_CPU1            
                                  A6       PVCCMCP_CPU1            
                                  A7       PVCCMCP_CPU1            
                                  A8       PVCCMCP_CPU1            
                                  A9       PVCCMCP_CPU1            
                                  A10      PVCCMCP_CPU1            
                                  A11      PVCCMCP_CPU1            
                                  A12      PVCCMCP_CPU1            
                                  A13      PVCCMCP_CPU1            
                                  A14      PVCCMCP_CPU1            
                                  A15      PVCCMCP_CPU1            
                                  A16      PVCCMCP_CPU1            
                                  A17      PVCCMCP_CPU1            
                                  A18      PVCCMCP_CPU1            
                                  A19      GND                     
                                  A20      GND                     
                                  B1       PVCCMCP_CPU1            
                                  B2       PVCCMCP_CPU1            
                                  B3       PVCCMCP_CPU1            
                                  B4       VSENSE_PVCCMCP_CPU1_SKT_VRTN
                                  B5       PVCCMCP_CPU1            
                                  B6       PVCCMCP_CPU1            
                                  B7       PVCCMCP_CPU1            
                                  B8       PVCCMCP_CPU1            
                                  B9       PVCCMCP_CPU1            
                                  B10      PVCCMCP_CPU1            
                                  B11      PVCCMCP_CPU1            
                                  B12      PVCCMCP_CPU1            
                                  B13      PVCCMCP_CPU1            
                                  B14      PVCCMCP_CPU1            
                                  B15      PVCCMCP_CPU1            
                                  B16      PVCCMCP_CPU1            
                                  B17      PVCCMCP_CPU1            
                                  B18      PVCCMCP_CPU1            
                                  B19      GND                     
                                  B20      GND                     
                                  C1       PVCCMCP_CPU1            
                                  C2       PVCCMCP_CPU1            
                                  C3       PVCCMCP_CPU1            
                                  C4       PVCCMCP_CPU1            
                                  C5       PVCCMCP_CPU1            
                                  C6       PVCCMCP_CPU1            
                                  C7       PVCCMCP_CPU1            
                                  C8       PVCCMCP_CPU1            
                                  C9       PVCCMCP_CPU1            
                                  C10      PVCCMCP_CPU1            
                                  C11      PVCCMCP_CPU1            
                                  C12      PVCCMCP_CPU1            
                                  C13      PVCCMCP_CPU1            
                                  C14      PVCCMCP_CPU1            
                                  C15      PVCCMCP_CPU1            
                                  C16      PVCCMCP_CPU1            
                                  C17      PVCCMCP_CPU1            
                                  C18      PVCCMCP_CPU1            
                                  C19      GND                     
                                  C20      GND                     
                                  D1       VSENSE_P1V8MCP_CPU1_SKT_VSEN
                                  D2       VSENSE_P1V8MCP_CPU1_SKT_VRTN
                                  D3       GND                     
                                  D4       GND                     
                                  D5       GND                     
                                  D6       GND                     
                                  D7       GND                     
                                  D8       GND                     
                                  D9       GND                     
                                  D10      GND                     
                                  D11      GND                     
                                  D12      GND                     
                                  D13      GND                     
                                  D14      GND                     
                                  D15      GND                     
                                  D16      GND                     
                                  D17      GND                     
                                  D18      GND                     
                                  D19      GND                     
                                  D20      GND                     
                                  E1       P1V8_MCP_CPU1           
                                  E2       P1V8_MCP_CPU1           
                                  E3       GND                     
                                  E4       GND                     
                                  E5       CLK_322M_156M_CPU1_OSC_VRM_DP
                                  E6       GND                     
                                  E7       GND                     
                                  E8       GND                     
                                  E9       GND                     
                                  E10      GND                     
                                  E11      GND                     
                                  E12      GND                     
                                  E13      GND                     
                                  E14      GND                     
                                  E15      GND                     
                                  E16      GND                     
                                  E17      GND                     
                                  E18      GND                     
                                  E19      GND                     
                                  E20      GND                     
                                  F1       P1V8_MCP_CPU1           
                                  F2       P1V8_MCP_CPU1           
                                  F3       GND                     
                                  F4       GND                     
                                  F5       CLK_322M_156M_CPU1_OSC_VRM_DN
                                  F6       GND                     
                                  F7       GND                     
                                  F8       GND                     
                                  F9       GND                     
                                  F10      GND                     
                                  F11      GND                     
                                  F12      GND                     
                                  F13      GND                     
                                  F14      GND                     
                                  F15      GND                     
                                  F16      GND                     
                                  F17      GND                     
                                  F18      GND                     
                                  F19      GND                     
                                  F20      GND                     
J4G1             SCONN288_H44441004_PIP-SCONN,HA 1        P12V_NVDIMM_ABC         
                                  2        GND                     
                                  3        M_A_DQ<5>               
                                  4        GND                     
                                  5        M_A_DQ<1>               
                                  6        GND                     
                                  7        M_A_DQS_DP<9>           
                                  8        M_A_DQS_DN<9>           
                                  9        GND                     
                                  10       M_A_DQ<7>               
                                  11       GND                     
                                  12       M_A_DQ<3>               
                                  13       GND                     
                                  14       M_A_DQ<13>              
                                  15       GND                     
                                  16       M_A_DQ<9>               
                                  17       GND                     
                                  18       M_A_DQS_DP<10>          
                                  19       M_A_DQS_DN<10>          
                                  20       GND                     
                                  21       M_A_DQ<15>              
                                  22       GND                     
                                  23       M_A_DQ<11>              
                                  24       GND                     
                                  25       M_A_DQ<21>              
                                  26       GND                     
                                  27       M_A_DQ<17>              
                                  28       GND                     
                                  29       M_A_DQS_DP<11>          
                                  30       M_A_DQS_DN<11>          
                                  31       GND                     
                                  32       M_A_DQ<23>              
                                  33       GND                     
                                  34       M_A_DQ<19>              
                                  35       GND                     
                                  36       M_A_DQ<29>              
                                  37       GND                     
                                  38       M_A_DQ<25>              
                                  39       GND                     
                                  40       M_A_DQS_DP<12>          
                                  41       M_A_DQS_DN<12>          
                                  42       GND                     
                                  43       M_A_DQ<31>              
                                  44       GND                     
                                  45       M_A_DQ<27>              
                                  46       GND                     
                                  47       M_A_ECC<5>              
                                  48       GND                     
                                  49       M_A_ECC<1>              
                                  50       GND                     
                                  51       M_A_DQS_DP<17>          
                                  52       M_A_DQS_DN<17>          
                                  53       GND                     
                                  54       M_A_ECC<7>              
                                  55       GND                     
                                  56       M_A_ECC<3>              
                                  57       GND                     
                                  58       M_ABC_RST_N             
                                  59       PVDDQ_ABC               
                                  60       M_A_CKE<0>              
                                  61       PVDDQ_ABC               
                                  62       M_A_ACT_N               
                                  63       M_A_BG<0>               
                                  64       PVDDQ_ABC               
                                  65       M_A_MA<12>              
                                  66       M_A_MA<9>               
                                  67       PVDDQ_ABC               
                                  68       M_A_MA<8>               
                                  69       M_A_MA<6>               
                                  70       PVDDQ_ABC               
                                  71       M_A_MA<3>               
                                  72       M_A_MA<1>               
                                  73       PVDDQ_ABC               
                                  74       M_A_CLK_DP<0>           
                                  75       M_A_CLK_DN<0>           
                                  76       PVDDQ_ABC               
                                  77       PVTT_ABC                
                                  78       FM_DIMM_EVENT_COD_N     
                                  79       M_A_MA<0>               
                                  80       PVDDQ_ABC               
                                  81       M_A_BA<0>               
                                  82       M_A_MA<16>              
                                  83       PVDDQ_ABC               
                                  84       M_A_CS_N<0>             
                                  85       PVDDQ_ABC               
                                  86       M_A_MA<15>              
                                  87       M_A_ODT<0>              
                                  88       PVDDQ_ABC               
                                  89       M_A_CS_N<1>             
                                  90       PVDDQ_ABC               
                                  91       M_A_ODT<1>              
                                  92       PVDDQ_ABC               
                                  93       M_A_CS_N<2>             
                                  94       GND                     
                                  95       M_A_DQ<37>              
                                  96       GND                     
                                  97       M_A_DQ<33>              
                                  98       GND                     
                                  99       M_A_DQS_DP<13>          
                                  100      M_A_DQS_DN<13>          
                                  101      GND                     
                                  102      M_A_DQ<39>              
                                  103      GND                     
                                  104      M_A_DQ<35>              
                                  105      GND                     
                                  106      M_A_DQ<45>              
                                  107      GND                     
                                  108      M_A_DQ<41>              
                                  109      GND                     
                                  110      M_A_DQS_DP<14>          
                                  111      M_A_DQS_DN<14>          
                                  112      GND                     
                                  113      M_A_DQ<47>              
                                  114      GND                     
                                  115      M_A_DQ<43>              
                                  116      GND                     
                                  117      M_A_DQ<53>              
                                  118      GND                     
                                  119      M_A_DQ<49>              
                                  120      GND                     
                                  121      M_A_DQS_DP<15>          
                                  122      M_A_DQS_DN<15>          
                                  123      GND                     
                                  124      M_A_DQ<55>              
                                  125      GND                     
                                  126      M_A_DQ<51>              
                                  127      GND                     
                                  128      M_A_DQ<61>              
                                  129      GND                     
                                  130      M_A_DQ<57>              
                                  131      GND                     
                                  132      M_A_DQS_DP<16>          
                                  133      M_A_DQS_DN<16>          
                                  134      GND                     
                                  135      M_A_DQ<63>              
                                  136      GND                     
                                  137      M_A_DQ<59>              
                                  138      GND                     
                                  139      GND                     
                                  140      GND                     
                                  141      SMB_DDR_ABC_VPP_SCL     
                                  142      PVPP_ABC                
                                  143      PVPP_ABC                
                                  144      TP_CH_A_DIMM_A0_RFU_2   
                                  145      P12V_NVDIMM_ABC         
                                  146      M_A_VREF                
                                  147      GND                     
                                  148      M_A_DQ<4>               
                                  149      GND                     
                                  150      M_A_DQ<0>               
                                  151      GND                     
                                  152      M_A_DQS_DN<0>           
                                  153      M_A_DQS_DP<0>           
                                  154      GND                     
                                  155      M_A_DQ<6>               
                                  156      GND                     
                                  157      M_A_DQ<2>               
                                  158      GND                     
                                  159      M_A_DQ<12>              
                                  160      GND                     
                                  161      M_A_DQ<8>               
                                  162      GND                     
                                  163      M_A_DQS_DN<1>           
                                  164      M_A_DQS_DP<1>           
                                  165      GND                     
                                  166      M_A_DQ<14>              
                                  167      GND                     
                                  168      M_A_DQ<10>              
                                  169      GND                     
                                  170      M_A_DQ<20>              
                                  171      GND                     
                                  172      M_A_DQ<16>              
                                  173      GND                     
                                  174      M_A_DQS_DN<2>           
                                  175      M_A_DQS_DP<2>           
                                  176      GND                     
                                  177      M_A_DQ<22>              
                                  178      GND                     
                                  179      M_A_DQ<18>              
                                  180      GND                     
                                  181      M_A_DQ<28>              
                                  182      GND                     
                                  183      M_A_DQ<24>              
                                  184      GND                     
                                  185      M_A_DQS_DN<3>           
                                  186      M_A_DQS_DP<3>           
                                  187      GND                     
                                  188      M_A_DQ<30>              
                                  189      GND                     
                                  190      M_A_DQ<26>              
                                  191      GND                     
                                  192      M_A_ECC<4>              
                                  193      GND                     
                                  194      M_A_ECC<0>              
                                  195      GND                     
                                  196      M_A_DQS_DN<8>           
                                  197      M_A_DQS_DP<8>           
                                  198      GND                     
                                  199      M_A_ECC<6>              
                                  200      GND                     
                                  201      M_A_ECC<2>              
                                  202      GND                     
                                  203      M_A_CKE<1>              
                                  204      PVDDQ_ABC               
                                  205      TP_CH_A_DIMM_A0_RFU_0   
                                  206      PVDDQ_ABC               
                                  207      M_A_BG<1>               
                                  208      M_A_ALERT_N             
                                  209      PVDDQ_ABC               
                                  210      M_A_MA<11>              
                                  211      M_A_MA<7>               
                                  212      PVDDQ_ABC               
                                  213      M_A_MA<5>               
                                  214      M_A_MA<4>               
                                  215      PVDDQ_ABC               
                                  216      M_A_MA<2>               
                                  217      PVDDQ_ABC               
                                  218      M_A_CLK_DP<1>           
                                  219      M_A_CLK_DN<1>           
                                  220      PVDDQ_ABC               
                                  221      PVTT_ABC                
                                  222      M_A_PAR                 
                                  223      PVDDQ_ABC               
                                  224      M_A_BA<1>               
                                  225      M_A_MA<10>              
                                  226      PVDDQ_ABC               
                                  227      TP_CH_A_DIMM_A0_RFU_1   
                                  228      M_A_MA<14>              
                                  229      PVDDQ_ABC               
                                  230      FM_ADR_COMPLETE_ABC_N   
                                  231      PVDDQ_ABC               
                                  232      M_A_MA<13>              
                                  233      PVDDQ_ABC               
                                  234      M_A_MA<17>              
                                  235      M_A_C<2>                
                                  236      PVDDQ_ABC               
                                  237      M_A_CS_N<3>             
                                  238      GND                     
                                  239      GND                     
                                  240      M_A_DQ<36>              
                                  241      GND                     
                                  242      M_A_DQ<32>              
                                  243      GND                     
                                  244      M_A_DQS_DN<4>           
                                  245      M_A_DQS_DP<4>           
                                  246      GND                     
                                  247      M_A_DQ<38>              
                                  248      GND                     
                                  249      M_A_DQ<34>              
                                  250      GND                     
                                  251      M_A_DQ<44>              
                                  252      GND                     
                                  253      M_A_DQ<40>              
                                  254      GND                     
                                  255      M_A_DQS_DN<5>           
                                  256      M_A_DQS_DP<5>           
                                  257      GND                     
                                  258      M_A_DQ<46>              
                                  259      GND                     
                                  260      M_A_DQ<42>              
                                  261      GND                     
                                  262      M_A_DQ<52>              
                                  263      GND                     
                                  264      M_A_DQ<48>              
                                  265      GND                     
                                  266      M_A_DQS_DN<6>           
                                  267      M_A_DQS_DP<6>           
                                  268      GND                     
                                  269      M_A_DQ<54>              
                                  270      GND                     
                                  271      M_A_DQ<50>              
                                  272      GND                     
                                  273      M_A_DQ<60>              
                                  274      GND                     
                                  275      M_A_DQ<56>              
                                  276      GND                     
                                  277      M_A_DQS_DN<7>           
                                  278      M_A_DQS_DP<7>           
                                  279      GND                     
                                  280      M_A_DQ<62>              
                                  281      GND                     
                                  282      M_A_DQ<58>              
                                  283      GND                     
                                  284      PVPP_ABC                
                                  285      SMB_DDR_ABC_VPP_SDA     
                                  286      PVPP_ABC                
                                  287      PVPP_ABC                
                                  288      PVPP_ABC                
J4G2             SCONN288_H44441004_PIP-SCONN,HA 1        P12V_NVDIMM_ABC         
                                  2        GND                     
                                  3        M_B_DQ<5>               
                                  4        GND                     
                                  5        M_B_DQ<1>               
                                  6        GND                     
                                  7        M_B_DQS_DP<9>           
                                  8        M_B_DQS_DN<9>           
                                  9        GND                     
                                  10       M_B_DQ<7>               
                                  11       GND                     
                                  12       M_B_DQ<3>               
                                  13       GND                     
                                  14       M_B_DQ<13>              
                                  15       GND                     
                                  16       M_B_DQ<9>               
                                  17       GND                     
                                  18       M_B_DQS_DP<10>          
                                  19       M_B_DQS_DN<10>          
                                  20       GND                     
                                  21       M_B_DQ<15>              
                                  22       GND                     
                                  23       M_B_DQ<11>              
                                  24       GND                     
                                  25       M_B_DQ<21>              
                                  26       GND                     
                                  27       M_B_DQ<17>              
                                  28       GND                     
                                  29       M_B_DQS_DP<11>          
                                  30       M_B_DQS_DN<11>          
                                  31       GND                     
                                  32       M_B_DQ<23>              
                                  33       GND                     
                                  34       M_B_DQ<19>              
                                  35       GND                     
                                  36       M_B_DQ<29>              
                                  37       GND                     
                                  38       M_B_DQ<25>              
                                  39       GND                     
                                  40       M_B_DQS_DP<12>          
                                  41       M_B_DQS_DN<12>          
                                  42       GND                     
                                  43       M_B_DQ<31>              
                                  44       GND                     
                                  45       M_B_DQ<27>              
                                  46       GND                     
                                  47       M_B_ECC<5>              
                                  48       GND                     
                                  49       M_B_ECC<1>              
                                  50       GND                     
                                  51       M_B_DQS_DP<17>          
                                  52       M_B_DQS_DN<17>          
                                  53       GND                     
                                  54       M_B_ECC<7>              
                                  55       GND                     
                                  56       M_B_ECC<3>              
                                  57       GND                     
                                  58       M_ABC_RST_N             
                                  59       PVDDQ_ABC               
                                  60       M_B_CKE<0>              
                                  61       PVDDQ_ABC               
                                  62       M_B_ACT_N               
                                  63       M_B_BG<0>               
                                  64       PVDDQ_ABC               
                                  65       M_B_MA<12>              
                                  66       M_B_MA<9>               
                                  67       PVDDQ_ABC               
                                  68       M_B_MA<8>               
                                  69       M_B_MA<6>               
                                  70       PVDDQ_ABC               
                                  71       M_B_MA<3>               
                                  72       M_B_MA<1>               
                                  73       PVDDQ_ABC               
                                  74       M_B_CLK_DP<0>           
                                  75       M_B_CLK_DN<0>           
                                  76       PVDDQ_ABC               
                                  77       PVTT_ABC                
                                  78       FM_DIMM_EVENT_COD_N     
                                  79       M_B_MA<0>               
                                  80       PVDDQ_ABC               
                                  81       M_B_BA<0>               
                                  82       M_B_MA<16>              
                                  83       PVDDQ_ABC               
                                  84       M_B_CS_N<0>             
                                  85       PVDDQ_ABC               
                                  86       M_B_MA<15>              
                                  87       M_B_ODT<0>              
                                  88       PVDDQ_ABC               
                                  89       M_B_CS_N<1>             
                                  90       PVDDQ_ABC               
                                  91       M_B_ODT<1>              
                                  92       PVDDQ_ABC               
                                  93       M_B_CS_N<2>             
                                  94       GND                     
                                  95       M_B_DQ<37>              
                                  96       GND                     
                                  97       M_B_DQ<33>              
                                  98       GND                     
                                  99       M_B_DQS_DP<13>          
                                  100      M_B_DQS_DN<13>          
                                  101      GND                     
                                  102      M_B_DQ<39>              
                                  103      GND                     
                                  104      M_B_DQ<35>              
                                  105      GND                     
                                  106      M_B_DQ<45>              
                                  107      GND                     
                                  108      M_B_DQ<41>              
                                  109      GND                     
                                  110      M_B_DQS_DP<14>          
                                  111      M_B_DQS_DN<14>          
                                  112      GND                     
                                  113      M_B_DQ<47>              
                                  114      GND                     
                                  115      M_B_DQ<43>              
                                  116      GND                     
                                  117      M_B_DQ<53>              
                                  118      GND                     
                                  119      M_B_DQ<49>              
                                  120      GND                     
                                  121      M_B_DQS_DP<15>          
                                  122      M_B_DQS_DN<15>          
                                  123      GND                     
                                  124      M_B_DQ<55>              
                                  125      GND                     
                                  126      M_B_DQ<51>              
                                  127      GND                     
                                  128      M_B_DQ<61>              
                                  129      GND                     
                                  130      M_B_DQ<57>              
                                  131      GND                     
                                  132      M_B_DQS_DP<16>          
                                  133      M_B_DQS_DN<16>          
                                  134      GND                     
                                  135      M_B_DQ<63>              
                                  136      GND                     
                                  137      M_B_DQ<59>              
                                  138      GND                     
                                  139      GND                     
                                  140      PVPP_ABC                
                                  141      SMB_DDR_ABC_VPP_SCL     
                                  142      PVPP_ABC                
                                  143      PVPP_ABC                
                                  144      TP_CH_B_DIMM_B0_RFU_2   
                                  145      P12V_NVDIMM_ABC         
                                  146      M_B_VREF                
                                  147      GND                     
                                  148      M_B_DQ<4>               
                                  149      GND                     
                                  150      M_B_DQ<0>               
                                  151      GND                     
                                  152      M_B_DQS_DN<0>           
                                  153      M_B_DQS_DP<0>           
                                  154      GND                     
                                  155      M_B_DQ<6>               
                                  156      GND                     
                                  157      M_B_DQ<2>               
                                  158      GND                     
                                  159      M_B_DQ<12>              
                                  160      GND                     
                                  161      M_B_DQ<8>               
                                  162      GND                     
                                  163      M_B_DQS_DN<1>           
                                  164      M_B_DQS_DP<1>           
                                  165      GND                     
                                  166      M_B_DQ<14>              
                                  167      GND                     
                                  168      M_B_DQ<10>              
                                  169      GND                     
                                  170      M_B_DQ<20>              
                                  171      GND                     
                                  172      M_B_DQ<16>              
                                  173      GND                     
                                  174      M_B_DQS_DN<2>           
                                  175      M_B_DQS_DP<2>           
                                  176      GND                     
                                  177      M_B_DQ<22>              
                                  178      GND                     
                                  179      M_B_DQ<18>              
                                  180      GND                     
                                  181      M_B_DQ<28>              
                                  182      GND                     
                                  183      M_B_DQ<24>              
                                  184      GND                     
                                  185      M_B_DQS_DN<3>           
                                  186      M_B_DQS_DP<3>           
                                  187      GND                     
                                  188      M_B_DQ<30>              
                                  189      GND                     
                                  190      M_B_DQ<26>              
                                  191      GND                     
                                  192      M_B_ECC<4>              
                                  193      GND                     
                                  194      M_B_ECC<0>              
                                  195      GND                     
                                  196      M_B_DQS_DN<8>           
                                  197      M_B_DQS_DP<8>           
                                  198      GND                     
                                  199      M_B_ECC<6>              
                                  200      GND                     
                                  201      M_B_ECC<2>              
                                  202      GND                     
                                  203      M_B_CKE<1>              
                                  204      PVDDQ_ABC               
                                  205      TP_CH_B_DIMM_B0_RFU_0   
                                  206      PVDDQ_ABC               
                                  207      M_B_BG<1>               
                                  208      M_B_ALERT_N             
                                  209      PVDDQ_ABC               
                                  210      M_B_MA<11>              
                                  211      M_B_MA<7>               
                                  212      PVDDQ_ABC               
                                  213      M_B_MA<5>               
                                  214      M_B_MA<4>               
                                  215      PVDDQ_ABC               
                                  216      M_B_MA<2>               
                                  217      PVDDQ_ABC               
                                  218      M_B_CLK_DP<1>           
                                  219      M_B_CLK_DN<1>           
                                  220      PVDDQ_ABC               
                                  221      PVTT_ABC                
                                  222      M_B_PAR                 
                                  223      PVDDQ_ABC               
                                  224      M_B_BA<1>               
                                  225      M_B_MA<10>              
                                  226      PVDDQ_ABC               
                                  227      TP_CH_B_DIMM_B0_RFU_1   
                                  228      M_B_MA<14>              
                                  229      PVDDQ_ABC               
                                  230      FM_ADR_COMPLETE_ABC_N   
                                  231      PVDDQ_ABC               
                                  232      M_B_MA<13>              
                                  233      PVDDQ_ABC               
                                  234      M_B_MA<17>              
                                  235      M_B_C<2>                
                                  236      PVDDQ_ABC               
                                  237      M_B_CS_N<3>             
                                  238      GND                     
                                  239      GND                     
                                  240      M_B_DQ<36>              
                                  241      GND                     
                                  242      M_B_DQ<32>              
                                  243      GND                     
                                  244      M_B_DQS_DN<4>           
                                  245      M_B_DQS_DP<4>           
                                  246      GND                     
                                  247      M_B_DQ<38>              
                                  248      GND                     
                                  249      M_B_DQ<34>              
                                  250      GND                     
                                  251      M_B_DQ<44>              
                                  252      GND                     
                                  253      M_B_DQ<40>              
                                  254      GND                     
                                  255      M_B_DQS_DN<5>           
                                  256      M_B_DQS_DP<5>           
                                  257      GND                     
                                  258      M_B_DQ<46>              
                                  259      GND                     
                                  260      M_B_DQ<42>              
                                  261      GND                     
                                  262      M_B_DQ<52>              
                                  263      GND                     
                                  264      M_B_DQ<48>              
                                  265      GND                     
                                  266      M_B_DQS_DN<6>           
                                  267      M_B_DQS_DP<6>           
                                  268      GND                     
                                  269      M_B_DQ<54>              
                                  270      GND                     
                                  271      M_B_DQ<50>              
                                  272      GND                     
                                  273      M_B_DQ<60>              
                                  274      GND                     
                                  275      M_B_DQ<56>              
                                  276      GND                     
                                  277      M_B_DQS_DN<7>           
                                  278      M_B_DQS_DP<7>           
                                  279      GND                     
                                  280      M_B_DQ<62>              
                                  281      GND                     
                                  282      M_B_DQ<58>              
                                  283      GND                     
                                  284      PVPP_ABC                
                                  285      SMB_DDR_ABC_VPP_SDA     
                                  286      PVPP_ABC                
                                  287      PVPP_ABC                
                                  288      PVPP_ABC                
J4G3             SCONN288_H44441004_PIP-SCONN,HA 1        P12V_NVDIMM_ABC         
                                  2        GND                     
                                  3        M_C_DQ<5>               
                                  4        GND                     
                                  5        M_C_DQ<1>               
                                  6        GND                     
                                  7        M_C_DQS_DP<9>           
                                  8        M_C_DQS_DN<9>           
                                  9        GND                     
                                  10       M_C_DQ<7>               
                                  11       GND                     
                                  12       M_C_DQ<3>               
                                  13       GND                     
                                  14       M_C_DQ<13>              
                                  15       GND                     
                                  16       M_C_DQ<9>               
                                  17       GND                     
                                  18       M_C_DQS_DP<10>          
                                  19       M_C_DQS_DN<10>          
                                  20       GND                     
                                  21       M_C_DQ<15>              
                                  22       GND                     
                                  23       M_C_DQ<11>              
                                  24       GND                     
                                  25       M_C_DQ<21>              
                                  26       GND                     
                                  27       M_C_DQ<17>              
                                  28       GND                     
                                  29       M_C_DQS_DP<11>          
                                  30       M_C_DQS_DN<11>          
                                  31       GND                     
                                  32       M_C_DQ<23>              
                                  33       GND                     
                                  34       M_C_DQ<19>              
                                  35       GND                     
                                  36       M_C_DQ<29>              
                                  37       GND                     
                                  38       M_C_DQ<25>              
                                  39       GND                     
                                  40       M_C_DQS_DP<12>          
                                  41       M_C_DQS_DN<12>          
                                  42       GND                     
                                  43       M_C_DQ<31>              
                                  44       GND                     
                                  45       M_C_DQ<27>              
                                  46       GND                     
                                  47       M_C_ECC<5>              
                                  48       GND                     
                                  49       M_C_ECC<1>              
                                  50       GND                     
                                  51       M_C_DQS_DP<17>          
                                  52       M_C_DQS_DN<17>          
                                  53       GND                     
                                  54       M_C_ECC<7>              
                                  55       GND                     
                                  56       M_C_ECC<3>              
                                  57       GND                     
                                  58       M_ABC_RST_N             
                                  59       PVDDQ_ABC               
                                  60       M_C_CKE<0>              
                                  61       PVDDQ_ABC               
                                  62       M_C_ACT_N               
                                  63       M_C_BG<0>               
                                  64       PVDDQ_ABC               
                                  65       M_C_MA<12>              
                                  66       M_C_MA<9>               
                                  67       PVDDQ_ABC               
                                  68       M_C_MA<8>               
                                  69       M_C_MA<6>               
                                  70       PVDDQ_ABC               
                                  71       M_C_MA<3>               
                                  72       M_C_MA<1>               
                                  73       PVDDQ_ABC               
                                  74       M_C_CLK_DP<0>           
                                  75       M_C_CLK_DN<0>           
                                  76       PVDDQ_ABC               
                                  77       PVTT_ABC                
                                  78       FM_DIMM_EVENT_COD_N     
                                  79       M_C_MA<0>               
                                  80       PVDDQ_ABC               
                                  81       M_C_BA<0>               
                                  82       M_C_MA<16>              
                                  83       PVDDQ_ABC               
                                  84       M_C_CS_N<0>             
                                  85       PVDDQ_ABC               
                                  86       M_C_MA<15>              
                                  87       M_C_ODT<0>              
                                  88       PVDDQ_ABC               
                                  89       M_C_CS_N<1>             
                                  90       PVDDQ_ABC               
                                  91       M_C_ODT<1>              
                                  92       PVDDQ_ABC               
                                  93       M_C_CS_N<2>             
                                  94       GND                     
                                  95       M_C_DQ<37>              
                                  96       GND                     
                                  97       M_C_DQ<33>              
                                  98       GND                     
                                  99       M_C_DQS_DP<13>          
                                  100      M_C_DQS_DN<13>          
                                  101      GND                     
                                  102      M_C_DQ<39>              
                                  103      GND                     
                                  104      M_C_DQ<35>              
                                  105      GND                     
                                  106      M_C_DQ<45>              
                                  107      GND                     
                                  108      M_C_DQ<41>              
                                  109      GND                     
                                  110      M_C_DQS_DP<14>          
                                  111      M_C_DQS_DN<14>          
                                  112      GND                     
                                  113      M_C_DQ<47>              
                                  114      GND                     
                                  115      M_C_DQ<43>              
                                  116      GND                     
                                  117      M_C_DQ<53>              
                                  118      GND                     
                                  119      M_C_DQ<49>              
                                  120      GND                     
                                  121      M_C_DQS_DP<15>          
                                  122      M_C_DQS_DN<15>          
                                  123      GND                     
                                  124      M_C_DQ<55>              
                                  125      GND                     
                                  126      M_C_DQ<51>              
                                  127      GND                     
                                  128      M_C_DQ<61>              
                                  129      GND                     
                                  130      M_C_DQ<57>              
                                  131      GND                     
                                  132      M_C_DQS_DP<16>          
                                  133      M_C_DQS_DN<16>          
                                  134      GND                     
                                  135      M_C_DQ<63>              
                                  136      GND                     
                                  137      M_C_DQ<59>              
                                  138      GND                     
                                  139      GND                     
                                  140      GND                     
                                  141      SMB_DDR_ABC_VPP_SCL     
                                  142      PVPP_ABC                
                                  143      PVPP_ABC                
                                  144      TP_CH_C_DIMM_C0_RFU_2   
                                  145      P12V_NVDIMM_ABC         
                                  146      M_C_VREF                
                                  147      GND                     
                                  148      M_C_DQ<4>               
                                  149      GND                     
                                  150      M_C_DQ<0>               
                                  151      GND                     
                                  152      M_C_DQS_DN<0>           
                                  153      M_C_DQS_DP<0>           
                                  154      GND                     
                                  155      M_C_DQ<6>               
                                  156      GND                     
                                  157      M_C_DQ<2>               
                                  158      GND                     
                                  159      M_C_DQ<12>              
                                  160      GND                     
                                  161      M_C_DQ<8>               
                                  162      GND                     
                                  163      M_C_DQS_DN<1>           
                                  164      M_C_DQS_DP<1>           
                                  165      GND                     
                                  166      M_C_DQ<14>              
                                  167      GND                     
                                  168      M_C_DQ<10>              
                                  169      GND                     
                                  170      M_C_DQ<20>              
                                  171      GND                     
                                  172      M_C_DQ<16>              
                                  173      GND                     
                                  174      M_C_DQS_DN<2>           
                                  175      M_C_DQS_DP<2>           
                                  176      GND                     
                                  177      M_C_DQ<22>              
                                  178      GND                     
                                  179      M_C_DQ<18>              
                                  180      GND                     
                                  181      M_C_DQ<28>              
                                  182      GND                     
                                  183      M_C_DQ<24>              
                                  184      GND                     
                                  185      M_C_DQS_DN<3>           
                                  186      M_C_DQS_DP<3>           
                                  187      GND                     
                                  188      M_C_DQ<30>              
                                  189      GND                     
                                  190      M_C_DQ<26>              
                                  191      GND                     
                                  192      M_C_ECC<4>              
                                  193      GND                     
                                  194      M_C_ECC<0>              
                                  195      GND                     
                                  196      M_C_DQS_DN<8>           
                                  197      M_C_DQS_DP<8>           
                                  198      GND                     
                                  199      M_C_ECC<6>              
                                  200      GND                     
                                  201      M_C_ECC<2>              
                                  202      GND                     
                                  203      M_C_CKE<1>              
                                  204      PVDDQ_ABC               
                                  205      TP_CH_C_DIMM_C0_RFU_0   
                                  206      PVDDQ_ABC               
                                  207      M_C_BG<1>               
                                  208      M_C_ALERT_N             
                                  209      PVDDQ_ABC               
                                  210      M_C_MA<11>              
                                  211      M_C_MA<7>               
                                  212      PVDDQ_ABC               
                                  213      M_C_MA<5>               
                                  214      M_C_MA<4>               
                                  215      PVDDQ_ABC               
                                  216      M_C_MA<2>               
                                  217      PVDDQ_ABC               
                                  218      M_C_CLK_DP<1>           
                                  219      M_C_CLK_DN<1>           
                                  220      PVDDQ_ABC               
                                  221      PVTT_ABC                
                                  222      M_C_PAR                 
                                  223      PVDDQ_ABC               
                                  224      M_C_BA<1>               
                                  225      M_C_MA<10>              
                                  226      PVDDQ_ABC               
                                  227      TP_CH_C_DIMM_C0_RFU_1   
                                  228      M_C_MA<14>              
                                  229      PVDDQ_ABC               
                                  230      FM_ADR_COMPLETE_ABC_N   
                                  231      PVDDQ_ABC               
                                  232      M_C_MA<13>              
                                  233      PVDDQ_ABC               
                                  234      M_C_MA<17>              
                                  235      M_C_C<2>                
                                  236      PVDDQ_ABC               
                                  237      M_C_CS_N<3>             
                                  238      PVPP_ABC                
                                  239      GND                     
                                  240      M_C_DQ<36>              
                                  241      GND                     
                                  242      M_C_DQ<32>              
                                  243      GND                     
                                  244      M_C_DQS_DN<4>           
                                  245      M_C_DQS_DP<4>           
                                  246      GND                     
                                  247      M_C_DQ<38>              
                                  248      GND                     
                                  249      M_C_DQ<34>              
                                  250      GND                     
                                  251      M_C_DQ<44>              
                                  252      GND                     
                                  253      M_C_DQ<40>              
                                  254      GND                     
                                  255      M_C_DQS_DN<5>           
                                  256      M_C_DQS_DP<5>           
                                  257      GND                     
                                  258      M_C_DQ<46>              
                                  259      GND                     
                                  260      M_C_DQ<42>              
                                  261      GND                     
                                  262      M_C_DQ<52>              
                                  263      GND                     
                                  264      M_C_DQ<48>              
                                  265      GND                     
                                  266      M_C_DQS_DN<6>           
                                  267      M_C_DQS_DP<6>           
                                  268      GND                     
                                  269      M_C_DQ<54>              
                                  270      GND                     
                                  271      M_C_DQ<50>              
                                  272      GND                     
                                  273      M_C_DQ<60>              
                                  274      GND                     
                                  275      M_C_DQ<56>              
                                  276      GND                     
                                  277      M_C_DQS_DN<7>           
                                  278      M_C_DQS_DP<7>           
                                  279      GND                     
                                  280      M_C_DQ<62>              
                                  281      GND                     
                                  282      M_C_DQ<58>              
                                  283      GND                     
                                  284      PVPP_ABC                
                                  285      SMB_DDR_ABC_VPP_SDA     
                                  286      PVPP_ABC                
                                  287      PVPP_ABC                
                                  288      PVPP_ABC                
J6B1             SCONN120_H61426002_SM-CONN,H61A A1       P12V_STBY               
                                  A2       P12V_STBY               
                                  A3       P12V_STBY               
                                  A4       P12V_STBY               
                                  A5       P12V_STBY               
                                  A6       P12V_STBY               
                                  A7       P12V_STBY               
                                  A8       P12V_STBY               
                                  A9       GND                     
                                  A10      GND                     
                                  A11      P3V3_STBY               
                                  A12      GND                     
                                  A13      P5V_STBY                
                                  A14      GND                     
                                  A15      FM_P1V8MCP_CPU0_EN      
                                  A16      FM_PVCCIOMCP_CPU0_EN    
                                  A17      GND                     
                                  A18      SMB_VR_STBY_LVC3_SCL    
                                  A19      SVID_ALERT0_CPU0_R_N    
                                  A20      SVID_CLK0_CPU0_R        
                                  B1       P12V_STBY               
                                  B2       P12V_STBY               
                                  B3       P12V_STBY               
                                  B4       P12V_STBY               
                                  B5       P12V_STBY               
                                  B6       P12V_STBY               
                                  B7       P12V_STBY               
                                  B8       P12V_STBY               
                                  B9       GND                     
                                  B10      GND                     
                                  B11      P3V3_STBY               
                                  B12      GND                     
                                  B13      P5V_STBY                
                                  B14      GND                     
                                  B15      PWRGD_P1V8MCP_CPU0      
                                  B16      PWRGD_PVCCIOMCP_CPU0    
                                  B17      GND                     
                                  B18      SMB_VR_STBY_LVC3_SDA    
                                  B19      SVID_ALERT1_CPU0_R_N    
                                  B20      SVID_DIO0_CPU0_R        
                                  C1       GND                     
                                  C2       GND                     
                                  C3       GND                     
                                  C4       GND                     
                                  C5       GND                     
                                  C6       GND                     
                                  C7       GND                     
                                  C8       GND                     
                                  C9       GND                     
                                  C10      GND                     
                                  C11      P3V3_STBY               
                                  C12      GND                     
                                  C13      P5V_STBY                
                                  C14      GND                     
                                  C15      GND                     
                                  C16      GND                     
                                  C17      PVCCIOMCP_CPU0          
                                  C18      PVCCIOMCP_CPU0          
                                  C19      PVCCIOMCP_CPU0          
                                  C20      FM_PVCCMCP_CPU0_EN      
                                  D1       P3V3                    
                                  D2       GND                     
                                  D3       GND                     
                                  D4       GND                     
                                  D5       GND                     
                                  D6       GND                     
                                  D7       GND                     
                                  D8       GND                     
                                  D9       GND                     
                                  D10      GND                     
                                  D11      GND                     
                                  D12      GND                     
                                  D13      GND                     
                                  D14      GND                     
                                  D15      PVCCIOMCP_CPU0          
                                  D16      PVCCIOMCP_CPU0          
                                  D17      PVCCIOMCP_CPU0          
                                  D18      PVCCIOMCP_CPU0          
                                  D19      PVCCIOMCP_CPU0          
                                  D20      PWRGD_PVCCMCP_CPU0      
                                  E1       FM_CPU0_VRM_322M_156M_OSC_EN
                                  E2       GND                     
                                  E3       GND                     
                                  E4       GND                     
                                  E5       GND                     
                                  E6       GND                     
                                  E7       GND                     
                                  E8       VSENSE_PVCCIOMCP_CPU0_SKT_VSEN
                                  E9       GND                     
                                  E10      VR_PVCCIOMCP_CPU0_XADDR1
                                  E11      GND                     
                                  E12      GND                     
                                  E13      GND                     
                                  E14      GND                     
                                  E15      PVCCIOMCP_CPU0          
                                  E16      PVCCIOMCP_CPU0          
                                  E17      PVCCIOMCP_CPU0          
                                  E18      PVCCIOMCP_CPU0          
                                  E19      PVCCIOMCP_CPU0          
                                  E20      SVID_CLK1_CPU0_R        
                                  F1       PVCCIO_CPU0             
                                  F2       GND                     
                                  F3       GND                     
                                  F4       GND                     
                                  F5       GND                     
                                  F6       GND                     
                                  F7       GND                     
                                  F8       VSENSE_PVCCIOMCP_CPU0_SKT_VRTN
                                  F9       GND                     
                                  F10      VR_PVCCMCP_CPU0_XADDR2  
                                  F11      GND                     
                                  F12      GND                     
                                  F13      GND                     
                                  F14      GND                     
                                  F15      PVCCIOMCP_CPU0          
                                  F16      PVCCIOMCP_CPU0          
                                  F17      PVCCIOMCP_CPU0          
                                  F18      PVCCIOMCP_CPU0          
                                  F19      PVCCIOMCP_CPU0          
                                  F20      SVID_DIO1_CPU0_R        
J6E1             SCONN120_H61426002_SM-CONN,H61A A1       PVCCMCP_CPU0            
                                  A2       PVCCMCP_CPU0            
                                  A3       PVCCMCP_CPU0            
                                  A4       VSENSE_PVCCMCP_CPU0_SKT_VSEN
                                  A5       PVCCMCP_CPU0            
                                  A6       PVCCMCP_CPU0            
                                  A7       PVCCMCP_CPU0            
                                  A8       PVCCMCP_CPU0            
                                  A9       PVCCMCP_CPU0            
                                  A10      PVCCMCP_CPU0            
                                  A11      PVCCMCP_CPU0            
                                  A12      PVCCMCP_CPU0            
                                  A13      PVCCMCP_CPU0            
                                  A14      PVCCMCP_CPU0            
                                  A15      PVCCMCP_CPU0            
                                  A16      PVCCMCP_CPU0            
                                  A17      PVCCMCP_CPU0            
                                  A18      PVCCMCP_CPU0            
                                  A19      GND                     
                                  A20      GND                     
                                  B1       PVCCMCP_CPU0            
                                  B2       PVCCMCP_CPU0            
                                  B3       PVCCMCP_CPU0            
                                  B4       VSENSE_PVCCMCP_CPU0_SKT_VRTN
                                  B5       PVCCMCP_CPU0            
                                  B6       PVCCMCP_CPU0            
                                  B7       PVCCMCP_CPU0            
                                  B8       PVCCMCP_CPU0            
                                  B9       PVCCMCP_CPU0            
                                  B10      PVCCMCP_CPU0            
                                  B11      PVCCMCP_CPU0            
                                  B12      PVCCMCP_CPU0            
                                  B13      PVCCMCP_CPU0            
                                  B14      PVCCMCP_CPU0            
                                  B15      PVCCMCP_CPU0            
                                  B16      PVCCMCP_CPU0            
                                  B17      PVCCMCP_CPU0            
                                  B18      PVCCMCP_CPU0            
                                  B19      GND                     
                                  B20      GND                     
                                  C1       PVCCMCP_CPU0            
                                  C2       PVCCMCP_CPU0            
                                  C3       PVCCMCP_CPU0            
                                  C4       PVCCMCP_CPU0            
                                  C5       PVCCMCP_CPU0            
                                  C6       PVCCMCP_CPU0            
                                  C7       PVCCMCP_CPU0            
                                  C8       PVCCMCP_CPU0            
                                  C9       PVCCMCP_CPU0            
                                  C10      PVCCMCP_CPU0            
                                  C11      PVCCMCP_CPU0            
                                  C12      PVCCMCP_CPU0            
                                  C13      PVCCMCP_CPU0            
                                  C14      PVCCMCP_CPU0            
                                  C15      PVCCMCP_CPU0            
                                  C16      PVCCMCP_CPU0            
                                  C17      PVCCMCP_CPU0            
                                  C18      PVCCMCP_CPU0            
                                  C19      GND                     
                                  C20      GND                     
                                  D1       VSENSE_P1V8MCP_CPU0_SKT_VSEN
                                  D2       VSENSE_P1V8MCP_CPU0_SKT_VRTN
                                  D3       GND                     
                                  D4       GND                     
                                  D5       GND                     
                                  D6       GND                     
                                  D7       GND                     
                                  D8       GND                     
                                  D9       GND                     
                                  D10      GND                     
                                  D11      GND                     
                                  D12      GND                     
                                  D13      GND                     
                                  D14      GND                     
                                  D15      GND                     
                                  D16      GND                     
                                  D17      GND                     
                                  D18      GND                     
                                  D19      GND                     
                                  D20      GND                     
                                  E1       P1V8_MCP_CPU0           
                                  E2       P1V8_MCP_CPU0           
                                  E3       GND                     
                                  E4       GND                     
                                  E5       CLK_322M_156M_CPU0_OSC_VRM_DP
                                  E6       GND                     
                                  E7       GND                     
                                  E8       GND                     
                                  E9       GND                     
                                  E10      GND                     
                                  E11      GND                     
                                  E12      GND                     
                                  E13      GND                     
                                  E14      GND                     
                                  E15      GND                     
                                  E16      GND                     
                                  E17      GND                     
                                  E18      GND                     
                                  E19      GND                     
                                  E20      GND                     
                                  F1       P1V8_MCP_CPU0           
                                  F2       P1V8_MCP_CPU0           
                                  F3       GND                     
                                  F4       GND                     
                                  F5       CLK_322M_156M_CPU0_OSC_VRM_DN
                                  F6       GND                     
                                  F7       GND                     
                                  F8       GND                     
                                  F9       GND                     
                                  F10      GND                     
                                  F11      GND                     
                                  F12      GND                     
                                  F13      GND                     
                                  F14      GND                     
                                  F15      GND                     
                                  F16      GND                     
                                  F17      GND                     
                                  F18      GND                     
                                  F19      GND                     
                                  F20      GND                     
J6L1             SCONN288_H44441003_PIP-SCONN,HA 1        P12V_NVDIMM_DEF         
                                  2        GND                     
                                  3        M_F_DQ<4>               
                                  4        GND                     
                                  5        M_F_DQ<0>               
                                  6        GND                     
                                  7        M_F_DQS_DP<9>           
                                  8        M_F_DQS_DN<9>           
                                  9        GND                     
                                  10       M_F_DQ<6>               
                                  11       GND                     
                                  12       M_F_DQ<2>               
                                  13       GND                     
                                  14       M_F_DQ<12>              
                                  15       GND                     
                                  16       M_F_DQ<8>               
                                  17       GND                     
                                  18       M_F_DQS_DP<10>          
                                  19       M_F_DQS_DN<10>          
                                  20       GND                     
                                  21       M_F_DQ<14>              
                                  22       GND                     
                                  23       M_F_DQ<10>              
                                  24       GND                     
                                  25       M_F_DQ<20>              
                                  26       GND                     
                                  27       M_F_DQ<16>              
                                  28       GND                     
                                  29       M_F_DQS_DP<11>          
                                  30       M_F_DQS_DN<11>          
                                  31       GND                     
                                  32       M_F_DQ<22>              
                                  33       GND                     
                                  34       M_F_DQ<18>              
                                  35       GND                     
                                  36       M_F_DQ<28>              
                                  37       GND                     
                                  38       M_F_DQ<24>              
                                  39       GND                     
                                  40       M_F_DQS_DP<12>          
                                  41       M_F_DQS_DN<12>          
                                  42       GND                     
                                  43       M_F_DQ<30>              
                                  44       GND                     
                                  45       M_F_DQ<26>              
                                  46       GND                     
                                  47       M_F_ECC<4>              
                                  48       GND                     
                                  49       M_F_ECC<0>              
                                  50       GND                     
                                  51       M_F_DQS_DP<17>          
                                  52       M_F_DQS_DN<17>          
                                  53       GND                     
                                  54       M_F_ECC<6>              
                                  55       GND                     
                                  56       M_F_ECC<2>              
                                  57       GND                     
                                  58       M_DEF_RST_N             
                                  59       PVDDQ_DEF               
                                  60       M_F_CKE<2>              
                                  61       PVDDQ_DEF               
                                  62       M_F_ACT_N               
                                  63       M_F_BG<0>               
                                  64       PVDDQ_DEF               
                                  65       M_F_MA<12>              
                                  66       M_F_MA<9>               
                                  67       PVDDQ_DEF               
                                  68       M_F_MA<8>               
                                  69       M_F_MA<6>               
                                  70       PVDDQ_DEF               
                                  71       M_F_MA<3>               
                                  72       M_F_MA<1>               
                                  73       PVDDQ_DEF               
                                  74       M_F_CLK_DP<2>           
                                  75       M_F_CLK_DN<2>           
                                  76       PVDDQ_DEF               
                                  77       PVTT_DEF                
                                  78       FM_DIMM_EVENT_COD_N     
                                  79       M_F_MA<0>               
                                  80       PVDDQ_DEF               
                                  81       M_F_BA<0>               
                                  82       M_F_MA<16>              
                                  83       PVDDQ_DEF               
                                  84       M_F_CS_N<4>             
                                  85       PVDDQ_DEF               
                                  86       M_F_MA<15>              
                                  87       M_F_ODT<2>              
                                  88       PVDDQ_DEF               
                                  89       M_F_CS_N<5>             
                                  90       PVDDQ_DEF               
                                  91       M_F_ODT<3>              
                                  92       PVDDQ_DEF               
                                  93       M_F_CS_N<6>             
                                  94       GND                     
                                  95       M_F_DQ<36>              
                                  96       GND                     
                                  97       M_F_DQ<32>              
                                  98       GND                     
                                  99       M_F_DQS_DP<13>          
                                  100      M_F_DQS_DN<13>          
                                  101      GND                     
                                  102      M_F_DQ<38>              
                                  103      GND                     
                                  104      M_F_DQ<34>              
                                  105      GND                     
                                  106      M_F_DQ<44>              
                                  107      GND                     
                                  108      M_F_DQ<40>              
                                  109      GND                     
                                  110      M_F_DQS_DP<14>          
                                  111      M_F_DQS_DN<14>          
                                  112      GND                     
                                  113      M_F_DQ<46>              
                                  114      GND                     
                                  115      M_F_DQ<42>              
                                  116      GND                     
                                  117      M_F_DQ<52>              
                                  118      GND                     
                                  119      M_F_DQ<48>              
                                  120      GND                     
                                  121      M_F_DQS_DP<15>          
                                  122      M_F_DQS_DN<15>          
                                  123      GND                     
                                  124      M_F_DQ<54>              
                                  125      GND                     
                                  126      M_F_DQ<50>              
                                  127      GND                     
                                  128      M_F_DQ<60>              
                                  129      GND                     
                                  130      M_F_DQ<56>              
                                  131      GND                     
                                  132      M_F_DQS_DP<16>          
                                  133      M_F_DQS_DN<16>          
                                  134      GND                     
                                  135      M_F_DQ<62>              
                                  136      GND                     
                                  137      M_F_DQ<58>              
                                  138      GND                     
                                  139      PVPP_DEF                
                                  140      GND                     
                                  141      SMB_DDR_DEF_VPP_SCL     
                                  142      PVPP_DEF                
                                  143      PVPP_DEF                
                                  144      TP_CH_F_DIMM_F1_RFU_2   
                                  145      P12V_NVDIMM_DEF         
                                  146      M_F_VREF                
                                  147      GND                     
                                  148      M_F_DQ<5>               
                                  149      GND                     
                                  150      M_F_DQ<1>               
                                  151      GND                     
                                  152      M_F_DQS_DN<0>           
                                  153      M_F_DQS_DP<0>           
                                  154      GND                     
                                  155      M_F_DQ<7>               
                                  156      GND                     
                                  157      M_F_DQ<3>               
                                  158      GND                     
                                  159      M_F_DQ<13>              
                                  160      GND                     
                                  161      M_F_DQ<9>               
                                  162      GND                     
                                  163      M_F_DQS_DN<1>           
                                  164      M_F_DQS_DP<1>           
                                  165      GND                     
                                  166      M_F_DQ<15>              
                                  167      GND                     
                                  168      M_F_DQ<11>              
                                  169      GND                     
                                  170      M_F_DQ<21>              
                                  171      GND                     
                                  172      M_F_DQ<17>              
                                  173      GND                     
                                  174      M_F_DQS_DN<2>           
                                  175      M_F_DQS_DP<2>           
                                  176      GND                     
                                  177      M_F_DQ<23>              
                                  178      GND                     
                                  179      M_F_DQ<19>              
                                  180      GND                     
                                  181      M_F_DQ<29>              
                                  182      GND                     
                                  183      M_F_DQ<25>              
                                  184      GND                     
                                  185      M_F_DQS_DN<3>           
                                  186      M_F_DQS_DP<3>           
                                  187      GND                     
                                  188      M_F_DQ<31>              
                                  189      GND                     
                                  190      M_F_DQ<27>              
                                  191      GND                     
                                  192      M_F_ECC<5>              
                                  193      GND                     
                                  194      M_F_ECC<1>              
                                  195      GND                     
                                  196      M_F_DQS_DN<8>           
                                  197      M_F_DQS_DP<8>           
                                  198      GND                     
                                  199      M_F_ECC<7>              
                                  200      GND                     
                                  201      M_F_ECC<3>              
                                  202      GND                     
                                  203      M_F_CKE<3>              
                                  204      PVDDQ_DEF               
                                  205      TP_CH_F_DIMM_F1_RFU_0   
                                  206      PVDDQ_DEF               
                                  207      M_F_BG<1>               
                                  208      M_F_ALERT_N             
                                  209      PVDDQ_DEF               
                                  210      M_F_MA<11>              
                                  211      M_F_MA<7>               
                                  212      PVDDQ_DEF               
                                  213      M_F_MA<5>               
                                  214      M_F_MA<4>               
                                  215      PVDDQ_DEF               
                                  216      M_F_MA<2>               
                                  217      PVDDQ_DEF               
                                  218      M_F_CLK_DP<3>           
                                  219      M_F_CLK_DN<3>           
                                  220      PVDDQ_DEF               
                                  221      PVTT_DEF                
                                  222      M_F_PAR                 
                                  223      PVDDQ_DEF               
                                  224      M_F_BA<1>               
                                  225      M_F_MA<10>              
                                  226      PVDDQ_DEF               
                                  227      TP_CH_F_DIMM_F1_RFU_1   
                                  228      M_F_MA<14>              
                                  229      PVDDQ_DEF               
                                  230      FM_ADR_COMPLETE_DEF_N   
                                  231      PVDDQ_DEF               
                                  232      M_F_MA<13>              
                                  233      PVDDQ_DEF               
                                  234      M_F_MA<17>              
                                  235      M_F_C<2>                
                                  236      PVDDQ_DEF               
                                  237      M_F_CS_N<7>             
                                  238      PVPP_DEF                
                                  239      GND                     
                                  240      M_F_DQ<37>              
                                  241      GND                     
                                  242      M_F_DQ<33>              
                                  243      GND                     
                                  244      M_F_DQS_DN<4>           
                                  245      M_F_DQS_DP<4>           
                                  246      GND                     
                                  247      M_F_DQ<39>              
                                  248      GND                     
                                  249      M_F_DQ<35>              
                                  250      GND                     
                                  251      M_F_DQ<45>              
                                  252      GND                     
                                  253      M_F_DQ<41>              
                                  254      GND                     
                                  255      M_F_DQS_DN<5>           
                                  256      M_F_DQS_DP<5>           
                                  257      GND                     
                                  258      M_F_DQ<47>              
                                  259      GND                     
                                  260      M_F_DQ<43>              
                                  261      GND                     
                                  262      M_F_DQ<53>              
                                  263      GND                     
                                  264      M_F_DQ<49>              
                                  265      GND                     
                                  266      M_F_DQS_DN<6>           
                                  267      M_F_DQS_DP<6>           
                                  268      GND                     
                                  269      M_F_DQ<55>              
                                  270      GND                     
                                  271      M_F_DQ<51>              
                                  272      GND                     
                                  273      M_F_DQ<61>              
                                  274      GND                     
                                  275      M_F_DQ<57>              
                                  276      GND                     
                                  277      M_F_DQS_DN<7>           
                                  278      M_F_DQS_DP<7>           
                                  279      GND                     
                                  280      M_F_DQ<63>              
                                  281      GND                     
                                  282      M_F_DQ<59>              
                                  283      GND                     
                                  284      PVPP_DEF                
                                  285      SMB_DDR_DEF_VPP_SDA     
                                  286      PVPP_DEF                
                                  287      PVPP_DEF                
                                  288      PVPP_DEF                
J6L2             SCONN288_H44441003_PIP-SCONN,HA 1        P12V_NVDIMM_DEF         
                                  2        GND                     
                                  3        M_E_DQ<4>               
                                  4        GND                     
                                  5        M_E_DQ<0>               
                                  6        GND                     
                                  7        M_E_DQS_DP<9>           
                                  8        M_E_DQS_DN<9>           
                                  9        GND                     
                                  10       M_E_DQ<6>               
                                  11       GND                     
                                  12       M_E_DQ<2>               
                                  13       GND                     
                                  14       M_E_DQ<12>              
                                  15       GND                     
                                  16       M_E_DQ<8>               
                                  17       GND                     
                                  18       M_E_DQS_DP<10>          
                                  19       M_E_DQS_DN<10>          
                                  20       GND                     
                                  21       M_E_DQ<14>              
                                  22       GND                     
                                  23       M_E_DQ<10>              
                                  24       GND                     
                                  25       M_E_DQ<20>              
                                  26       GND                     
                                  27       M_E_DQ<16>              
                                  28       GND                     
                                  29       M_E_DQS_DP<11>          
                                  30       M_E_DQS_DN<11>          
                                  31       GND                     
                                  32       M_E_DQ<22>              
                                  33       GND                     
                                  34       M_E_DQ<18>              
                                  35       GND                     
                                  36       M_E_DQ<28>              
                                  37       GND                     
                                  38       M_E_DQ<24>              
                                  39       GND                     
                                  40       M_E_DQS_DP<12>          
                                  41       M_E_DQS_DN<12>          
                                  42       GND                     
                                  43       M_E_DQ<30>              
                                  44       GND                     
                                  45       M_E_DQ<26>              
                                  46       GND                     
                                  47       M_E_ECC<4>              
                                  48       GND                     
                                  49       M_E_ECC<0>              
                                  50       GND                     
                                  51       M_E_DQS_DP<17>          
                                  52       M_E_DQS_DN<17>          
                                  53       GND                     
                                  54       M_E_ECC<6>              
                                  55       GND                     
                                  56       M_E_ECC<2>              
                                  57       GND                     
                                  58       M_DEF_RST_N             
                                  59       PVDDQ_DEF               
                                  60       M_E_CKE<2>              
                                  61       PVDDQ_DEF               
                                  62       M_E_ACT_N               
                                  63       M_E_BG<0>               
                                  64       PVDDQ_DEF               
                                  65       M_E_MA<12>              
                                  66       M_E_MA<9>               
                                  67       PVDDQ_DEF               
                                  68       M_E_MA<8>               
                                  69       M_E_MA<6>               
                                  70       PVDDQ_DEF               
                                  71       M_E_MA<3>               
                                  72       M_E_MA<1>               
                                  73       PVDDQ_DEF               
                                  74       M_E_CLK_DP<2>           
                                  75       M_E_CLK_DN<2>           
                                  76       PVDDQ_DEF               
                                  77       PVTT_DEF                
                                  78       FM_DIMM_EVENT_COD_N     
                                  79       M_E_MA<0>               
                                  80       PVDDQ_DEF               
                                  81       M_E_BA<0>               
                                  82       M_E_MA<16>              
                                  83       PVDDQ_DEF               
                                  84       M_E_CS_N<4>             
                                  85       PVDDQ_DEF               
                                  86       M_E_MA<15>              
                                  87       M_E_ODT<2>              
                                  88       PVDDQ_DEF               
                                  89       M_E_CS_N<5>             
                                  90       PVDDQ_DEF               
                                  91       M_E_ODT<3>              
                                  92       PVDDQ_DEF               
                                  93       M_E_CS_N<6>             
                                  94       GND                     
                                  95       M_E_DQ<36>              
                                  96       GND                     
                                  97       M_E_DQ<32>              
                                  98       GND                     
                                  99       M_E_DQS_DP<13>          
                                  100      M_E_DQS_DN<13>          
                                  101      GND                     
                                  102      M_E_DQ<38>              
                                  103      GND                     
                                  104      M_E_DQ<34>              
                                  105      GND                     
                                  106      M_E_DQ<44>              
                                  107      GND                     
                                  108      M_E_DQ<40>              
                                  109      GND                     
                                  110      M_E_DQS_DP<14>          
                                  111      M_E_DQS_DN<14>          
                                  112      GND                     
                                  113      M_E_DQ<46>              
                                  114      GND                     
                                  115      M_E_DQ<42>              
                                  116      GND                     
                                  117      M_E_DQ<52>              
                                  118      GND                     
                                  119      M_E_DQ<48>              
                                  120      GND                     
                                  121      M_E_DQS_DP<15>          
                                  122      M_E_DQS_DN<15>          
                                  123      GND                     
                                  124      M_E_DQ<54>              
                                  125      GND                     
                                  126      M_E_DQ<50>              
                                  127      GND                     
                                  128      M_E_DQ<60>              
                                  129      GND                     
                                  130      M_E_DQ<56>              
                                  131      GND                     
                                  132      M_E_DQS_DP<16>          
                                  133      M_E_DQS_DN<16>          
                                  134      GND                     
                                  135      M_E_DQ<62>              
                                  136      GND                     
                                  137      M_E_DQ<58>              
                                  138      GND                     
                                  139      PVPP_DEF                
                                  140      PVPP_DEF                
                                  141      SMB_DDR_DEF_VPP_SCL     
                                  142      PVPP_DEF                
                                  143      PVPP_DEF                
                                  144      TP_CH_E_DIMM_E1_RFU_2   
                                  145      P12V_NVDIMM_DEF         
                                  146      M_E_VREF                
                                  147      GND                     
                                  148      M_E_DQ<5>               
                                  149      GND                     
                                  150      M_E_DQ<1>               
                                  151      GND                     
                                  152      M_E_DQS_DN<0>           
                                  153      M_E_DQS_DP<0>           
                                  154      GND                     
                                  155      M_E_DQ<7>               
                                  156      GND                     
                                  157      M_E_DQ<3>               
                                  158      GND                     
                                  159      M_E_DQ<13>              
                                  160      GND                     
                                  161      M_E_DQ<9>               
                                  162      GND                     
                                  163      M_E_DQS_DN<1>           
                                  164      M_E_DQS_DP<1>           
                                  165      GND                     
                                  166      M_E_DQ<15>              
                                  167      GND                     
                                  168      M_E_DQ<11>              
                                  169      GND                     
                                  170      M_E_DQ<21>              
                                  171      GND                     
                                  172      M_E_DQ<17>              
                                  173      GND                     
                                  174      M_E_DQS_DN<2>           
                                  175      M_E_DQS_DP<2>           
                                  176      GND                     
                                  177      M_E_DQ<23>              
                                  178      GND                     
                                  179      M_E_DQ<19>              
                                  180      GND                     
                                  181      M_E_DQ<29>              
                                  182      GND                     
                                  183      M_E_DQ<25>              
                                  184      GND                     
                                  185      M_E_DQS_DN<3>           
                                  186      M_E_DQS_DP<3>           
                                  187      GND                     
                                  188      M_E_DQ<31>              
                                  189      GND                     
                                  190      M_E_DQ<27>              
                                  191      GND                     
                                  192      M_E_ECC<5>              
                                  193      GND                     
                                  194      M_E_ECC<1>              
                                  195      GND                     
                                  196      M_E_DQS_DN<8>           
                                  197      M_E_DQS_DP<8>           
                                  198      GND                     
                                  199      M_E_ECC<7>              
                                  200      GND                     
                                  201      M_E_ECC<3>              
                                  202      GND                     
                                  203      M_E_CKE<3>              
                                  204      PVDDQ_DEF               
                                  205      TP_CH_E_DIMM_E1_RFU_0   
                                  206      PVDDQ_DEF               
                                  207      M_E_BG<1>               
                                  208      M_E_ALERT_N             
                                  209      PVDDQ_DEF               
                                  210      M_E_MA<11>              
                                  211      M_E_MA<7>               
                                  212      PVDDQ_DEF               
                                  213      M_E_MA<5>               
                                  214      M_E_MA<4>               
                                  215      PVDDQ_DEF               
                                  216      M_E_MA<2>               
                                  217      PVDDQ_DEF               
                                  218      M_E_CLK_DP<3>           
                                  219      M_E_CLK_DN<3>           
                                  220      PVDDQ_DEF               
                                  221      PVTT_DEF                
                                  222      M_E_PAR                 
                                  223      PVDDQ_DEF               
                                  224      M_E_BA<1>               
                                  225      M_E_MA<10>              
                                  226      PVDDQ_DEF               
                                  227      TP_CH_E_DIMM_E1_RFU_1   
                                  228      M_E_MA<14>              
                                  229      PVDDQ_DEF               
                                  230      FM_ADR_COMPLETE_DEF_N   
                                  231      PVDDQ_DEF               
                                  232      M_E_MA<13>              
                                  233      PVDDQ_DEF               
                                  234      M_E_MA<17>              
                                  235      M_E_C<2>                
                                  236      PVDDQ_DEF               
                                  237      M_E_CS_N<7>             
                                  238      GND                     
                                  239      GND                     
                                  240      M_E_DQ<37>              
                                  241      GND                     
                                  242      M_E_DQ<33>              
                                  243      GND                     
                                  244      M_E_DQS_DN<4>           
                                  245      M_E_DQS_DP<4>           
                                  246      GND                     
                                  247      M_E_DQ<39>              
                                  248      GND                     
                                  249      M_E_DQ<35>              
                                  250      GND                     
                                  251      M_E_DQ<45>              
                                  252      GND                     
                                  253      M_E_DQ<41>              
                                  254      GND                     
                                  255      M_E_DQS_DN<5>           
                                  256      M_E_DQS_DP<5>           
                                  257      GND                     
                                  258      M_E_DQ<47>              
                                  259      GND                     
                                  260      M_E_DQ<43>              
                                  261      GND                     
                                  262      M_E_DQ<53>              
                                  263      GND                     
                                  264      M_E_DQ<49>              
                                  265      GND                     
                                  266      M_E_DQS_DN<6>           
                                  267      M_E_DQS_DP<6>           
                                  268      GND                     
                                  269      M_E_DQ<55>              
                                  270      GND                     
                                  271      M_E_DQ<51>              
                                  272      GND                     
                                  273      M_E_DQ<61>              
                                  274      GND                     
                                  275      M_E_DQ<57>              
                                  276      GND                     
                                  277      M_E_DQS_DN<7>           
                                  278      M_E_DQS_DP<7>           
                                  279      GND                     
                                  280      M_E_DQ<63>              
                                  281      GND                     
                                  282      M_E_DQ<59>              
                                  283      GND                     
                                  284      PVPP_DEF                
                                  285      SMB_DDR_DEF_VPP_SDA     
                                  286      PVPP_DEF                
                                  287      PVPP_DEF                
                                  288      PVPP_DEF                
J6M1             SCONN288_H44441003_PIP-SCONN,HA 1        P12V_NVDIMM_DEF         
                                  2        GND                     
                                  3        M_D_DQ<4>               
                                  4        GND                     
                                  5        M_D_DQ<0>               
                                  6        GND                     
                                  7        M_D_DQS_DP<9>           
                                  8        M_D_DQS_DN<9>           
                                  9        GND                     
                                  10       M_D_DQ<6>               
                                  11       GND                     
                                  12       M_D_DQ<2>               
                                  13       GND                     
                                  14       M_D_DQ<12>              
                                  15       GND                     
                                  16       M_D_DQ<8>               
                                  17       GND                     
                                  18       M_D_DQS_DP<10>          
                                  19       M_D_DQS_DN<10>          
                                  20       GND                     
                                  21       M_D_DQ<14>              
                                  22       GND                     
                                  23       M_D_DQ<10>              
                                  24       GND                     
                                  25       M_D_DQ<20>              
                                  26       GND                     
                                  27       M_D_DQ<16>              
                                  28       GND                     
                                  29       M_D_DQS_DP<11>          
                                  30       M_D_DQS_DN<11>          
                                  31       GND                     
                                  32       M_D_DQ<22>              
                                  33       GND                     
                                  34       M_D_DQ<18>              
                                  35       GND                     
                                  36       M_D_DQ<28>              
                                  37       GND                     
                                  38       M_D_DQ<24>              
                                  39       GND                     
                                  40       M_D_DQS_DP<12>          
                                  41       M_D_DQS_DN<12>          
                                  42       GND                     
                                  43       M_D_DQ<30>              
                                  44       GND                     
                                  45       M_D_DQ<26>              
                                  46       GND                     
                                  47       M_D_ECC<4>              
                                  48       GND                     
                                  49       M_D_ECC<0>              
                                  50       GND                     
                                  51       M_D_DQS_DP<17>          
                                  52       M_D_DQS_DN<17>          
                                  53       GND                     
                                  54       M_D_ECC<6>              
                                  55       GND                     
                                  56       M_D_ECC<2>              
                                  57       GND                     
                                  58       M_DEF_RST_N             
                                  59       PVDDQ_DEF               
                                  60       M_D_CKE<2>              
                                  61       PVDDQ_DEF               
                                  62       M_D_ACT_N               
                                  63       M_D_BG<0>               
                                  64       PVDDQ_DEF               
                                  65       M_D_MA<12>              
                                  66       M_D_MA<9>               
                                  67       PVDDQ_DEF               
                                  68       M_D_MA<8>               
                                  69       M_D_MA<6>               
                                  70       PVDDQ_DEF               
                                  71       M_D_MA<3>               
                                  72       M_D_MA<1>               
                                  73       PVDDQ_DEF               
                                  74       M_D_CLK_DP<2>           
                                  75       M_D_CLK_DN<2>           
                                  76       PVDDQ_DEF               
                                  77       PVTT_DEF                
                                  78       FM_DIMM_EVENT_COD_N     
                                  79       M_D_MA<0>               
                                  80       PVDDQ_DEF               
                                  81       M_D_BA<0>               
                                  82       M_D_MA<16>              
                                  83       PVDDQ_DEF               
                                  84       M_D_CS_N<4>             
                                  85       PVDDQ_DEF               
                                  86       M_D_MA<15>              
                                  87       M_D_ODT<2>              
                                  88       PVDDQ_DEF               
                                  89       M_D_CS_N<5>             
                                  90       PVDDQ_DEF               
                                  91       M_D_ODT<3>              
                                  92       PVDDQ_DEF               
                                  93       M_D_CS_N<6>             
                                  94       GND                     
                                  95       M_D_DQ<36>              
                                  96       GND                     
                                  97       M_D_DQ<32>              
                                  98       GND                     
                                  99       M_D_DQS_DP<13>          
                                  100      M_D_DQS_DN<13>          
                                  101      GND                     
                                  102      M_D_DQ<38>              
                                  103      GND                     
                                  104      M_D_DQ<34>              
                                  105      GND                     
                                  106      M_D_DQ<44>              
                                  107      GND                     
                                  108      M_D_DQ<40>              
                                  109      GND                     
                                  110      M_D_DQS_DP<14>          
                                  111      M_D_DQS_DN<14>          
                                  112      GND                     
                                  113      M_D_DQ<46>              
                                  114      GND                     
                                  115      M_D_DQ<42>              
                                  116      GND                     
                                  117      M_D_DQ<52>              
                                  118      GND                     
                                  119      M_D_DQ<48>              
                                  120      GND                     
                                  121      M_D_DQS_DP<15>          
                                  122      M_D_DQS_DN<15>          
                                  123      GND                     
                                  124      M_D_DQ<54>              
                                  125      GND                     
                                  126      M_D_DQ<50>              
                                  127      GND                     
                                  128      M_D_DQ<60>              
                                  129      GND                     
                                  130      M_D_DQ<56>              
                                  131      GND                     
                                  132      M_D_DQS_DP<16>          
                                  133      M_D_DQS_DN<16>          
                                  134      GND                     
                                  135      M_D_DQ<62>              
                                  136      GND                     
                                  137      M_D_DQ<58>              
                                  138      GND                     
                                  139      PVPP_DEF                
                                  140      GND                     
                                  141      SMB_DDR_DEF_VPP_SCL     
                                  142      PVPP_DEF                
                                  143      PVPP_DEF                
                                  144      TP_CH_D_DIMM_D1_RFU_2   
                                  145      P12V_NVDIMM_DEF         
                                  146      M_D_VREF                
                                  147      GND                     
                                  148      M_D_DQ<5>               
                                  149      GND                     
                                  150      M_D_DQ<1>               
                                  151      GND                     
                                  152      M_D_DQS_DN<0>           
                                  153      M_D_DQS_DP<0>           
                                  154      GND                     
                                  155      M_D_DQ<7>               
                                  156      GND                     
                                  157      M_D_DQ<3>               
                                  158      GND                     
                                  159      M_D_DQ<13>              
                                  160      GND                     
                                  161      M_D_DQ<9>               
                                  162      GND                     
                                  163      M_D_DQS_DN<1>           
                                  164      M_D_DQS_DP<1>           
                                  165      GND                     
                                  166      M_D_DQ<15>              
                                  167      GND                     
                                  168      M_D_DQ<11>              
                                  169      GND                     
                                  170      M_D_DQ<21>              
                                  171      GND                     
                                  172      M_D_DQ<17>              
                                  173      GND                     
                                  174      M_D_DQS_DN<2>           
                                  175      M_D_DQS_DP<2>           
                                  176      GND                     
                                  177      M_D_DQ<23>              
                                  178      GND                     
                                  179      M_D_DQ<19>              
                                  180      GND                     
                                  181      M_D_DQ<29>              
                                  182      GND                     
                                  183      M_D_DQ<25>              
                                  184      GND                     
                                  185      M_D_DQS_DN<3>           
                                  186      M_D_DQS_DP<3>           
                                  187      GND                     
                                  188      M_D_DQ<31>              
                                  189      GND                     
                                  190      M_D_DQ<27>              
                                  191      GND                     
                                  192      M_D_ECC<5>              
                                  193      GND                     
                                  194      M_D_ECC<1>              
                                  195      GND                     
                                  196      M_D_DQS_DN<8>           
                                  197      M_D_DQS_DP<8>           
                                  198      GND                     
                                  199      M_D_ECC<7>              
                                  200      GND                     
                                  201      M_D_ECC<3>              
                                  202      GND                     
                                  203      M_D_CKE<3>              
                                  204      PVDDQ_DEF               
                                  205      TP_CH_D_DIMM_D1_RFU_0   
                                  206      PVDDQ_DEF               
                                  207      M_D_BG<1>               
                                  208      M_D_ALERT_N             
                                  209      PVDDQ_DEF               
                                  210      M_D_MA<11>              
                                  211      M_D_MA<7>               
                                  212      PVDDQ_DEF               
                                  213      M_D_MA<5>               
                                  214      M_D_MA<4>               
                                  215      PVDDQ_DEF               
                                  216      M_D_MA<2>               
                                  217      PVDDQ_DEF               
                                  218      M_D_CLK_DP<3>           
                                  219      M_D_CLK_DN<3>           
                                  220      PVDDQ_DEF               
                                  221      PVTT_DEF                
                                  222      M_D_PAR                 
                                  223      PVDDQ_DEF               
                                  224      M_D_BA<1>               
                                  225      M_D_MA<10>              
                                  226      PVDDQ_DEF               
                                  227      TP_CH_D_DIMM_D1_RFU_1   
                                  228      M_D_MA<14>              
                                  229      PVDDQ_DEF               
                                  230      FM_ADR_COMPLETE_DEF_N   
                                  231      PVDDQ_DEF               
                                  232      M_D_MA<13>              
                                  233      PVDDQ_DEF               
                                  234      M_D_MA<17>              
                                  235      M_D_C<2>                
                                  236      PVDDQ_DEF               
                                  237      M_D_CS_N<7>             
                                  238      GND                     
                                  239      GND                     
                                  240      M_D_DQ<37>              
                                  241      GND                     
                                  242      M_D_DQ<33>              
                                  243      GND                     
                                  244      M_D_DQS_DN<4>           
                                  245      M_D_DQS_DP<4>           
                                  246      GND                     
                                  247      M_D_DQ<39>              
                                  248      GND                     
                                  249      M_D_DQ<35>              
                                  250      GND                     
                                  251      M_D_DQ<45>              
                                  252      GND                     
                                  253      M_D_DQ<41>              
                                  254      GND                     
                                  255      M_D_DQS_DN<5>           
                                  256      M_D_DQS_DP<5>           
                                  257      GND                     
                                  258      M_D_DQ<47>              
                                  259      GND                     
                                  260      M_D_DQ<43>              
                                  261      GND                     
                                  262      M_D_DQ<53>              
                                  263      GND                     
                                  264      M_D_DQ<49>              
                                  265      GND                     
                                  266      M_D_DQS_DN<6>           
                                  267      M_D_DQS_DP<6>           
                                  268      GND                     
                                  269      M_D_DQ<55>              
                                  270      GND                     
                                  271      M_D_DQ<51>              
                                  272      GND                     
                                  273      M_D_DQ<61>              
                                  274      GND                     
                                  275      M_D_DQ<57>              
                                  276      GND                     
                                  277      M_D_DQS_DN<7>           
                                  278      M_D_DQS_DP<7>           
                                  279      GND                     
                                  280      M_D_DQ<63>              
                                  281      GND                     
                                  282      M_D_DQ<59>              
                                  283      GND                     
                                  284      PVPP_DEF                
                                  285      SMB_DDR_DEF_VPP_SDA     
                                  286      PVPP_DEF                
                                  287      PVPP_DEF                
                                  288      PVPP_DEF                
J6T1             SCONN288_H44441003_PIP-SCONN,HA 1        P12V_NVDIMM_ABC         
                                  2        GND                     
                                  3        M_A_DQ<4>               
                                  4        GND                     
                                  5        M_A_DQ<0>               
                                  6        GND                     
                                  7        M_A_DQS_DP<9>           
                                  8        M_A_DQS_DN<9>           
                                  9        GND                     
                                  10       M_A_DQ<6>               
                                  11       GND                     
                                  12       M_A_DQ<2>               
                                  13       GND                     
                                  14       M_A_DQ<12>              
                                  15       GND                     
                                  16       M_A_DQ<8>               
                                  17       GND                     
                                  18       M_A_DQS_DP<10>          
                                  19       M_A_DQS_DN<10>          
                                  20       GND                     
                                  21       M_A_DQ<14>              
                                  22       GND                     
                                  23       M_A_DQ<10>              
                                  24       GND                     
                                  25       M_A_DQ<20>              
                                  26       GND                     
                                  27       M_A_DQ<16>              
                                  28       GND                     
                                  29       M_A_DQS_DP<11>          
                                  30       M_A_DQS_DN<11>          
                                  31       GND                     
                                  32       M_A_DQ<22>              
                                  33       GND                     
                                  34       M_A_DQ<18>              
                                  35       GND                     
                                  36       M_A_DQ<28>              
                                  37       GND                     
                                  38       M_A_DQ<24>              
                                  39       GND                     
                                  40       M_A_DQS_DP<12>          
                                  41       M_A_DQS_DN<12>          
                                  42       GND                     
                                  43       M_A_DQ<30>              
                                  44       GND                     
                                  45       M_A_DQ<26>              
                                  46       GND                     
                                  47       M_A_ECC<4>              
                                  48       GND                     
                                  49       M_A_ECC<0>              
                                  50       GND                     
                                  51       M_A_DQS_DP<17>          
                                  52       M_A_DQS_DN<17>          
                                  53       GND                     
                                  54       M_A_ECC<6>              
                                  55       GND                     
                                  56       M_A_ECC<2>              
                                  57       GND                     
                                  58       M_ABC_RST_N             
                                  59       PVDDQ_ABC               
                                  60       M_A_CKE<2>              
                                  61       PVDDQ_ABC               
                                  62       M_A_ACT_N               
                                  63       M_A_BG<0>               
                                  64       PVDDQ_ABC               
                                  65       M_A_MA<12>              
                                  66       M_A_MA<9>               
                                  67       PVDDQ_ABC               
                                  68       M_A_MA<8>               
                                  69       M_A_MA<6>               
                                  70       PVDDQ_ABC               
                                  71       M_A_MA<3>               
                                  72       M_A_MA<1>               
                                  73       PVDDQ_ABC               
                                  74       M_A_CLK_DP<2>           
                                  75       M_A_CLK_DN<2>           
                                  76       PVDDQ_ABC               
                                  77       PVTT_ABC                
                                  78       FM_DIMM_EVENT_COD_N     
                                  79       M_A_MA<0>               
                                  80       PVDDQ_ABC               
                                  81       M_A_BA<0>               
                                  82       M_A_MA<16>              
                                  83       PVDDQ_ABC               
                                  84       M_A_CS_N<4>             
                                  85       PVDDQ_ABC               
                                  86       M_A_MA<15>              
                                  87       M_A_ODT<2>              
                                  88       PVDDQ_ABC               
                                  89       M_A_CS_N<5>             
                                  90       PVDDQ_ABC               
                                  91       M_A_ODT<3>              
                                  92       PVDDQ_ABC               
                                  93       M_A_CS_N<6>             
                                  94       GND                     
                                  95       M_A_DQ<36>              
                                  96       GND                     
                                  97       M_A_DQ<32>              
                                  98       GND                     
                                  99       M_A_DQS_DP<13>          
                                  100      M_A_DQS_DN<13>          
                                  101      GND                     
                                  102      M_A_DQ<38>              
                                  103      GND                     
                                  104      M_A_DQ<34>              
                                  105      GND                     
                                  106      M_A_DQ<44>              
                                  107      GND                     
                                  108      M_A_DQ<40>              
                                  109      GND                     
                                  110      M_A_DQS_DP<14>          
                                  111      M_A_DQS_DN<14>          
                                  112      GND                     
                                  113      M_A_DQ<46>              
                                  114      GND                     
                                  115      M_A_DQ<42>              
                                  116      GND                     
                                  117      M_A_DQ<52>              
                                  118      GND                     
                                  119      M_A_DQ<48>              
                                  120      GND                     
                                  121      M_A_DQS_DP<15>          
                                  122      M_A_DQS_DN<15>          
                                  123      GND                     
                                  124      M_A_DQ<54>              
                                  125      GND                     
                                  126      M_A_DQ<50>              
                                  127      GND                     
                                  128      M_A_DQ<60>              
                                  129      GND                     
                                  130      M_A_DQ<56>              
                                  131      GND                     
                                  132      M_A_DQS_DP<16>          
                                  133      M_A_DQS_DN<16>          
                                  134      GND                     
                                  135      M_A_DQ<62>              
                                  136      GND                     
                                  137      M_A_DQ<58>              
                                  138      GND                     
                                  139      PVPP_ABC                
                                  140      GND                     
                                  141      SMB_DDR_ABC_VPP_SCL     
                                  142      PVPP_ABC                
                                  143      PVPP_ABC                
                                  144      TP_CH_A_DIMM_A1_RFU_2   
                                  145      P12V_NVDIMM_ABC         
                                  146      M_A_VREF                
                                  147      GND                     
                                  148      M_A_DQ<5>               
                                  149      GND                     
                                  150      M_A_DQ<1>               
                                  151      GND                     
                                  152      M_A_DQS_DN<0>           
                                  153      M_A_DQS_DP<0>           
                                  154      GND                     
                                  155      M_A_DQ<7>               
                                  156      GND                     
                                  157      M_A_DQ<3>               
                                  158      GND                     
                                  159      M_A_DQ<13>              
                                  160      GND                     
                                  161      M_A_DQ<9>               
                                  162      GND                     
                                  163      M_A_DQS_DN<1>           
                                  164      M_A_DQS_DP<1>           
                                  165      GND                     
                                  166      M_A_DQ<15>              
                                  167      GND                     
                                  168      M_A_DQ<11>              
                                  169      GND                     
                                  170      M_A_DQ<21>              
                                  171      GND                     
                                  172      M_A_DQ<17>              
                                  173      GND                     
                                  174      M_A_DQS_DN<2>           
                                  175      M_A_DQS_DP<2>           
                                  176      GND                     
                                  177      M_A_DQ<23>              
                                  178      GND                     
                                  179      M_A_DQ<19>              
                                  180      GND                     
                                  181      M_A_DQ<29>              
                                  182      GND                     
                                  183      M_A_DQ<25>              
                                  184      GND                     
                                  185      M_A_DQS_DN<3>           
                                  186      M_A_DQS_DP<3>           
                                  187      GND                     
                                  188      M_A_DQ<31>              
                                  189      GND                     
                                  190      M_A_DQ<27>              
                                  191      GND                     
                                  192      M_A_ECC<5>              
                                  193      GND                     
                                  194      M_A_ECC<1>              
                                  195      GND                     
                                  196      M_A_DQS_DN<8>           
                                  197      M_A_DQS_DP<8>           
                                  198      GND                     
                                  199      M_A_ECC<7>              
                                  200      GND                     
                                  201      M_A_ECC<3>              
                                  202      GND                     
                                  203      M_A_CKE<3>              
                                  204      PVDDQ_ABC               
                                  205      TP_CH_A_DIMM_A1_RFU_0   
                                  206      PVDDQ_ABC               
                                  207      M_A_BG<1>               
                                  208      M_A_ALERT_N             
                                  209      PVDDQ_ABC               
                                  210      M_A_MA<11>              
                                  211      M_A_MA<7>               
                                  212      PVDDQ_ABC               
                                  213      M_A_MA<5>               
                                  214      M_A_MA<4>               
                                  215      PVDDQ_ABC               
                                  216      M_A_MA<2>               
                                  217      PVDDQ_ABC               
                                  218      M_A_CLK_DP<3>           
                                  219      M_A_CLK_DN<3>           
                                  220      PVDDQ_ABC               
                                  221      PVTT_ABC                
                                  222      M_A_PAR                 
                                  223      PVDDQ_ABC               
                                  224      M_A_BA<1>               
                                  225      M_A_MA<10>              
                                  226      PVDDQ_ABC               
                                  227      TP_CH_A_DIMM_A1_RFU_1   
                                  228      M_A_MA<14>              
                                  229      PVDDQ_ABC               
                                  230      FM_ADR_COMPLETE_ABC_N   
                                  231      PVDDQ_ABC               
                                  232      M_A_MA<13>              
                                  233      PVDDQ_ABC               
                                  234      M_A_MA<17>              
                                  235      M_A_C<2>                
                                  236      PVDDQ_ABC               
                                  237      M_A_CS_N<7>             
                                  238      GND                     
                                  239      GND                     
                                  240      M_A_DQ<37>              
                                  241      GND                     
                                  242      M_A_DQ<33>              
                                  243      GND                     
                                  244      M_A_DQS_DN<4>           
                                  245      M_A_DQS_DP<4>           
                                  246      GND                     
                                  247      M_A_DQ<39>              
                                  248      GND                     
                                  249      M_A_DQ<35>              
                                  250      GND                     
                                  251      M_A_DQ<45>              
                                  252      GND                     
                                  253      M_A_DQ<41>              
                                  254      GND                     
                                  255      M_A_DQS_DN<5>           
                                  256      M_A_DQS_DP<5>           
                                  257      GND                     
                                  258      M_A_DQ<47>              
                                  259      GND                     
                                  260      M_A_DQ<43>              
                                  261      GND                     
                                  262      M_A_DQ<53>              
                                  263      GND                     
                                  264      M_A_DQ<49>              
                                  265      GND                     
                                  266      M_A_DQS_DN<6>           
                                  267      M_A_DQS_DP<6>           
                                  268      GND                     
                                  269      M_A_DQ<55>              
                                  270      GND                     
                                  271      M_A_DQ<51>              
                                  272      GND                     
                                  273      M_A_DQ<61>              
                                  274      GND                     
                                  275      M_A_DQ<57>              
                                  276      GND                     
                                  277      M_A_DQS_DN<7>           
                                  278      M_A_DQS_DP<7>           
                                  279      GND                     
                                  280      M_A_DQ<63>              
                                  281      GND                     
                                  282      M_A_DQ<59>              
                                  283      GND                     
                                  284      PVPP_ABC                
                                  285      SMB_DDR_ABC_VPP_SDA     
                                  286      PVPP_ABC                
                                  287      PVPP_ABC                
                                  288      PVPP_ABC                
J6U1             SCONN288_H44441003_PIP-SCONN,HA 1        P12V_NVDIMM_ABC         
                                  2        GND                     
                                  3        M_B_DQ<4>               
                                  4        GND                     
                                  5        M_B_DQ<0>               
                                  6        GND                     
                                  7        M_B_DQS_DP<9>           
                                  8        M_B_DQS_DN<9>           
                                  9        GND                     
                                  10       M_B_DQ<6>               
                                  11       GND                     
                                  12       M_B_DQ<2>               
                                  13       GND                     
                                  14       M_B_DQ<12>              
                                  15       GND                     
                                  16       M_B_DQ<8>               
                                  17       GND                     
                                  18       M_B_DQS_DP<10>          
                                  19       M_B_DQS_DN<10>          
                                  20       GND                     
                                  21       M_B_DQ<14>              
                                  22       GND                     
                                  23       M_B_DQ<10>              
                                  24       GND                     
                                  25       M_B_DQ<20>              
                                  26       GND                     
                                  27       M_B_DQ<16>              
                                  28       GND                     
                                  29       M_B_DQS_DP<11>          
                                  30       M_B_DQS_DN<11>          
                                  31       GND                     
                                  32       M_B_DQ<22>              
                                  33       GND                     
                                  34       M_B_DQ<18>              
                                  35       GND                     
                                  36       M_B_DQ<28>              
                                  37       GND                     
                                  38       M_B_DQ<24>              
                                  39       GND                     
                                  40       M_B_DQS_DP<12>          
                                  41       M_B_DQS_DN<12>          
                                  42       GND                     
                                  43       M_B_DQ<30>              
                                  44       GND                     
                                  45       M_B_DQ<26>              
                                  46       GND                     
                                  47       M_B_ECC<4>              
                                  48       GND                     
                                  49       M_B_ECC<0>              
                                  50       GND                     
                                  51       M_B_DQS_DP<17>          
                                  52       M_B_DQS_DN<17>          
                                  53       GND                     
                                  54       M_B_ECC<6>              
                                  55       GND                     
                                  56       M_B_ECC<2>              
                                  57       GND                     
                                  58       M_ABC_RST_N             
                                  59       PVDDQ_ABC               
                                  60       M_B_CKE<2>              
                                  61       PVDDQ_ABC               
                                  62       M_B_ACT_N               
                                  63       M_B_BG<0>               
                                  64       PVDDQ_ABC               
                                  65       M_B_MA<12>              
                                  66       M_B_MA<9>               
                                  67       PVDDQ_ABC               
                                  68       M_B_MA<8>               
                                  69       M_B_MA<6>               
                                  70       PVDDQ_ABC               
                                  71       M_B_MA<3>               
                                  72       M_B_MA<1>               
                                  73       PVDDQ_ABC               
                                  74       M_B_CLK_DP<2>           
                                  75       M_B_CLK_DN<2>           
                                  76       PVDDQ_ABC               
                                  77       PVTT_ABC                
                                  78       FM_DIMM_EVENT_COD_N     
                                  79       M_B_MA<0>               
                                  80       PVDDQ_ABC               
                                  81       M_B_BA<0>               
                                  82       M_B_MA<16>              
                                  83       PVDDQ_ABC               
                                  84       M_B_CS_N<4>             
                                  85       PVDDQ_ABC               
                                  86       M_B_MA<15>              
                                  87       M_B_ODT<2>              
                                  88       PVDDQ_ABC               
                                  89       M_B_CS_N<5>             
                                  90       PVDDQ_ABC               
                                  91       M_B_ODT<3>              
                                  92       PVDDQ_ABC               
                                  93       M_B_CS_N<6>             
                                  94       GND                     
                                  95       M_B_DQ<36>              
                                  96       GND                     
                                  97       M_B_DQ<32>              
                                  98       GND                     
                                  99       M_B_DQS_DP<13>          
                                  100      M_B_DQS_DN<13>          
                                  101      GND                     
                                  102      M_B_DQ<38>              
                                  103      GND                     
                                  104      M_B_DQ<34>              
                                  105      GND                     
                                  106      M_B_DQ<44>              
                                  107      GND                     
                                  108      M_B_DQ<40>              
                                  109      GND                     
                                  110      M_B_DQS_DP<14>          
                                  111      M_B_DQS_DN<14>          
                                  112      GND                     
                                  113      M_B_DQ<46>              
                                  114      GND                     
                                  115      M_B_DQ<42>              
                                  116      GND                     
                                  117      M_B_DQ<52>              
                                  118      GND                     
                                  119      M_B_DQ<48>              
                                  120      GND                     
                                  121      M_B_DQS_DP<15>          
                                  122      M_B_DQS_DN<15>          
                                  123      GND                     
                                  124      M_B_DQ<54>              
                                  125      GND                     
                                  126      M_B_DQ<50>              
                                  127      GND                     
                                  128      M_B_DQ<60>              
                                  129      GND                     
                                  130      M_B_DQ<56>              
                                  131      GND                     
                                  132      M_B_DQS_DP<16>          
                                  133      M_B_DQS_DN<16>          
                                  134      GND                     
                                  135      M_B_DQ<62>              
                                  136      GND                     
                                  137      M_B_DQ<58>              
                                  138      GND                     
                                  139      PVPP_ABC                
                                  140      PVPP_ABC                
                                  141      SMB_DDR_ABC_VPP_SCL     
                                  142      PVPP_ABC                
                                  143      PVPP_ABC                
                                  144      TP_CH_B_DIMM_B1_RFU_2   
                                  145      P12V_NVDIMM_ABC         
                                  146      M_B_VREF                
                                  147      GND                     
                                  148      M_B_DQ<5>               
                                  149      GND                     
                                  150      M_B_DQ<1>               
                                  151      GND                     
                                  152      M_B_DQS_DN<0>           
                                  153      M_B_DQS_DP<0>           
                                  154      GND                     
                                  155      M_B_DQ<7>               
                                  156      GND                     
                                  157      M_B_DQ<3>               
                                  158      GND                     
                                  159      M_B_DQ<13>              
                                  160      GND                     
                                  161      M_B_DQ<9>               
                                  162      GND                     
                                  163      M_B_DQS_DN<1>           
                                  164      M_B_DQS_DP<1>           
                                  165      GND                     
                                  166      M_B_DQ<15>              
                                  167      GND                     
                                  168      M_B_DQ<11>              
                                  169      GND                     
                                  170      M_B_DQ<21>              
                                  171      GND                     
                                  172      M_B_DQ<17>              
                                  173      GND                     
                                  174      M_B_DQS_DN<2>           
                                  175      M_B_DQS_DP<2>           
                                  176      GND                     
                                  177      M_B_DQ<23>              
                                  178      GND                     
                                  179      M_B_DQ<19>              
                                  180      GND                     
                                  181      M_B_DQ<29>              
                                  182      GND                     
                                  183      M_B_DQ<25>              
                                  184      GND                     
                                  185      M_B_DQS_DN<3>           
                                  186      M_B_DQS_DP<3>           
                                  187      GND                     
                                  188      M_B_DQ<31>              
                                  189      GND                     
                                  190      M_B_DQ<27>              
                                  191      GND                     
                                  192      M_B_ECC<5>              
                                  193      GND                     
                                  194      M_B_ECC<1>              
                                  195      GND                     
                                  196      M_B_DQS_DN<8>           
                                  197      M_B_DQS_DP<8>           
                                  198      GND                     
                                  199      M_B_ECC<7>              
                                  200      GND                     
                                  201      M_B_ECC<3>              
                                  202      GND                     
                                  203      M_B_CKE<3>              
                                  204      PVDDQ_ABC               
                                  205      TP_CH_B_DIMM_B1_RFU_0   
                                  206      PVDDQ_ABC               
                                  207      M_B_BG<1>               
                                  208      M_B_ALERT_N             
                                  209      PVDDQ_ABC               
                                  210      M_B_MA<11>              
                                  211      M_B_MA<7>               
                                  212      PVDDQ_ABC               
                                  213      M_B_MA<5>               
                                  214      M_B_MA<4>               
                                  215      PVDDQ_ABC               
                                  216      M_B_MA<2>               
                                  217      PVDDQ_ABC               
                                  218      M_B_CLK_DP<3>           
                                  219      M_B_CLK_DN<3>           
                                  220      PVDDQ_ABC               
                                  221      PVTT_ABC                
                                  222      M_B_PAR                 
                                  223      PVDDQ_ABC               
                                  224      M_B_BA<1>               
                                  225      M_B_MA<10>              
                                  226      PVDDQ_ABC               
                                  227      TP_CH_B_DIMM_B1_RFU_1   
                                  228      M_B_MA<14>              
                                  229      PVDDQ_ABC               
                                  230      FM_ADR_COMPLETE_ABC_N   
                                  231      PVDDQ_ABC               
                                  232      M_B_MA<13>              
                                  233      PVDDQ_ABC               
                                  234      M_B_MA<17>              
                                  235      M_B_C<2>                
                                  236      PVDDQ_ABC               
                                  237      M_B_CS_N<7>             
                                  238      GND                     
                                  239      GND                     
                                  240      M_B_DQ<37>              
                                  241      GND                     
                                  242      M_B_DQ<33>              
                                  243      GND                     
                                  244      M_B_DQS_DN<4>           
                                  245      M_B_DQS_DP<4>           
                                  246      GND                     
                                  247      M_B_DQ<39>              
                                  248      GND                     
                                  249      M_B_DQ<35>              
                                  250      GND                     
                                  251      M_B_DQ<45>              
                                  252      GND                     
                                  253      M_B_DQ<41>              
                                  254      GND                     
                                  255      M_B_DQS_DN<5>           
                                  256      M_B_DQS_DP<5>           
                                  257      GND                     
                                  258      M_B_DQ<47>              
                                  259      GND                     
                                  260      M_B_DQ<43>              
                                  261      GND                     
                                  262      M_B_DQ<53>              
                                  263      GND                     
                                  264      M_B_DQ<49>              
                                  265      GND                     
                                  266      M_B_DQS_DN<6>           
                                  267      M_B_DQS_DP<6>           
                                  268      GND                     
                                  269      M_B_DQ<55>              
                                  270      GND                     
                                  271      M_B_DQ<51>              
                                  272      GND                     
                                  273      M_B_DQ<61>              
                                  274      GND                     
                                  275      M_B_DQ<57>              
                                  276      GND                     
                                  277      M_B_DQS_DN<7>           
                                  278      M_B_DQS_DP<7>           
                                  279      GND                     
                                  280      M_B_DQ<63>              
                                  281      GND                     
                                  282      M_B_DQ<59>              
                                  283      GND                     
                                  284      PVPP_ABC                
                                  285      SMB_DDR_ABC_VPP_SDA     
                                  286      PVPP_ABC                
                                  287      PVPP_ABC                
                                  288      PVPP_ABC                
J6U2             SCONN288_H44441003_PIP-SCONN,HA 1        P12V_NVDIMM_ABC         
                                  2        GND                     
                                  3        M_C_DQ<4>               
                                  4        GND                     
                                  5        M_C_DQ<0>               
                                  6        GND                     
                                  7        M_C_DQS_DP<9>           
                                  8        M_C_DQS_DN<9>           
                                  9        GND                     
                                  10       M_C_DQ<6>               
                                  11       GND                     
                                  12       M_C_DQ<2>               
                                  13       GND                     
                                  14       M_C_DQ<12>              
                                  15       GND                     
                                  16       M_C_DQ<8>               
                                  17       GND                     
                                  18       M_C_DQS_DP<10>          
                                  19       M_C_DQS_DN<10>          
                                  20       GND                     
                                  21       M_C_DQ<14>              
                                  22       GND                     
                                  23       M_C_DQ<10>              
                                  24       GND                     
                                  25       M_C_DQ<20>              
                                  26       GND                     
                                  27       M_C_DQ<16>              
                                  28       GND                     
                                  29       M_C_DQS_DP<11>          
                                  30       M_C_DQS_DN<11>          
                                  31       GND                     
                                  32       M_C_DQ<22>              
                                  33       GND                     
                                  34       M_C_DQ<18>              
                                  35       GND                     
                                  36       M_C_DQ<28>              
                                  37       GND                     
                                  38       M_C_DQ<24>              
                                  39       GND                     
                                  40       M_C_DQS_DP<12>          
                                  41       M_C_DQS_DN<12>          
                                  42       GND                     
                                  43       M_C_DQ<30>              
                                  44       GND                     
                                  45       M_C_DQ<26>              
                                  46       GND                     
                                  47       M_C_ECC<4>              
                                  48       GND                     
                                  49       M_C_ECC<0>              
                                  50       GND                     
                                  51       M_C_DQS_DP<17>          
                                  52       M_C_DQS_DN<17>          
                                  53       GND                     
                                  54       M_C_ECC<6>              
                                  55       GND                     
                                  56       M_C_ECC<2>              
                                  57       GND                     
                                  58       M_ABC_RST_N             
                                  59       PVDDQ_ABC               
                                  60       M_C_CKE<2>              
                                  61       PVDDQ_ABC               
                                  62       M_C_ACT_N               
                                  63       M_C_BG<0>               
                                  64       PVDDQ_ABC               
                                  65       M_C_MA<12>              
                                  66       M_C_MA<9>               
                                  67       PVDDQ_ABC               
                                  68       M_C_MA<8>               
                                  69       M_C_MA<6>               
                                  70       PVDDQ_ABC               
                                  71       M_C_MA<3>               
                                  72       M_C_MA<1>               
                                  73       PVDDQ_ABC               
                                  74       M_C_CLK_DP<2>           
                                  75       M_C_CLK_DN<2>           
                                  76       PVDDQ_ABC               
                                  77       PVTT_ABC                
                                  78       FM_DIMM_EVENT_COD_N     
                                  79       M_C_MA<0>               
                                  80       PVDDQ_ABC               
                                  81       M_C_BA<0>               
                                  82       M_C_MA<16>              
                                  83       PVDDQ_ABC               
                                  84       M_C_CS_N<4>             
                                  85       PVDDQ_ABC               
                                  86       M_C_MA<15>              
                                  87       M_C_ODT<2>              
                                  88       PVDDQ_ABC               
                                  89       M_C_CS_N<5>             
                                  90       PVDDQ_ABC               
                                  91       M_C_ODT<3>              
                                  92       PVDDQ_ABC               
                                  93       M_C_CS_N<6>             
                                  94       GND                     
                                  95       M_C_DQ<36>              
                                  96       GND                     
                                  97       M_C_DQ<32>              
                                  98       GND                     
                                  99       M_C_DQS_DP<13>          
                                  100      M_C_DQS_DN<13>          
                                  101      GND                     
                                  102      M_C_DQ<38>              
                                  103      GND                     
                                  104      M_C_DQ<34>              
                                  105      GND                     
                                  106      M_C_DQ<44>              
                                  107      GND                     
                                  108      M_C_DQ<40>              
                                  109      GND                     
                                  110      M_C_DQS_DP<14>          
                                  111      M_C_DQS_DN<14>          
                                  112      GND                     
                                  113      M_C_DQ<46>              
                                  114      GND                     
                                  115      M_C_DQ<42>              
                                  116      GND                     
                                  117      M_C_DQ<52>              
                                  118      GND                     
                                  119      M_C_DQ<48>              
                                  120      GND                     
                                  121      M_C_DQS_DP<15>          
                                  122      M_C_DQS_DN<15>          
                                  123      GND                     
                                  124      M_C_DQ<54>              
                                  125      GND                     
                                  126      M_C_DQ<50>              
                                  127      GND                     
                                  128      M_C_DQ<60>              
                                  129      GND                     
                                  130      M_C_DQ<56>              
                                  131      GND                     
                                  132      M_C_DQS_DP<16>          
                                  133      M_C_DQS_DN<16>          
                                  134      GND                     
                                  135      M_C_DQ<62>              
                                  136      GND                     
                                  137      M_C_DQ<58>              
                                  138      GND                     
                                  139      PVPP_ABC                
                                  140      GND                     
                                  141      SMB_DDR_ABC_VPP_SCL     
                                  142      PVPP_ABC                
                                  143      PVPP_ABC                
                                  144      TP_CH_C_DIMM_C1_RFU_2   
                                  145      P12V_NVDIMM_ABC         
                                  146      M_C_VREF                
                                  147      GND                     
                                  148      M_C_DQ<5>               
                                  149      GND                     
                                  150      M_C_DQ<1>               
                                  151      GND                     
                                  152      M_C_DQS_DN<0>           
                                  153      M_C_DQS_DP<0>           
                                  154      GND                     
                                  155      M_C_DQ<7>               
                                  156      GND                     
                                  157      M_C_DQ<3>               
                                  158      GND                     
                                  159      M_C_DQ<13>              
                                  160      GND                     
                                  161      M_C_DQ<9>               
                                  162      GND                     
                                  163      M_C_DQS_DN<1>           
                                  164      M_C_DQS_DP<1>           
                                  165      GND                     
                                  166      M_C_DQ<15>              
                                  167      GND                     
                                  168      M_C_DQ<11>              
                                  169      GND                     
                                  170      M_C_DQ<21>              
                                  171      GND                     
                                  172      M_C_DQ<17>              
                                  173      GND                     
                                  174      M_C_DQS_DN<2>           
                                  175      M_C_DQS_DP<2>           
                                  176      GND                     
                                  177      M_C_DQ<23>              
                                  178      GND                     
                                  179      M_C_DQ<19>              
                                  180      GND                     
                                  181      M_C_DQ<29>              
                                  182      GND                     
                                  183      M_C_DQ<25>              
                                  184      GND                     
                                  185      M_C_DQS_DN<3>           
                                  186      M_C_DQS_DP<3>           
                                  187      GND                     
                                  188      M_C_DQ<31>              
                                  189      GND                     
                                  190      M_C_DQ<27>              
                                  191      GND                     
                                  192      M_C_ECC<5>              
                                  193      GND                     
                                  194      M_C_ECC<1>              
                                  195      GND                     
                                  196      M_C_DQS_DN<8>           
                                  197      M_C_DQS_DP<8>           
                                  198      GND                     
                                  199      M_C_ECC<7>              
                                  200      GND                     
                                  201      M_C_ECC<3>              
                                  202      GND                     
                                  203      M_C_CKE<3>              
                                  204      PVDDQ_ABC               
                                  205      TP_CH_C_DIMM_C1_RFU_0   
                                  206      PVDDQ_ABC               
                                  207      M_C_BG<1>               
                                  208      M_C_ALERT_N             
                                  209      PVDDQ_ABC               
                                  210      M_C_MA<11>              
                                  211      M_C_MA<7>               
                                  212      PVDDQ_ABC               
                                  213      M_C_MA<5>               
                                  214      M_C_MA<4>               
                                  215      PVDDQ_ABC               
                                  216      M_C_MA<2>               
                                  217      PVDDQ_ABC               
                                  218      M_C_CLK_DP<3>           
                                  219      M_C_CLK_DN<3>           
                                  220      PVDDQ_ABC               
                                  221      PVTT_ABC                
                                  222      M_C_PAR                 
                                  223      PVDDQ_ABC               
                                  224      M_C_BA<1>               
                                  225      M_C_MA<10>              
                                  226      PVDDQ_ABC               
                                  227      TP_CH_C_DIMM_C1_RFU_1   
                                  228      M_C_MA<14>              
                                  229      PVDDQ_ABC               
                                  230      FM_ADR_COMPLETE_ABC_N   
                                  231      PVDDQ_ABC               
                                  232      M_C_MA<13>              
                                  233      PVDDQ_ABC               
                                  234      M_C_MA<17>              
                                  235      M_C_C<2>                
                                  236      PVDDQ_ABC               
                                  237      M_C_CS_N<7>             
                                  238      PVPP_ABC                
                                  239      GND                     
                                  240      M_C_DQ<37>              
                                  241      GND                     
                                  242      M_C_DQ<33>              
                                  243      GND                     
                                  244      M_C_DQS_DN<4>           
                                  245      M_C_DQS_DP<4>           
                                  246      GND                     
                                  247      M_C_DQ<39>              
                                  248      GND                     
                                  249      M_C_DQ<35>              
                                  250      GND                     
                                  251      M_C_DQ<45>              
                                  252      GND                     
                                  253      M_C_DQ<41>              
                                  254      GND                     
                                  255      M_C_DQS_DN<5>           
                                  256      M_C_DQS_DP<5>           
                                  257      GND                     
                                  258      M_C_DQ<47>              
                                  259      GND                     
                                  260      M_C_DQ<43>              
                                  261      GND                     
                                  262      M_C_DQ<53>              
                                  263      GND                     
                                  264      M_C_DQ<49>              
                                  265      GND                     
                                  266      M_C_DQS_DN<6>           
                                  267      M_C_DQS_DP<6>           
                                  268      GND                     
                                  269      M_C_DQ<55>              
                                  270      GND                     
                                  271      M_C_DQ<51>              
                                  272      GND                     
                                  273      M_C_DQ<61>              
                                  274      GND                     
                                  275      M_C_DQ<57>              
                                  276      GND                     
                                  277      M_C_DQS_DN<7>           
                                  278      M_C_DQS_DP<7>           
                                  279      GND                     
                                  280      M_C_DQ<63>              
                                  281      GND                     
                                  282      M_C_DQ<59>              
                                  283      GND                     
                                  284      PVPP_ABC                
                                  285      SMB_DDR_ABC_VPP_SDA     
                                  286      PVPP_ABC                
                                  287      PVPP_ABC                
                                  288      PVPP_ABC                
J7G2             CONN8_C77962004_PIP-CONN,C7796A 1        P3V3_STBY_PLD_D         
                                  2        JTAG_TDO_R              
                                  3        JTAG_TDI_R              
                                  4        JTAG_TRST_N             
                                  5        PWRGD_P3V3_STBY         
                                  6        JTAG_TMS_R              
                                  7        GND                     
                                  8        JTAG_TCK_R              
J7G3             CONN12_C73564003_PIP-CONN,C735A 1        TP_ME_RCVR_BOOT         
                                  2        TP_BIOS_USB_RECOVERY    
                                  3        FM_ME_RECOVER_N         
                                  4        FM_BIOS_USB_RECOVERY    
                                  5        PD_ME_RCVR_N            
                                  6        PU_BIOS_USB_RECOVERY    
                                  7        TP_PASSWORD_CLEAR       
                                  8        TP_BIOS_RECOVER_BOOT    
                                  9        FM_PASSWORD_CLEAR_N     
                                  10       FM_BIOS_TOP_SWAP        
                                  11       PD_PASSWORD_CLEAR       
                                  12       PU_BIOS_RECOVER_BOOT    
J8A1             CONN72_G97614002_A_CP-CONN,G97A 1A1      TP_FM_QAT_CBL_PRSNT0_R_N
                                  1A2      SGPIO_PCH_SATA_CLOCK_R  
                                  1A3      GND                     
                                  1A4      SATA6G_P1_RX_C_DP       
                                  1A5      SATA6G_P1_RX_C_DN       
                                  1A6      GND                     
                                  1A7      SATA6G_P3_RX_C_DP       
                                  1A8      SATA6G_P3_RX_C_DN       
                                  1A9      GND                     
                                  1B1      GND                     
                                  1B2      SGPIO_PCH_SATA_LOAD_R   
                                  1B3      GND                     
                                  1B4      SATA6G_P0_RX_C_DP       
                                  1B5      SATA6G_P0_RX_C_DN       
                                  1B6      GND                     
                                  1B7      SATA6G_P2_RX_C_DP       
                                  1B8      SATA6G_P2_RX_C_DN       
                                  1B9      GND                     
                                  1C1      SGPIO_PCH_SATA_DOUT0_R  
                                  1C2      GND                     
                                  1C3      GND                     
                                  1C4      SATA6G_P1_TX_C_DP       
                                  1C5      SATA6G_P1_TX_C_DN       
                                  1C6      GND                     
                                  1C7      SATA6G_P3_TX_C_DP       
                                  1C8      SATA6G_P3_TX_C_DN       
                                  1C9      GND                     
                                  1D1      PU_DATAIN1_SATA_0_R     
                                  1D2      PD_SATA0_CONTROLLER_TYPE_R
                                  1D3      GND                     
                                  1D4      SATA6G_P0_TX_C_DP       
                                  1D5      SATA6G_P0_TX_C_DN       
                                  1D6      GND                     
                                  1D7      SATA6G_P2_TX_C_DP       
                                  1D8      SATA6G_P2_TX_C_DN       
                                  1D9      GND                     
                                  2A1      TP_FM_QAT_CBL_PRSNT1_N_R
                                  2A2      TP_SGPIO_SATA_CLOCK1_R  
                                  2A3      GND                     
                                  2A4      SATA6G_P5_RX_C_DP       
                                  2A5      SATA6G_P5_RX_C_DN       
                                  2A6      GND                     
                                  2A7      SATA6G_P7_RX_C_DP       
                                  2A8      SATA6G_P7_RX_C_DN       
                                  2A9      GND                     
                                  2B1      GND                     
                                  2B2      TP_SGPIO_SATA_LOAD1_R   
                                  2B3      GND                     
                                  2B4      SATA6G_P4_RX_C_DP       
                                  2B5      SATA6G_P4_RX_C_DN       
                                  2B6      GND                     
                                  2B7      SATA6G_P6_RX_C_DP       
                                  2B8      SATA6G_P6_RX_C_DN       
                                  2B9      GND                     
                                  2C1      TP_SGPIO_SATA_DATA1_R   
                                  2C2      GND                     
                                  2C3      GND                     
                                  2C4      SATA6G_P5_TX_C_DP       
                                  2C5      SATA6G_P5_TX_C_DN       
                                  2C6      GND                     
                                  2C7      SATA6G_P7_TX_C_DP       
                                  2C8      SATA6G_P7_TX_C_DN       
                                  2C9      GND                     
                                  2D1      PU_DATAIN1_SATA_1_R     
                                  2D2      PD_SATA1_CONTROLLER_TYPE_R
                                  2D3      GND                     
                                  2D4      SATA6G_P4_TX_C_DP       
                                  2D5      SATA6G_P4_TX_C_DN       
                                  2D6      GND                     
                                  2D7      SATA6G_P6_TX_C_DP       
                                  2D8      SATA6G_P6_TX_C_DN       
                                  2D9      GND                     
J8A2             CONN36_G97614001_CP-CONN,G9761A A1       TP_FM_QAT_CBL_PRSNT2_N  
                                  A2       SGPIO_PCH_SSATA_CLOCK_R 
                                  A3       GND                     
                                  A4       SATA6G_P9_RX_C_DP       
                                  A5       SATA6G_P9_RX_C_DN       
                                  A6       GND                     
                                  A7       SATA6G_P11_RX_C_DP      
                                  A8       SATA6G_P11_RX_C_DN      
                                  A9       GND                     
                                  B1       GND                     
                                  B2       SGPIO_PCH_SSATA_LOAD_R  
                                  B3       GND                     
                                  B4       SATA6G_P8_RX_C_DP       
                                  B5       SATA6G_P8_RX_C_DN       
                                  B6       GND                     
                                  B7       SATA6G_P10_RX_C_DP      
                                  B8       SATA6G_P10_RX_C_DN      
                                  B9       GND                     
                                  C1       SGPIO_PCH_SSATA_DOUT0_R 
                                  C2       GND                     
                                  C3       GND                     
                                  C4       SATA6G_P9_TX_C_DP       
                                  C5       SATA6G_P9_TX_C_DN       
                                  C6       GND                     
                                  C7       SATA6G_P11_TX_C_DP      
                                  C8       SATA6G_P11_TX_C_DN      
                                  C9       GND                     
                                  D1       PU_DATAIN1_SATA_2       
                                  D2       PD_SATA2_CONTROLLER_TYPE
                                  D3       GND                     
                                  D4       SATA6G_P8_TX_C_DP       
                                  D5       SATA6G_P8_TX_C_DN       
                                  D6       GND                     
                                  D7       SATA6G_P10_TX_C_DP      
                                  D8       SATA6G_P10_TX_C_DN      
                                  D9       GND                     
J8A3             CONN7_E82125014_PIP_TH-EMPTY,EA 1        GND                     
                                  2        SATA6G_S1_TX_C_DP       
                                  3        SATA6G_S1_TX_C_DN       
                                  4        GND                     
                                  5        SATA6G_S1_RX_C_DN       
                                  6        SATA6G_S1_RX_C_DP       
                                  7        GND                     
                                  MH1      GND                     
                                  MH2      GND                     
J8A4             CONN4_H73295001_PIP-EMPTY,H732A 1        P5V_HDD_SATA            
                                  2        GND                     
                                  3        GND                     
                                  4        P12V_HDD_SATA           
J8B1             SCONN24_H46321001_SM-SCONN,H46A 1        GND                     
                                  2        SMB_HFI0_CPU0_LVC2_SCL  
                                  3        FM_MODPRST_HFI0_CPU0_LVT2_N
                                  4        SMB_HFI0_CPU0_LVC2_SDA  
                                  5        LED_HFI0_CPU0_N         
                                  6        RST_HFI0_CPU0_LVT2_N    
                                  7        GND                     
                                  8        IRQ_HFI0_CPU0_LVT2_N    
                                  9        GND                     
                                  10       SMB_HFI1_CPU0_LVC2_SCL  
                                  11       FM_MODPRST_HFI1_CPU0_LVT2_N
                                  12       SMB_HFI1_CPU0_LVC2_SDA  
                                  13       LED_HFI1_CPU0_N         
                                  14       RST_HFI1_CPU0_LVT2_N    
                                  15       GND                     
                                  16       IRQ_HFI1_CPU0_LVT2_N    
                                  17       TP_HFI_IO_CONN0_RSVD_17 
                                  18       P3V3                    
                                  19       PWRGD_PVPP_ABC          
                                  20       P3V3                    
                                  21       PVPP_ABC                
                                  22       SMB_OCP_FRU_STBY_LVC3_SCL
                                  23       GND                     
                                  24       SMB_OCP_FRU_STBY_LVC3_SDA
                                  MP1      GND                     
                                  MP2      GND                     
J8C1             CONN3_C95678002_PIP-CONN,C9567A 1        SMB_HOST_STBY_LVC3_SDA  
                                  2        GND                     
                                  3        SMB_HOST_STBY_LVC3_SCL  
J8D4             CONN3_C95678002_PIP-CONN,C9567A 1        SMB_VR_STBY_LVC3_SDA    
                                  2        GND                     
                                  3        SMB_VR_STBY_LVC3_SCL    
J8E1             SCONN11_H67026001_SM-CONN,H670A 1        SPI_PCH_TPM_CLK_R       
                                  2        RST_PLTRST_BUF_N        
                                  3        SPI_PCH_TPM_MOSI_R      
                                  4        SPI_PCH_TPM_MISO_R      
                                  5        SPI_PCH_TPM_CS_R_N      
                                  6        SMB_SENSOR_STBY_LVC3_SDA
                                  7        P3V3_STBY               
                                  8        FM_TPM_PRES_N           
                                  9        IRQ_SPI_TPM_N_R         
                                  10       SMB_SENSOR_STBY_LVC3_SCL
                                  11       GND                     
                                  MP1      GND                     
                                  MP2      GND                     
J8E3             SCONN80_E67482007_SM-CONN,E674A 1        FM_MEZZ_PRSNTB1_N       
                                  2        P12V_STBY               
                                  3        GND                     
                                  4        P12V_STBY               
                                  5        P3E_CPU0_PE3_OCP_RXP<7> 
                                  6        TP_RSVD_B1              
                                  7        P3E_CPU0_PE3_OCP_RXN<7> 
                                  8        GND                     
                                  9        GND                     
                                  10       P3E_OCP_CPU0_PE3_C_TXP<7>
                                  11       GND                     
                                  12       P3E_OCP_CPU0_PE3_C_TXN<7>
                                  13       P3E_CPU0_PE3_OCP_RXN<6> 
                                  14       GND                     
                                  15       P3E_CPU0_PE3_OCP_RXP<6> 
                                  16       GND                     
                                  17       GND                     
                                  18       P3E_OCP_CPU0_PE3_C_TXP<6>
                                  19       GND                     
                                  20       P3E_OCP_CPU0_PE3_C_TXN<6>
                                  21       P3E_CPU0_PE3_OCP_RXN<5> 
                                  22       GND                     
                                  23       P3E_CPU0_PE3_OCP_RXP<5> 
                                  24       GND                     
                                  25       GND                     
                                  26       P3E_OCP_CPU0_PE3_C_TXP<5>
                                  27       GND                     
                                  28       P3E_OCP_CPU0_PE3_C_TXN<5>
                                  29       P3E_CPU0_PE3_OCP_RXN<4> 
                                  30       GND                     
                                  31       P3E_CPU0_PE3_OCP_RXP<4> 
                                  32       GND                     
                                  33       GND                     
                                  34       P3E_OCP_CPU0_PE3_C_TXP<4>
                                  35       GND                     
                                  36       P3E_OCP_CPU0_PE3_C_TXN<4>
                                  37       P3E_CPU0_PE3_OCP_RXP<3> 
                                  38       GND                     
                                  39       P3E_CPU0_PE3_OCP_RXN<3> 
                                  40       GND                     
                                  41       GND                     
                                  42       P3E_OCP_CPU0_PE3_C_TXP<3>
                                  43       GND                     
                                  44       P3E_OCP_CPU0_PE3_C_TXN<3>
                                  45       P3E_CPU0_PE3_OCP_RXP<2> 
                                  46       GND                     
                                  47       P3E_CPU0_PE3_OCP_RXN<2> 
                                  48       GND                     
                                  49       GND                     
                                  50       P3E_OCP_CPU0_PE3_C_TXP<2>
                                  51       GND                     
                                  52       P3E_OCP_CPU0_PE3_C_TXN<2>
                                  53       P3E_CPU0_PE3_OCP_RXP<1> 
                                  54       GND                     
                                  55       P3E_CPU0_PE3_OCP_RXN<1> 
                                  56       GND                     
                                  57       GND                     
                                  58       P3E_OCP_CPU0_PE3_C_TXP<1>
                                  59       GND                     
                                  60       P3E_OCP_CPU0_PE3_C_TXN<1>
                                  61       P3E_CPU0_PE3_OCP_RXP<0> 
                                  62       GND                     
                                  63       P3E_CPU0_PE3_OCP_RXN<0> 
                                  64       GND                     
                                  65       GND                     
                                  66       P3E_OCP_CPU0_PE3_C_TXP<0>
                                  67       GND                     
                                  68       P3E_OCP_CPU0_PE3_C_TXN<0>
                                  69       CLK_100M_MEZZ3_DP       
                                  70       GND                     
                                  71       CLK_100M_MEZZ3_DN       
                                  72       GND                     
                                  73       GND                     
                                  74       CLK_100M_MEZZ4_DP       
                                  75       RST_PCIE_CPU_DEV1_R_N   
                                  76       CLK_100M_MEZZ4_DN       
                                  77       RST_PCIE_CPU_DEV2_R_N   
                                  78       GND                     
                                  79       RST_PCIE_CPU_DEV3_R_N   
                                  80       FM_OCP_MEZZB_PRES_N     
J8E4             SCONN64_H87568002_A_SMT-CONN,HA 1        SMB_OCP_FRU_STBY_LVC3_SCL
                                  2        SMB_OCP_FRU_STBY_LVC3_SDA
                                  3        TP_EXT_MDIO_I2C_SEL     
                                  4        GND                     
                                  5        KR_P2_OCP_TX_DP         
                                  6        KR_P2_OCP_TX_DN         
                                  7        GND                     
                                  8        LED_GBE_P1_0            
                                  9        LED_GBE_P1_1            
                                  10       GND                     
                                  11       KR_P3_OCP_TX_DP         
                                  12       KR_P3_OCP_TX_DN         
                                  13       GND                     
                                  14       LED_GBE_P2_0            
                                  15       LED_GBE_P2_1            
                                  16       GND                     
                                  17       KR_P2_OCP_RX_DP         
                                  18       KR_P2_OCP_RX_DN         
                                  19       GND                     
                                  20       SMB_PCH_MEZZ_LOM0_SCL   
                                  21       SMB_PCH_MEZZ_LOM0_SDA   
                                  22       GND                     
                                  23       KR_P3_OCP_RX_DP         
                                  24       KR_P3_OCP_RX_DN         
                                  25       GND                     
                                  26       SMB_PCH_MEZZ_LOM1_SCL   
                                  27       SMB_PCH_MEZZ_LOM1_SDA   
                                  28       GND                     
                                  29       SMB_PCH_MEZZ_LOM3_SCL   
                                  30       SMB_PCH_MEZZ_LOM3_SDA   
                                  31       FM_GBE2_LVC3_MOD_ABS    
                                  32       FM_GBE3_LVC3_MOD_ABS    
                                  33       P12V_STBY               
                                  34       P12V_STBY               
                                  35       P12V_STBY               
                                  36       TP_RSVD<0>              
                                  37       FM_GBE0_LVC3_MOD_ABS    
                                  38       FM_GBE1_LVC3_MOD_ABS    
                                  39       GND                     
                                  40       KR_P0_OCP_TX_DP         
                                  41       KR_P0_OCP_TX_DN         
                                  42       GND                     
                                  43       LED_GBE_P0_0            
                                  44       LED_GBE_P0_1            
                                  45       GND                     
                                  46       KR_P1_OCP_TX_DP         
                                  47       KR_P1_OCP_TX_DN         
                                  48       GND                     
                                  49       TP_SHARED_KR_MDC_0      
                                  50       TP_SHARED_KR_MDIO_0     
                                  51       GND                     
                                  52       KR_P0_OCP_RX_DP         
                                  53       KR_P0_OCP_RX_DN         
                                  54       GND                     
                                  55       LED_GBE_P3_0            
                                  56       LED_GBE_P3_1            
                                  57       GND                     
                                  58       KR_P1_OCP_RX_DP         
                                  59       KR_P1_OCP_RX_DN         
                                  60       GND                     
                                  61       SMB_PCH_MEZZ_LOM2_SCL   
                                  62       SMB_PCH_MEZZ_LOM2_SDA   
                                  63       GND                     
                                  64       FM_OCP_MEZZC_PRES_N     
J8F1             SCONN75K_H17033002_SMT1-SCONN,A 1        GND                     
                                  2        P3V3                    
                                  3        GND                     
                                  4        P3V3                    
                                  5        P3E_PCH_M2_RX_DN<3>     
                                  6        NC_M2<0>                
                                  7        P3E_PCH_M2_RX_DP<3>     
                                  8        NC_M2<1>                
                                  9        GND                     
                                  10       TP_LED_M2_ACT_N         
                                  11       P3E_PCH_M2_TX_C_DN<3>   
                                  12       P3V3                    
                                  13       P3E_PCH_M2_TX_C_DP<3>   
                                  14       P3V3                    
                                  15       GND                     
                                  16       P3V3                    
                                  17       P3E_PCH_M2_RX_DN<2>     
                                  18       P3V3                    
                                  19       P3E_PCH_M2_RX_DP<2>     
                                  20       NC_M2<2>                
                                  21       GND                     
                                  22       NC_M2<3>                
                                  23       P3E_PCH_M2_TX_C_DN<2>   
                                  24       NC_M2<4>                
                                  25       P3E_PCH_M2_TX_C_DP<2>   
                                  26       NC_M2<5>                
                                  27       GND                     
                                  28       NC_M2<6>                
                                  29       P3E_PCH_M2_RX_DN<1>     
                                  30       NC_M2<7>                
                                  31       P3E_PCH_M2_RX_DP<1>     
                                  32       NC_M2<8>                
                                  33       GND                     
                                  34       NC_M2<9>                
                                  35       P3E_PCH_M2_TX_C_DN<1>   
                                  36       NC_M2<10>               
                                  37       P3E_PCH_M2_TX_C_DP<1>   
                                  38       TP_M2_DEVSLP            
                                  39       GND                     
                                  40       NC_M2<11>               
                                  41       P3E_PCH_M2_SATA6G_RX_R_DP
                                  42       NC_M2<12>               
                                  43       P3E_PCH_M2_SATA6G_RX_R_DN
                                  44       NC_M2<13>               
                                  45       GND                     
                                  46       NC_M2<14>               
                                  47       P3E_PCH_M2_SATA6G_TX_R_DN
                                  48       NC_M2<15>               
                                  49       P3E_PCH_M2_SATA6G_TX_R_DP
                                  50       RST_PCIE_M2_DEV_N       
                                  51       GND                     
                                  52       PU_M2_CLK_REQ_N         
                                  53       CLK_100M_M2_DN          
                                  54       FM_PE_M2_WAKE_N         
                                  55       CLK_100M_M2_DP          
                                  56       NC_M2<16>               
                                  57       GND                     
                                  58       NC_M2<17>               
                                  67       NC_M2<18>               
                                  68       TP_M2_32M_SUSCLK        
                                  69       FM_M2_SSD_PEDET         
                                  70       P3V3                    
                                  71       GND                     
                                  72       P3V3                    
                                  73       GND                     
                                  74       P3V3                    
                                  75       GND                     
                                  MP1      GND                     
                                  MP2      GND                     
J8G1             SCONN200_H68296001_SM-CONN,H68A 1        P12V                    
                                  2        P12V                    
                                  3        P12V                    
                                  4        P12V                    
                                  5        P12V                    
                                  6        P12V                    
                                  7        P12V                    
                                  8        P12V                    
                                  9        P12V                    
                                  10       P12V                    
                                  11       P12V                    
                                  12       P12V                    
                                  13       GND                     
                                  14       GND                     
                                  15       SMB_SLOTX24_STBY_LVC3_SDA_R2
                                  16       IRQ_OOB_MGMT_RISER_ALERT_N
                                  17       SMB_SLOTX24_STBY_LVC3_SCL_R2
                                  18       FM_SLT_CFG1             
                                  19       FM_SLT_CFG0             
                                  20       FM_PWRBRK_SLOT_N        
                                  21       P3V3                    
                                  22       P3V3                    
                                  23       P3V3                    
                                  24       P3V3                    
                                  25       P3V3_STBY               
                                  26       GND                     
                                  27       FM_PRSNT_2_1_N          
                                  28       FM_PE_SLOTX24_WAKE_N    
                                  29       RST_PCIE_RISER1_PERST_R_N
                                  30       FM_PRSNT_2_2_N          
                                  31       GND                     
                                  32       FM_PRSNT_2_3_N          
                                  33       CLK_100M_PCH_SLOTX24_S0_DP
                                  34       GND                     
                                  35       CLK_100M_PCH_SLOTX24_S0_DN
                                  36       CLK_100M_PCH_SLOTX24_S1_DP
                                  37       GND                     
                                  38       CLK_100M_PCH_SLOTX24_S1_DN
                                  39       CLK_100M_PCH_SLOTX24_S2_DP
                                  40       GND                     
                                  41       CLK_100M_PCH_SLOTX24_S2_DN
                                  42       CLK_100M_PCH_SLOTX24_S3_DP
                                  43       GND                     
                                  44       CLK_100M_PCH_SLOTX24_S3_DN
                                  45       CLK_100M_PCH_SLOTX24_S4_DP
                                  46       GND                     
                                  47       CLK_100M_PCH_SLOTX24_S4_DN
                                  48       CLK_100M_PCH_SLOTX24_S5_DP
                                  49       GND                     
                                  50       CLK_100M_PCH_SLOTX24_S5_DN
                                  51       P3E_CPU0_PE1_SS_C_TXP<0>
                                  52       GND                     
                                  53       P3E_CPU0_PE1_SS_C_TXN<0>
                                  54       P3E_CPU0_PE1_SS_R_RXP<0>
                                  55       GND                     
                                  56       P3E_CPU0_PE1_SS_R_RXN<0>
                                  57       P3E_CPU0_PE1_SS_C_TXP<1>
                                  58       GND                     
                                  59       P3E_CPU0_PE1_SS_C_TXN<1>
                                  60       P3E_CPU0_PE1_SS_R_RXP<1>
                                  61       GND                     
                                  62       P3E_CPU0_PE1_SS_R_RXN<1>
                                  63       FM_PRSNT_2_4_N          
                                  64       GND                     
                                  65       GND                     
                                  66       FM_PRSNT_2_5_N          
                                  67       P3E_CPU0_PE1_SS_C_TXP<2>
                                  68       GND                     
                                  69       P3E_CPU0_PE1_SS_C_TXN<2>
                                  70       P3E_CPU0_PE1_SS_R_RXP<2>
                                  71       GND                     
                                  72       P3E_CPU0_PE1_SS_R_RXN<2>
                                  73       P3E_CPU0_PE1_SS_C_TXP<3>
                                  74       GND                     
                                  75       P3E_CPU0_PE1_SS_C_TXN<3>
                                  76       P3E_CPU0_PE1_SS_R_RXP<3>
                                  77       GND                     
                                  78       P3E_CPU0_PE1_SS_R_RXN<3>
                                  79       P3E_CPU0_PE1_SS_C_TXP<4>
                                  80       GND                     
                                  81       P3E_CPU0_PE1_SS_C_TXN<4>
                                  82       P3E_CPU0_PE1_SS_R_RXP<4>
                                  83       GND                     
                                  84       P3E_CPU0_PE1_SS_R_RXN<4>
                                  85       P3E_CPU0_PE1_SS_C_TXP<5>
                                  86       GND                     
                                  87       P3E_CPU0_PE1_SS_C_TXN<5>
                                  88       P3E_CPU0_PE1_SS_R_RXP<5>
                                  89       GND                     
                                  90       P3E_CPU0_PE1_SS_R_RXN<5>
                                  91       P3E_CPU0_PE1_SS_C_TXP<6>
                                  92       GND                     
                                  93       P3E_CPU0_PE1_SS_C_TXN<6>
                                  94       P3E_CPU0_PE1_SS_R_RXP<6>
                                  95       GND                     
                                  96       P3E_CPU0_PE1_SS_R_RXN<6>
                                  97       P3E_CPU0_PE1_SS_C_TXP<7>
                                  98       GND                     
                                  99       P3E_CPU0_PE1_SS_C_TXN<7>
                                  100      P3E_CPU0_PE1_SS_R_RXP<7>
                                  101      GND                     
                                  102      P3E_CPU0_PE1_SS_R_RXN<7>
                                  103      P3E_CPU0_PE2_SS_C_TXN<0>
                                  104      GND                     
                                  105      P3E_CPU0_PE2_SS_C_TXP<0>
                                  106      P3E_CPU0_PE2_SS_RXN<0>  
                                  107      GND                     
                                  108      P3E_CPU0_PE2_SS_RXP<0>  
                                  109      P3E_CPU0_PE2_SS_C_TXP<1>
                                  110      GND                     
                                  111      P3E_CPU0_PE2_SS_C_TXN<1>
                                  112      P3E_CPU0_PE2_SS_RXN<1>  
                                  113      GND                     
                                  114      P3E_CPU0_PE2_SS_RXP<1>  
                                  115      P3E_CPU0_PE2_SS_C_TXN<2>
                                  116      GND                     
                                  117      P3E_CPU0_PE2_SS_C_TXP<2>
                                  118      P3E_CPU0_PE2_SS_RXN<2>  
                                  119      GND                     
                                  120      P3E_CPU0_PE2_SS_RXP<2>  
                                  121      P3E_CPU0_PE2_SS_C_TXN<3>
                                  122      GND                     
                                  123      P3E_CPU0_PE2_SS_C_TXP<3>
                                  124      P3E_CPU0_PE2_SS_RXN<3>  
                                  125      GND                     
                                  126      P3E_CPU0_PE2_SS_RXP<3>  
                                  127      P3E_CPU0_PE2_SS_C_TXN<4>
                                  128      GND                     
                                  129      P3E_CPU0_PE2_SS_C_TXP<4>
                                  130      P3E_CPU0_PE2_SS_RXN<4>  
                                  131      GND                     
                                  132      P3E_CPU0_PE2_SS_RXP<4>  
                                  133      P3E_CPU0_PE2_SS_C_TXN<5>
                                  134      GND                     
                                  135      P3E_CPU0_PE2_SS_C_TXP<5>
                                  136      P3E_CPU0_PE2_SS_RXN<5>  
                                  137      GND                     
                                  138      P3E_CPU0_PE2_SS_RXP<5>  
                                  139      P3E_CPU0_PE2_SS_C_TXN<6>
                                  140      GND                     
                                  141      P3E_CPU0_PE2_SS_C_TXP<6>
                                  142      P3E_CPU0_PE2_SS_RXP<6>  
                                  143      GND                     
                                  144      P3E_CPU0_PE2_SS_RXN<6>  
                                  145      P3E_CPU0_PE2_SS_C_TXN<7>
                                  146      GND                     
                                  147      P3E_CPU0_PE2_SS_C_TXP<7>
                                  148      P3E_CPU0_PE2_SS_RXN<7>  
                                  149      GND                     
                                  150      P3E_CPU0_PE2_SS_RXP<7>  
                                  151      P3E_CPU0_PE2_SS_C_TXN<8>
                                  152      GND                     
                                  153      P3E_CPU0_PE2_SS_C_TXP<8>
                                  154      P3E_CPU0_PE2_SS_RXN<8>  
                                  155      GND                     
                                  156      P3E_CPU0_PE2_SS_RXP<8>  
                                  157      P3E_CPU0_PE2_SS_C_TXN<9>
                                  158      GND                     
                                  159      P3E_CPU0_PE2_SS_C_TXP<9>
                                  160      P3E_CPU0_PE2_SS_RXN<9>  
                                  161      GND                     
                                  162      P3E_CPU0_PE2_SS_RXP<9>  
                                  163      P3E_CPU0_PE2_SS_C_TXN<10>
                                  164      GND                     
                                  165      P3E_CPU0_PE2_SS_C_TXP<10>
                                  166      P3E_CPU0_PE2_SS_RXN<10> 
                                  167      GND                     
                                  168      P3E_CPU0_PE2_SS_RXP<10> 
                                  169      P3E_CPU0_PE2_SS_C_TXP<11>
                                  170      GND                     
                                  171      P3E_CPU0_PE2_SS_C_TXN<11>
                                  172      P3E_CPU0_PE2_SS_RXN<11> 
                                  173      GND                     
                                  174      P3E_CPU0_PE2_SS_RXP<11> 
                                  175      P3E_CPU0_PE2_SS_C_TXN<12>
                                  176      GND                     
                                  177      P3E_CPU0_PE2_SS_C_TXP<12>
                                  178      P3E_CPU0_PE2_SS_RXN<12> 
                                  179      GND                     
                                  180      P3E_CPU0_PE2_SS_RXP<12> 
                                  181      P3E_CPU0_PE2_SS_C_TXN<13>
                                  182      GND                     
                                  183      P3E_CPU0_PE2_SS_C_TXP<13>
                                  184      P3E_CPU0_PE2_SS_RXP<13> 
                                  185      GND                     
                                  186      P3E_CPU0_PE2_SS_RXN<13> 
                                  187      P3E_CPU0_PE2_SS_C_TXP<14>
                                  188      GND                     
                                  189      P3E_CPU0_PE2_SS_C_TXN<14>
                                  190      P3E_CPU0_PE2_SS_RXN<14> 
                                  191      GND                     
                                  192      P3E_CPU0_PE2_SS_RXP<14> 
                                  193      P3E_CPU0_PE2_SS_C_TXN<15>
                                  194      GND                     
                                  195      P3E_CPU0_PE2_SS_C_TXP<15>
                                  196      P3E_CPU0_PE2_SS_RXN<15> 
                                  197      GND                     
                                  198      P3E_CPU0_PE2_SS_RXP<15> 
                                  199      FM_PRSNT_2_6_N          
                                  200      GND                     
                                  MH1      GND                     
                                  MH2      GND                     
J8G2             CONN12_C73564003_PIP-CONN,C735A 1        TP_JUMPER_BLOCK_1_1     
                                  2        TP_JUMPER_BLOCK_1_2     
                                  3        RST_BMC_SRST_N          
                                  4        FM_IE_DISABLE_N         
                                  5        GND                     
                                  6        GND                     
                                  7        TP_JUMPER_BLOCK_1_7     
                                  8        TP_JUMPER_BLOCK_1_8     
                                  9        FM_CPLD_UART_CH_LOCK_N  
                                  10       FM_DIS_ADR_DLY          
                                  11       GND                     
                                  12       GND                     
J9A1             CONN4_D42317002_PIP-CONN,D4231A 1        GND                     
                                  2        PU_KEY_CONN_PIN2_R      
                                  3        GND                     
                                  4        FM_PCH_SATA_RAID_KEY_R  
J9A2             CONN14_H54902001_PIP-CONN,H549A 1        LED_POSTCODE_0_R        
                                  2        LED_POSTCODE_1_R        
                                  3        LED_POSTCODE_2_R        
                                  4        LED_POSTCODE_3_R        
                                  5        LED_POSTCODE_4_R        
                                  6        LED_POSTCODE_5_R        
                                  7        LED_POSTCODE_6_R        
                                  8        LED_POSTCODE_7_R        
                                  9        SPA_MID_DBG_TX          
                                  10       SPA_5V_SIN_SW           
                                  11       FM_DEBUG_RST_BTN_N      
                                  12       FM_UART_SWITCH_N        
                                  13       GND                     
                                  14       P5V_STBY_DGB_FS         
J9A3             SCONN60_C21100002_SMLF-CONN,C2A 1        XDP_DEBUG_CONSENT_N     
                                  2        GND                     
                                  3        XDP_PREQ_N              
                                  4        TP_XDP_CPU_OBSFN_C0     
                                  5        XDP_PRDY_N              
                                  6        XDP_SPI_PCH_MOSI_BOOT_HALT_N
                                  7        GND                     
                                  8        GND                     
                                  9        TP_XDP_OBSDATA_A0       
                                  10       TP_XDP_CPU_OBSDATA_C0   
                                  11       TP_XDP_OBSDATA_A1       
                                  12       TP_XDP_CPU_OBSDATA_C1   
                                  13       GND                     
                                  14       GND                     
                                  15       TP_XDP_OBSDATA_A2       
                                  16       TP_XDP_CPU_OBSDATA_C2   
                                  17       TP_XDP_OBSDATA_A3       
                                  18       TP_XDP_CPU_OBSDATA_C3   
                                  19       GND                     
                                  20       GND                     
                                  21       TP_XDP_OBSFN_B0         
                                  22       XDP_OBSFN_B0_MBP6_N     
                                  23       TP_XDP_OBSFN_B1         
                                  24       XDP_OBSFN_B1_MBP7_N     
                                  25       GND                     
                                  26       GND                     
                                  27       TP_XDP_OBSDATA_B0       
                                  28       TP_XDP_CPU_OBSDATA_D0   
                                  29       TP_XDP_OBSDATA_B1       
                                  30       TP_XDP_CPU_OBSDATA_D1   
                                  31       GND                     
                                  32       GND                     
                                  33       TP_XDP_OBSDATA_B2       
                                  34       TP_XDP_CPU_OBSDATA_D2   
                                  35       TP_XDP_OBSDATA_B3       
                                  36       TP_XDP_CPU_OBSDATA_D3   
                                  37       GND                     
                                  38       GND                     
                                  39       XDP_RSMRST_N            
                                  40       CLK_100M_PCH_XDP_DP     
                                  41       XDP_PWRGD_RST_N         
                                  42       CLK_100M_PCH_XDP_DN     
                                  43       P1V05_PCH_STBY          
                                  44       P1V05_PCH_STBY          
                                  45       XDP_CPU_PWR_DEBUG_N     
                                  46       XDP_ITP_PMODE           
                                  47       XDP_SYSPWROK            
                                  48       XDP_RST_CO_N            
                                  49       GND                     
                                  50       GND                     
                                  51       SMB_HOST_STBY_LVC3_SDA  
                                  52       XDP_TDO                 
                                  53       SMB_HOST_STBY_LVC3_SCL  
                                  54       XDP_TRST_N              
                                  55       XDP_PCH_TCK1            
                                  56       XDP_TDI                 
                                  57       XDP_CPU_TCK0            
                                  58       XDP_TMS                 
                                  59       GND                     
                                  60       XDP_PRESENT_N           
J9B1             CONN9_H51826001_PIP2-CONN,H518A 1        P5V_USB                 
                                  2        USB2_P01_ESD_DN         
                                  3        USB2_P01_ESD_DP         
                                  4        GND                     
                                  5        USB3_P01_FB_RXN         
                                  6        USB3_P01_FB_RXP         
                                  7        GND                     
                                  8        USB3_P01_FB_TXN         
                                  9        USB3_P01_FB_TXP         
                                  MH1      GND                     
                                  MH2      GND                     
                                  MH3      GND                     
                                  MH4      GND                     
J9B2             CONN3_C95678002_PIP-CONN,C9567A 1        SMB_SMLINK0_STBY_LVC3_SDA
                                  2        GND                     
                                  3        SMB_SMLINK0_STBY_LVC3_SCL
J9B3             SCONN120_A28699018_SM-SCONN,A2A 1        FM_MEZZA_PRSNT1_N       
                                  2        P12V_STBY               
                                  3        P5V_STBY                
                                  4        P12V_STBY               
                                  5        P5V_STBY                
                                  6        P12V_STBY               
                                  7        P5V_STBY                
                                  8        GND                     
                                  9        GND                     
                                  10       GND                     
                                  11       GND                     
                                  12       P3V3_STBY               
                                  13       P3V3_STBY               
                                  14       GND                     
                                  15       GND                     
                                  16       GND                     
                                  17       GND                     
                                  18       P3V3                    
                                  19       P3V3                    
                                  20       P3V3                    
                                  21       P3V3                    
                                  22       P3V3                    
                                  23       P3V3                    
                                  24       P3V3                    
                                  25       P3V3                    
                                  26       GND                     
                                  27       RMII_BMC_OCP_CRSDV_R    
                                  28       IRQ_MEZZ_LAN_ALERT_N    
                                  29       CLK_50M_CKMNG_OCP       
                                  30       SMB_OCP_FRU_STBY_LVC3_SCL
                                  31       RMII_BMC_OCP_TXEN       
                                  32       SMB_OCP_FRU_STBY_LVC3_SDA
                                  33       RST_PCIE_CPU_DEV0_R_N   
                                  34       FM_PE_OCP_WAKE_N        
                                  35       SMB_OCP_LAN_STBY_LVC3_SCL
                                  36       RMII_BMC_OCP_RXER_R     
                                  37       SMB_OCP_LAN_STBY_LVC3_SDA
                                  38       GND                     
                                  39       GND                     
                                  40       RMII_BMC_OCP_TXD0       
                                  41       GND                     
                                  42       RMII_BMC_OCP_TXD1       
                                  43       RMII_BMC_OCP_RXD0_R     
                                  44       GND                     
                                  45       RMII_BMC_OCP_RXD1_R     
                                  46       GND                     
                                  47       GND                     
                                  48       CLK_100M_MEZZ1_DP       
                                  49       GND                     
                                  50       CLK_100M_MEZZ1_DN       
                                  51       CLK_100M_MEZZ2_DP       
                                  52       GND                     
                                  53       CLK_100M_MEZZ2_DN       
                                  54       GND                     
                                  55       GND                     
                                  56       P3E_OCP_CPU0_PE3_C_TXP<15>
                                  57       GND                     
                                  58       P3E_OCP_CPU0_PE3_C_TXN<15>
                                  59       P3E_CPU0_PE3_OCP_RXP<15>
                                  60       GND                     
                                  61       P3E_CPU0_PE3_OCP_RXN<15>
                                  62       GND                     
                                  63       GND                     
                                  64       P3E_OCP_CPU0_PE3_C_TXP<14>
                                  65       GND                     
                                  66       P3E_OCP_CPU0_PE3_C_TXN<14>
                                  67       P3E_CPU0_PE3_OCP_RXP<14>
                                  68       GND                     
                                  69       P3E_CPU0_PE3_OCP_RXN<14>
                                  70       GND                     
                                  71       GND                     
                                  72       P3E_OCP_CPU0_PE3_C_TXP<13>
                                  73       GND                     
                                  74       P3E_OCP_CPU0_PE3_C_TXN<13>
                                  75       P3E_CPU0_PE3_OCP_RXP<13>
                                  76       GND                     
                                  77       P3E_CPU0_PE3_OCP_RXN<13>
                                  78       GND                     
                                  79       GND                     
                                  80       P3E_OCP_CPU0_PE3_C_TXP<12>
                                  81       GND                     
                                  82       P3E_OCP_CPU0_PE3_C_TXN<12>
                                  83       P3E_CPU0_PE3_OCP_RXP<12>
                                  84       GND                     
                                  85       P3E_CPU0_PE3_OCP_RXN<12>
                                  86       GND                     
                                  87       GND                     
                                  88       P3E_OCP_CPU0_PE3_C_TXP<11>
                                  89       GND                     
                                  90       P3E_OCP_CPU0_PE3_C_TXN<11>
                                  91       P3E_CPU0_PE3_OCP_RXP<11>
                                  92       GND                     
                                  93       P3E_CPU0_PE3_OCP_RXN<11>
                                  94       GND                     
                                  95       GND                     
                                  96       P3E_OCP_CPU0_PE3_C_TXP<10>
                                  97       GND                     
                                  98       P3E_OCP_CPU0_PE3_C_TXN<10>
                                  99       P3E_CPU0_PE3_OCP_RXP<10>
                                  100      GND                     
                                  101      P3E_CPU0_PE3_OCP_RXN<10>
                                  102      GND                     
                                  103      GND                     
                                  104      P3E_OCP_CPU0_PE3_C_TXP<9>
                                  105      GND                     
                                  106      P3E_OCP_CPU0_PE3_C_TXN<9>
                                  107      P3E_CPU0_PE3_OCP_RXP<9> 
                                  108      GND                     
                                  109      P3E_CPU0_PE3_OCP_RXN<9> 
                                  110      GND                     
                                  111      GND                     
                                  112      P3E_OCP_CPU0_PE3_C_TXP<8>
                                  113      GND                     
                                  114      P3E_OCP_CPU0_PE3_C_TXN<8>
                                  115      P3E_CPU0_PE3_OCP_RXP<8> 
                                  116      GND                     
                                  117      P3E_CPU0_PE3_OCP_RXN<8> 
                                  118      GND                     
                                  119      GND                     
                                  120      FM_OCP_MEZZA_PRES_N     
J9B4             SCONN10_C12536004_SMLF-CONN,C1A 1        JTAG_MCP_TCK_R          
                                  2        GND                     
                                  3        JTAG_MCP_MUX_TDO        
                                  4        P1V8_MCP_CPU0           
                                  5        JTAG_MCP_TMS_R          
                                  6        JTAG_MCP_TRST_N         
                                  7        PWRGD_CPU0_G_R          
                                  8        TP_JTAG_MCP_IO8_RSVD    
                                  9        JTAG_MCP_MUX_TDI        
                                  10       GND                     
J9G1             CONN12_C73564003_PIP-CONN,C735A 1        TP_BMC_DISABLE          
                                  2        TP_RST_RTCRST_N         
                                  3        FM_ROMA<0>              
                                  4        RST_RTCRST_N            
                                  5        FM_BMC_DISABLE          
                                  6        PD_RST_RTCRST_N         
                                  7        TP_IE_DEBUG_MODE        
                                  8        TP_JUMPER_BLOCK_2_8     
                                  9        FM_UART_PRES_N          
                                  10       TP_JUMPER_BLOCK_2_10    
                                  11       PD_IE_DEBUG_MODE        
                                  12       TP_JUMPER_BLOCK_2_12    
J9L1             SCONN288_H44441003_PIP-SCONN,HA 1        P12V_NVDIMM_KLM         
                                  2        GND                     
                                  3        M_M_DQ<4>               
                                  4        GND                     
                                  5        M_M_DQ<0>               
                                  6        GND                     
                                  7        M_M_DQS_DP<9>           
                                  8        M_M_DQS_DN<9>           
                                  9        GND                     
                                  10       M_M_DQ<6>               
                                  11       GND                     
                                  12       M_M_DQ<2>               
                                  13       GND                     
                                  14       M_M_DQ<12>              
                                  15       GND                     
                                  16       M_M_DQ<8>               
                                  17       GND                     
                                  18       M_M_DQS_DP<10>          
                                  19       M_M_DQS_DN<10>          
                                  20       GND                     
                                  21       M_M_DQ<14>              
                                  22       GND                     
                                  23       M_M_DQ<10>              
                                  24       GND                     
                                  25       M_M_DQ<20>              
                                  26       GND                     
                                  27       M_M_DQ<16>              
                                  28       GND                     
                                  29       M_M_DQS_DP<11>          
                                  30       M_M_DQS_DN<11>          
                                  31       GND                     
                                  32       M_M_DQ<22>              
                                  33       GND                     
                                  34       M_M_DQ<18>              
                                  35       GND                     
                                  36       M_M_DQ<28>              
                                  37       GND                     
                                  38       M_M_DQ<24>              
                                  39       GND                     
                                  40       M_M_DQS_DP<12>          
                                  41       M_M_DQS_DN<12>          
                                  42       GND                     
                                  43       M_M_DQ<30>              
                                  44       GND                     
                                  45       M_M_DQ<26>              
                                  46       GND                     
                                  47       M_M_ECC<4>              
                                  48       GND                     
                                  49       M_M_ECC<0>              
                                  50       GND                     
                                  51       M_M_DQS_DP<17>          
                                  52       M_M_DQS_DN<17>          
                                  53       GND                     
                                  54       M_M_ECC<6>              
                                  55       GND                     
                                  56       M_M_ECC<2>              
                                  57       GND                     
                                  58       M_KLM_RST_N             
                                  59       PVDDQ_KLM               
                                  60       M_M_CKE<2>              
                                  61       PVDDQ_KLM               
                                  62       M_M_ACT_N               
                                  63       M_M_BG<0>               
                                  64       PVDDQ_KLM               
                                  65       M_M_MA<12>              
                                  66       M_M_MA<9>               
                                  67       PVDDQ_KLM               
                                  68       M_M_MA<8>               
                                  69       M_M_MA<6>               
                                  70       PVDDQ_KLM               
                                  71       M_M_MA<3>               
                                  72       M_M_MA<1>               
                                  73       PVDDQ_KLM               
                                  74       M_M_CLK_DP<2>           
                                  75       M_M_CLK_DN<2>           
                                  76       PVDDQ_KLM               
                                  77       PVTT_KLM                
                                  78       FM_DIMM_EVENT_COD_N     
                                  79       M_M_MA<0>               
                                  80       PVDDQ_KLM               
                                  81       M_M_BA<0>               
                                  82       M_M_MA<16>              
                                  83       PVDDQ_KLM               
                                  84       M_M_CS_N<4>             
                                  85       PVDDQ_KLM               
                                  86       M_M_MA<15>              
                                  87       M_M_ODT<2>              
                                  88       PVDDQ_KLM               
                                  89       M_M_CS_N<5>             
                                  90       PVDDQ_KLM               
                                  91       M_M_ODT<3>              
                                  92       PVDDQ_KLM               
                                  93       M_M_CS_N<6>             
                                  94       GND                     
                                  95       M_M_DQ<36>              
                                  96       GND                     
                                  97       M_M_DQ<32>              
                                  98       GND                     
                                  99       M_M_DQS_DP<13>          
                                  100      M_M_DQS_DN<13>          
                                  101      GND                     
                                  102      M_M_DQ<38>              
                                  103      GND                     
                                  104      M_M_DQ<34>              
                                  105      GND                     
                                  106      M_M_DQ<44>              
                                  107      GND                     
                                  108      M_M_DQ<40>              
                                  109      GND                     
                                  110      M_M_DQS_DP<14>          
                                  111      M_M_DQS_DN<14>          
                                  112      GND                     
                                  113      M_M_DQ<46>              
                                  114      GND                     
                                  115      M_M_DQ<42>              
                                  116      GND                     
                                  117      M_M_DQ<52>              
                                  118      GND                     
                                  119      M_M_DQ<48>              
                                  120      GND                     
                                  121      M_M_DQS_DP<15>          
                                  122      M_M_DQS_DN<15>          
                                  123      GND                     
                                  124      M_M_DQ<54>              
                                  125      GND                     
                                  126      M_M_DQ<50>              
                                  127      GND                     
                                  128      M_M_DQ<60>              
                                  129      GND                     
                                  130      M_M_DQ<56>              
                                  131      GND                     
                                  132      M_M_DQS_DP<16>          
                                  133      M_M_DQS_DN<16>          
                                  134      GND                     
                                  135      M_M_DQ<62>              
                                  136      GND                     
                                  137      M_M_DQ<58>              
                                  138      GND                     
                                  139      PVPP_KLM                
                                  140      GND                     
                                  141      SMB_DDR_KLM_VPP_SCL     
                                  142      PVPP_KLM                
                                  143      PVPP_KLM                
                                  144      TP_CH_M_DIMM_M1_RFU_2   
                                  145      P12V_NVDIMM_KLM         
                                  146      M_M_VREF                
                                  147      GND                     
                                  148      M_M_DQ<5>               
                                  149      GND                     
                                  150      M_M_DQ<1>               
                                  151      GND                     
                                  152      M_M_DQS_DN<0>           
                                  153      M_M_DQS_DP<0>           
                                  154      GND                     
                                  155      M_M_DQ<7>               
                                  156      GND                     
                                  157      M_M_DQ<3>               
                                  158      GND                     
                                  159      M_M_DQ<13>              
                                  160      GND                     
                                  161      M_M_DQ<9>               
                                  162      GND                     
                                  163      M_M_DQS_DN<1>           
                                  164      M_M_DQS_DP<1>           
                                  165      GND                     
                                  166      M_M_DQ<15>              
                                  167      GND                     
                                  168      M_M_DQ<11>              
                                  169      GND                     
                                  170      M_M_DQ<21>              
                                  171      GND                     
                                  172      M_M_DQ<17>              
                                  173      GND                     
                                  174      M_M_DQS_DN<2>           
                                  175      M_M_DQS_DP<2>           
                                  176      GND                     
                                  177      M_M_DQ<23>              
                                  178      GND                     
                                  179      M_M_DQ<19>              
                                  180      GND                     
                                  181      M_M_DQ<29>              
                                  182      GND                     
                                  183      M_M_DQ<25>              
                                  184      GND                     
                                  185      M_M_DQS_DN<3>           
                                  186      M_M_DQS_DP<3>           
                                  187      GND                     
                                  188      M_M_DQ<31>              
                                  189      GND                     
                                  190      M_M_DQ<27>              
                                  191      GND                     
                                  192      M_M_ECC<5>              
                                  193      GND                     
                                  194      M_M_ECC<1>              
                                  195      GND                     
                                  196      M_M_DQS_DN<8>           
                                  197      M_M_DQS_DP<8>           
                                  198      GND                     
                                  199      M_M_ECC<7>              
                                  200      GND                     
                                  201      M_M_ECC<3>              
                                  202      GND                     
                                  203      M_M_CKE<3>              
                                  204      PVDDQ_KLM               
                                  205      TP_CH_M_DIMM_M1_RFU_0   
                                  206      PVDDQ_KLM               
                                  207      M_M_BG<1>               
                                  208      M_M_ALERT_N             
                                  209      PVDDQ_KLM               
                                  210      M_M_MA<11>              
                                  211      M_M_MA<7>               
                                  212      PVDDQ_KLM               
                                  213      M_M_MA<5>               
                                  214      M_M_MA<4>               
                                  215      PVDDQ_KLM               
                                  216      M_M_MA<2>               
                                  217      PVDDQ_KLM               
                                  218      M_M_CLK_DP<3>           
                                  219      M_M_CLK_DN<3>           
                                  220      PVDDQ_KLM               
                                  221      PVTT_KLM                
                                  222      M_M_PAR                 
                                  223      PVDDQ_KLM               
                                  224      M_M_BA<1>               
                                  225      M_M_MA<10>              
                                  226      PVDDQ_KLM               
                                  227      TP_CH_M_DIMM_M1_RFU_1   
                                  228      M_M_MA<14>              
                                  229      PVDDQ_KLM               
                                  230      FM_ADR_COMPLETE_KLM_N   
                                  231      PVDDQ_KLM               
                                  232      M_M_MA<13>              
                                  233      PVDDQ_KLM               
                                  234      M_M_MA<17>              
                                  235      M_M_C<2>                
                                  236      PVDDQ_KLM               
                                  237      M_M_CS_N<7>             
                                  238      PVPP_KLM                
                                  239      GND                     
                                  240      M_M_DQ<37>              
                                  241      GND                     
                                  242      M_M_DQ<33>              
                                  243      GND                     
                                  244      M_M_DQS_DN<4>           
                                  245      M_M_DQS_DP<4>           
                                  246      GND                     
                                  247      M_M_DQ<39>              
                                  248      GND                     
                                  249      M_M_DQ<35>              
                                  250      GND                     
                                  251      M_M_DQ<45>              
                                  252      GND                     
                                  253      M_M_DQ<41>              
                                  254      GND                     
                                  255      M_M_DQS_DN<5>           
                                  256      M_M_DQS_DP<5>           
                                  257      GND                     
                                  258      M_M_DQ<47>              
                                  259      GND                     
                                  260      M_M_DQ<43>              
                                  261      GND                     
                                  262      M_M_DQ<53>              
                                  263      GND                     
                                  264      M_M_DQ<49>              
                                  265      GND                     
                                  266      M_M_DQS_DN<6>           
                                  267      M_M_DQS_DP<6>           
                                  268      GND                     
                                  269      M_M_DQ<55>              
                                  270      GND                     
                                  271      M_M_DQ<51>              
                                  272      GND                     
                                  273      M_M_DQ<61>              
                                  274      GND                     
                                  275      M_M_DQ<57>              
                                  276      GND                     
                                  277      M_M_DQS_DN<7>           
                                  278      M_M_DQS_DP<7>           
                                  279      GND                     
                                  280      M_M_DQ<63>              
                                  281      GND                     
                                  282      M_M_DQ<59>              
                                  283      GND                     
                                  284      PVPP_KLM                
                                  285      SMB_DDR_KLM_VPP_SDA     
                                  286      PVPP_KLM                
                                  287      PVPP_KLM                
                                  288      PVPP_KLM                
J9L2             SCONN288_H44441003_PIP-SCONN,HA 1        P12V_NVDIMM_KLM         
                                  2        GND                     
                                  3        M_L_DQ<4>               
                                  4        GND                     
                                  5        M_L_DQ<0>               
                                  6        GND                     
                                  7        M_L_DQS_DP<9>           
                                  8        M_L_DQS_DN<9>           
                                  9        GND                     
                                  10       M_L_DQ<6>               
                                  11       GND                     
                                  12       M_L_DQ<2>               
                                  13       GND                     
                                  14       M_L_DQ<12>              
                                  15       GND                     
                                  16       M_L_DQ<8>               
                                  17       GND                     
                                  18       M_L_DQS_DP<10>          
                                  19       M_L_DQS_DN<10>          
                                  20       GND                     
                                  21       M_L_DQ<14>              
                                  22       GND                     
                                  23       M_L_DQ<10>              
                                  24       GND                     
                                  25       M_L_DQ<20>              
                                  26       GND                     
                                  27       M_L_DQ<16>              
                                  28       GND                     
                                  29       M_L_DQS_DP<11>          
                                  30       M_L_DQS_DN<11>          
                                  31       GND                     
                                  32       M_L_DQ<22>              
                                  33       GND                     
                                  34       M_L_DQ<18>              
                                  35       GND                     
                                  36       M_L_DQ<28>              
                                  37       GND                     
                                  38       M_L_DQ<24>              
                                  39       GND                     
                                  40       M_L_DQS_DP<12>          
                                  41       M_L_DQS_DN<12>          
                                  42       GND                     
                                  43       M_L_DQ<30>              
                                  44       GND                     
                                  45       M_L_DQ<26>              
                                  46       GND                     
                                  47       M_L_ECC<4>              
                                  48       GND                     
                                  49       M_L_ECC<0>              
                                  50       GND                     
                                  51       M_L_DQS_DP<17>          
                                  52       M_L_DQS_DN<17>          
                                  53       GND                     
                                  54       M_L_ECC<6>              
                                  55       GND                     
                                  56       M_L_ECC<2>              
                                  57       GND                     
                                  58       M_KLM_RST_N             
                                  59       PVDDQ_KLM               
                                  60       M_L_CKE<2>              
                                  61       PVDDQ_KLM               
                                  62       M_L_ACT_N               
                                  63       M_L_BG<0>               
                                  64       PVDDQ_KLM               
                                  65       M_L_MA<12>              
                                  66       M_L_MA<9>               
                                  67       PVDDQ_KLM               
                                  68       M_L_MA<8>               
                                  69       M_L_MA<6>               
                                  70       PVDDQ_KLM               
                                  71       M_L_MA<3>               
                                  72       M_L_MA<1>               
                                  73       PVDDQ_KLM               
                                  74       M_L_CLK_DP<2>           
                                  75       M_L_CLK_DN<2>           
                                  76       PVDDQ_KLM               
                                  77       PVTT_KLM                
                                  78       FM_DIMM_EVENT_COD_N     
                                  79       M_L_MA<0>               
                                  80       PVDDQ_KLM               
                                  81       M_L_BA<0>               
                                  82       M_L_MA<16>              
                                  83       PVDDQ_KLM               
                                  84       M_L_CS_N<4>             
                                  85       PVDDQ_KLM               
                                  86       M_L_MA<15>              
                                  87       M_L_ODT<2>              
                                  88       PVDDQ_KLM               
                                  89       M_L_CS_N<5>             
                                  90       PVDDQ_KLM               
                                  91       M_L_ODT<3>              
                                  92       PVDDQ_KLM               
                                  93       M_L_CS_N<6>             
                                  94       GND                     
                                  95       M_L_DQ<36>              
                                  96       GND                     
                                  97       M_L_DQ<32>              
                                  98       GND                     
                                  99       M_L_DQS_DP<13>          
                                  100      M_L_DQS_DN<13>          
                                  101      GND                     
                                  102      M_L_DQ<38>              
                                  103      GND                     
                                  104      M_L_DQ<34>              
                                  105      GND                     
                                  106      M_L_DQ<44>              
                                  107      GND                     
                                  108      M_L_DQ<40>              
                                  109      GND                     
                                  110      M_L_DQS_DP<14>          
                                  111      M_L_DQS_DN<14>          
                                  112      GND                     
                                  113      M_L_DQ<46>              
                                  114      GND                     
                                  115      M_L_DQ<42>              
                                  116      GND                     
                                  117      M_L_DQ<52>              
                                  118      GND                     
                                  119      M_L_DQ<48>              
                                  120      GND                     
                                  121      M_L_DQS_DP<15>          
                                  122      M_L_DQS_DN<15>          
                                  123      GND                     
                                  124      M_L_DQ<54>              
                                  125      GND                     
                                  126      M_L_DQ<50>              
                                  127      GND                     
                                  128      M_L_DQ<60>              
                                  129      GND                     
                                  130      M_L_DQ<56>              
                                  131      GND                     
                                  132      M_L_DQS_DP<16>          
                                  133      M_L_DQS_DN<16>          
                                  134      GND                     
                                  135      M_L_DQ<62>              
                                  136      GND                     
                                  137      M_L_DQ<58>              
                                  138      GND                     
                                  139      PVPP_KLM                
                                  140      PVPP_KLM                
                                  141      SMB_DDR_KLM_VPP_SCL     
                                  142      PVPP_KLM                
                                  143      PVPP_KLM                
                                  144      TP_CH_L_DIMM0_RFU_2     
                                  145      P12V_NVDIMM_KLM         
                                  146      M_L_VREF                
                                  147      GND                     
                                  148      M_L_DQ<5>               
                                  149      GND                     
                                  150      M_L_DQ<1>               
                                  151      GND                     
                                  152      M_L_DQS_DN<0>           
                                  153      M_L_DQS_DP<0>           
                                  154      GND                     
                                  155      M_L_DQ<7>               
                                  156      GND                     
                                  157      M_L_DQ<3>               
                                  158      GND                     
                                  159      M_L_DQ<13>              
                                  160      GND                     
                                  161      M_L_DQ<9>               
                                  162      GND                     
                                  163      M_L_DQS_DN<1>           
                                  164      M_L_DQS_DP<1>           
                                  165      GND                     
                                  166      M_L_DQ<15>              
                                  167      GND                     
                                  168      M_L_DQ<11>              
                                  169      GND                     
                                  170      M_L_DQ<21>              
                                  171      GND                     
                                  172      M_L_DQ<17>              
                                  173      GND                     
                                  174      M_L_DQS_DN<2>           
                                  175      M_L_DQS_DP<2>           
                                  176      GND                     
                                  177      M_L_DQ<23>              
                                  178      GND                     
                                  179      M_L_DQ<19>              
                                  180      GND                     
                                  181      M_L_DQ<29>              
                                  182      GND                     
                                  183      M_L_DQ<25>              
                                  184      GND                     
                                  185      M_L_DQS_DN<3>           
                                  186      M_L_DQS_DP<3>           
                                  187      GND                     
                                  188      M_L_DQ<31>              
                                  189      GND                     
                                  190      M_L_DQ<27>              
                                  191      GND                     
                                  192      M_L_ECC<5>              
                                  193      GND                     
                                  194      M_L_ECC<1>              
                                  195      GND                     
                                  196      M_L_DQS_DN<8>           
                                  197      M_L_DQS_DP<8>           
                                  198      GND                     
                                  199      M_L_ECC<7>              
                                  200      GND                     
                                  201      M_L_ECC<3>              
                                  202      GND                     
                                  203      M_L_CKE<3>              
                                  204      PVDDQ_KLM               
                                  205      TP_CH_L_DIMM0_RFU_0     
                                  206      PVDDQ_KLM               
                                  207      M_L_BG<1>               
                                  208      M_L_ALERT_N             
                                  209      PVDDQ_KLM               
                                  210      M_L_MA<11>              
                                  211      M_L_MA<7>               
                                  212      PVDDQ_KLM               
                                  213      M_L_MA<5>               
                                  214      M_L_MA<4>               
                                  215      PVDDQ_KLM               
                                  216      M_L_MA<2>               
                                  217      PVDDQ_KLM               
                                  218      M_L_CLK_DP<3>           
                                  219      M_L_CLK_DN<3>           
                                  220      PVDDQ_KLM               
                                  221      PVTT_KLM                
                                  222      M_L_PAR                 
                                  223      PVDDQ_KLM               
                                  224      M_L_BA<1>               
                                  225      M_L_MA<10>              
                                  226      PVDDQ_KLM               
                                  227      TP_CH_L_DIMM0_RFU_1     
                                  228      M_L_MA<14>              
                                  229      PVDDQ_KLM               
                                  230      FM_ADR_COMPLETE_KLM_N   
                                  231      PVDDQ_KLM               
                                  232      M_L_MA<13>              
                                  233      PVDDQ_KLM               
                                  234      M_L_MA<17>              
                                  235      M_L_C<2>                
                                  236      PVDDQ_KLM               
                                  237      M_L_CS_N<7>             
                                  238      GND                     
                                  239      GND                     
                                  240      M_L_DQ<37>              
                                  241      GND                     
                                  242      M_L_DQ<33>              
                                  243      GND                     
                                  244      M_L_DQS_DN<4>           
                                  245      M_L_DQS_DP<4>           
                                  246      GND                     
                                  247      M_L_DQ<39>              
                                  248      GND                     
                                  249      M_L_DQ<35>              
                                  250      GND                     
                                  251      M_L_DQ<45>              
                                  252      GND                     
                                  253      M_L_DQ<41>              
                                  254      GND                     
                                  255      M_L_DQS_DN<5>           
                                  256      M_L_DQS_DP<5>           
                                  257      GND                     
                                  258      M_L_DQ<47>              
                                  259      GND                     
                                  260      M_L_DQ<43>              
                                  261      GND                     
                                  262      M_L_DQ<53>              
                                  263      GND                     
                                  264      M_L_DQ<49>              
                                  265      GND                     
                                  266      M_L_DQS_DN<6>           
                                  267      M_L_DQS_DP<6>           
                                  268      GND                     
                                  269      M_L_DQ<55>              
                                  270      GND                     
                                  271      M_L_DQ<51>              
                                  272      GND                     
                                  273      M_L_DQ<61>              
                                  274      GND                     
                                  275      M_L_DQ<57>              
                                  276      GND                     
                                  277      M_L_DQS_DN<7>           
                                  278      M_L_DQS_DP<7>           
                                  279      GND                     
                                  280      M_L_DQ<63>              
                                  281      GND                     
                                  282      M_L_DQ<59>              
                                  283      GND                     
                                  284      PVPP_KLM                
                                  285      SMB_DDR_KLM_VPP_SDA     
                                  286      PVPP_KLM                
                                  287      PVPP_KLM                
                                  288      PVPP_KLM                
J9M1             SCONN288_H44441003_PIP-SCONN,HA 1        P12V_NVDIMM_KLM         
                                  2        GND                     
                                  3        M_K_DQ<4>               
                                  4        GND                     
                                  5        M_K_DQ<0>               
                                  6        GND                     
                                  7        M_K_DQS_DP<9>           
                                  8        M_K_DQS_DN<9>           
                                  9        GND                     
                                  10       M_K_DQ<6>               
                                  11       GND                     
                                  12       M_K_DQ<2>               
                                  13       GND                     
                                  14       M_K_DQ<12>              
                                  15       GND                     
                                  16       M_K_DQ<8>               
                                  17       GND                     
                                  18       M_K_DQS_DP<10>          
                                  19       M_K_DQS_DN<10>          
                                  20       GND                     
                                  21       M_K_DQ<14>              
                                  22       GND                     
                                  23       M_K_DQ<10>              
                                  24       GND                     
                                  25       M_K_DQ<20>              
                                  26       GND                     
                                  27       M_K_DQ<16>              
                                  28       GND                     
                                  29       M_K_DQS_DP<11>          
                                  30       M_K_DQS_DN<11>          
                                  31       GND                     
                                  32       M_K_DQ<22>              
                                  33       GND                     
                                  34       M_K_DQ<18>              
                                  35       GND                     
                                  36       M_K_DQ<28>              
                                  37       GND                     
                                  38       M_K_DQ<24>              
                                  39       GND                     
                                  40       M_K_DQS_DP<12>          
                                  41       M_K_DQS_DN<12>          
                                  42       GND                     
                                  43       M_K_DQ<30>              
                                  44       GND                     
                                  45       M_K_DQ<26>              
                                  46       GND                     
                                  47       M_K_ECC<4>              
                                  48       GND                     
                                  49       M_K_ECC<0>              
                                  50       GND                     
                                  51       M_K_DQS_DP<17>          
                                  52       M_K_DQS_DN<17>          
                                  53       GND                     
                                  54       M_K_ECC<6>              
                                  55       GND                     
                                  56       M_K_ECC<2>              
                                  57       GND                     
                                  58       M_KLM_RST_N             
                                  59       PVDDQ_KLM               
                                  60       M_K_CKE<2>              
                                  61       PVDDQ_KLM               
                                  62       M_K_ACT_N               
                                  63       M_K_BG<0>               
                                  64       PVDDQ_KLM               
                                  65       M_K_MA<12>              
                                  66       M_K_MA<9>               
                                  67       PVDDQ_KLM               
                                  68       M_K_MA<8>               
                                  69       M_K_MA<6>               
                                  70       PVDDQ_KLM               
                                  71       M_K_MA<3>               
                                  72       M_K_MA<1>               
                                  73       PVDDQ_KLM               
                                  74       M_K_CLK_DP<2>           
                                  75       M_K_CLK_DN<2>           
                                  76       PVDDQ_KLM               
                                  77       PVTT_KLM                
                                  78       FM_DIMM_EVENT_COD_N     
                                  79       M_K_MA<0>               
                                  80       PVDDQ_KLM               
                                  81       M_K_BA<0>               
                                  82       M_K_MA<16>              
                                  83       PVDDQ_KLM               
                                  84       M_K_CS_N<4>             
                                  85       PVDDQ_KLM               
                                  86       M_K_MA<15>              
                                  87       M_K_ODT<2>              
                                  88       PVDDQ_KLM               
                                  89       M_K_CS_N<5>             
                                  90       PVDDQ_KLM               
                                  91       M_K_ODT<3>              
                                  92       PVDDQ_KLM               
                                  93       M_K_CS_N<6>             
                                  94       GND                     
                                  95       M_K_DQ<36>              
                                  96       GND                     
                                  97       M_K_DQ<32>              
                                  98       GND                     
                                  99       M_K_DQS_DP<13>          
                                  100      M_K_DQS_DN<13>          
                                  101      GND                     
                                  102      M_K_DQ<38>              
                                  103      GND                     
                                  104      M_K_DQ<34>              
                                  105      GND                     
                                  106      M_K_DQ<44>              
                                  107      GND                     
                                  108      M_K_DQ<40>              
                                  109      GND                     
                                  110      M_K_DQS_DP<14>          
                                  111      M_K_DQS_DN<14>          
                                  112      GND                     
                                  113      M_K_DQ<46>              
                                  114      GND                     
                                  115      M_K_DQ<42>              
                                  116      GND                     
                                  117      M_K_DQ<52>              
                                  118      GND                     
                                  119      M_K_DQ<48>              
                                  120      GND                     
                                  121      M_K_DQS_DP<15>          
                                  122      M_K_DQS_DN<15>          
                                  123      GND                     
                                  124      M_K_DQ<54>              
                                  125      GND                     
                                  126      M_K_DQ<50>              
                                  127      GND                     
                                  128      M_K_DQ<60>              
                                  129      GND                     
                                  130      M_K_DQ<56>              
                                  131      GND                     
                                  132      M_K_DQS_DP<16>          
                                  133      M_K_DQS_DN<16>          
                                  134      GND                     
                                  135      M_K_DQ<62>              
                                  136      GND                     
                                  137      M_K_DQ<58>              
                                  138      GND                     
                                  139      PVPP_KLM                
                                  140      GND                     
                                  141      SMB_DDR_KLM_VPP_SCL     
                                  142      PVPP_KLM                
                                  143      PVPP_KLM                
                                  144      TP_CH_K_DIMM0_RFU_2     
                                  145      P12V_NVDIMM_KLM         
                                  146      M_K_VREF                
                                  147      GND                     
                                  148      M_K_DQ<5>               
                                  149      GND                     
                                  150      M_K_DQ<1>               
                                  151      GND                     
                                  152      M_K_DQS_DN<0>           
                                  153      M_K_DQS_DP<0>           
                                  154      GND                     
                                  155      M_K_DQ<7>               
                                  156      GND                     
                                  157      M_K_DQ<3>               
                                  158      GND                     
                                  159      M_K_DQ<13>              
                                  160      GND                     
                                  161      M_K_DQ<9>               
                                  162      GND                     
                                  163      M_K_DQS_DN<1>           
                                  164      M_K_DQS_DP<1>           
                                  165      GND                     
                                  166      M_K_DQ<15>              
                                  167      GND                     
                                  168      M_K_DQ<11>              
                                  169      GND                     
                                  170      M_K_DQ<21>              
                                  171      GND                     
                                  172      M_K_DQ<17>              
                                  173      GND                     
                                  174      M_K_DQS_DN<2>           
                                  175      M_K_DQS_DP<2>           
                                  176      GND                     
                                  177      M_K_DQ<23>              
                                  178      GND                     
                                  179      M_K_DQ<19>              
                                  180      GND                     
                                  181      M_K_DQ<29>              
                                  182      GND                     
                                  183      M_K_DQ<25>              
                                  184      GND                     
                                  185      M_K_DQS_DN<3>           
                                  186      M_K_DQS_DP<3>           
                                  187      GND                     
                                  188      M_K_DQ<31>              
                                  189      GND                     
                                  190      M_K_DQ<27>              
                                  191      GND                     
                                  192      M_K_ECC<5>              
                                  193      GND                     
                                  194      M_K_ECC<1>              
                                  195      GND                     
                                  196      M_K_DQS_DN<8>           
                                  197      M_K_DQS_DP<8>           
                                  198      GND                     
                                  199      M_K_ECC<7>              
                                  200      GND                     
                                  201      M_K_ECC<3>              
                                  202      GND                     
                                  203      M_K_CKE<3>              
                                  204      PVDDQ_KLM               
                                  205      TP_CH_K_DIMM0_RFU_0     
                                  206      PVDDQ_KLM               
                                  207      M_K_BG<1>               
                                  208      M_K_ALERT_N             
                                  209      PVDDQ_KLM               
                                  210      M_K_MA<11>              
                                  211      M_K_MA<7>               
                                  212      PVDDQ_KLM               
                                  213      M_K_MA<5>               
                                  214      M_K_MA<4>               
                                  215      PVDDQ_KLM               
                                  216      M_K_MA<2>               
                                  217      PVDDQ_KLM               
                                  218      M_K_CLK_DP<3>           
                                  219      M_K_CLK_DN<3>           
                                  220      PVDDQ_KLM               
                                  221      PVTT_KLM                
                                  222      M_K_PAR                 
                                  223      PVDDQ_KLM               
                                  224      M_K_BA<1>               
                                  225      M_K_MA<10>              
                                  226      PVDDQ_KLM               
                                  227      TP_CH_K_DIMM0_RFU_1     
                                  228      M_K_MA<14>              
                                  229      PVDDQ_KLM               
                                  230      FM_ADR_COMPLETE_KLM_N   
                                  231      PVDDQ_KLM               
                                  232      M_K_MA<13>              
                                  233      PVDDQ_KLM               
                                  234      M_K_MA<17>              
                                  235      M_K_C<2>                
                                  236      PVDDQ_KLM               
                                  237      M_K_CS_N<7>             
                                  238      GND                     
                                  239      GND                     
                                  240      M_K_DQ<37>              
                                  241      GND                     
                                  242      M_K_DQ<33>              
                                  243      GND                     
                                  244      M_K_DQS_DN<4>           
                                  245      M_K_DQS_DP<4>           
                                  246      GND                     
                                  247      M_K_DQ<39>              
                                  248      GND                     
                                  249      M_K_DQ<35>              
                                  250      GND                     
                                  251      M_K_DQ<45>              
                                  252      GND                     
                                  253      M_K_DQ<41>              
                                  254      GND                     
                                  255      M_K_DQS_DN<5>           
                                  256      M_K_DQS_DP<5>           
                                  257      GND                     
                                  258      M_K_DQ<47>              
                                  259      GND                     
                                  260      M_K_DQ<43>              
                                  261      GND                     
                                  262      M_K_DQ<53>              
                                  263      GND                     
                                  264      M_K_DQ<49>              
                                  265      GND                     
                                  266      M_K_DQS_DN<6>           
                                  267      M_K_DQS_DP<6>           
                                  268      GND                     
                                  269      M_K_DQ<55>              
                                  270      GND                     
                                  271      M_K_DQ<51>              
                                  272      GND                     
                                  273      M_K_DQ<61>              
                                  274      GND                     
                                  275      M_K_DQ<57>              
                                  276      GND                     
                                  277      M_K_DQS_DN<7>           
                                  278      M_K_DQS_DP<7>           
                                  279      GND                     
                                  280      M_K_DQ<63>              
                                  281      GND                     
                                  282      M_K_DQ<59>              
                                  283      GND                     
                                  284      PVPP_KLM                
                                  285      SMB_DDR_KLM_VPP_SDA     
                                  286      PVPP_KLM                
                                  287      PVPP_KLM                
                                  288      PVPP_KLM                
J9T1             SCONN288_H44441003_PIP-SCONN,HA 1        P12V_NVDIMM_GHJ         
                                  2        GND                     
                                  3        M_G_DQ<4>               
                                  4        GND                     
                                  5        M_G_DQ<0>               
                                  6        GND                     
                                  7        M_G_DQS_DP<9>           
                                  8        M_G_DQS_DN<9>           
                                  9        GND                     
                                  10       M_G_DQ<6>               
                                  11       GND                     
                                  12       M_G_DQ<2>               
                                  13       GND                     
                                  14       M_G_DQ<12>              
                                  15       GND                     
                                  16       M_G_DQ<8>               
                                  17       GND                     
                                  18       M_G_DQS_DP<10>          
                                  19       M_G_DQS_DN<10>          
                                  20       GND                     
                                  21       M_G_DQ<14>              
                                  22       GND                     
                                  23       M_G_DQ<10>              
                                  24       GND                     
                                  25       M_G_DQ<20>              
                                  26       GND                     
                                  27       M_G_DQ<16>              
                                  28       GND                     
                                  29       M_G_DQS_DP<11>          
                                  30       M_G_DQS_DN<11>          
                                  31       GND                     
                                  32       M_G_DQ<22>              
                                  33       GND                     
                                  34       M_G_DQ<18>              
                                  35       GND                     
                                  36       M_G_DQ<28>              
                                  37       GND                     
                                  38       M_G_DQ<24>              
                                  39       GND                     
                                  40       M_G_DQS_DP<12>          
                                  41       M_G_DQS_DN<12>          
                                  42       GND                     
                                  43       M_G_DQ<30>              
                                  44       GND                     
                                  45       M_G_DQ<26>              
                                  46       GND                     
                                  47       M_G_ECC<4>              
                                  48       GND                     
                                  49       M_G_ECC<0>              
                                  50       GND                     
                                  51       M_G_DQS_DP<17>          
                                  52       M_G_DQS_DN<17>          
                                  53       GND                     
                                  54       M_G_ECC<6>              
                                  55       GND                     
                                  56       M_G_ECC<2>              
                                  57       GND                     
                                  58       M_GHJ_RST_N             
                                  59       PVDDQ_GHJ               
                                  60       M_G_CKE<2>              
                                  61       PVDDQ_GHJ               
                                  62       M_G_ACT_N               
                                  63       M_G_BG<0>               
                                  64       PVDDQ_GHJ               
                                  65       M_G_MA<12>              
                                  66       M_G_MA<9>               
                                  67       PVDDQ_GHJ               
                                  68       M_G_MA<8>               
                                  69       M_G_MA<6>               
                                  70       PVDDQ_GHJ               
                                  71       M_G_MA<3>               
                                  72       M_G_MA<1>               
                                  73       PVDDQ_GHJ               
                                  74       M_G_CLK_DP<2>           
                                  75       M_G_CLK_DN<2>           
                                  76       PVDDQ_GHJ               
                                  77       PVTT_GHJ                
                                  78       FM_DIMM_EVENT_COD_N     
                                  79       M_G_MA<0>               
                                  80       PVDDQ_GHJ               
                                  81       M_G_BA<0>               
                                  82       M_G_MA<16>              
                                  83       PVDDQ_GHJ               
                                  84       M_G_CS_N<4>             
                                  85       PVDDQ_GHJ               
                                  86       M_G_MA<15>              
                                  87       M_G_ODT<2>              
                                  88       PVDDQ_GHJ               
                                  89       M_G_CS_N<5>             
                                  90       PVDDQ_GHJ               
                                  91       M_G_ODT<3>              
                                  92       PVDDQ_GHJ               
                                  93       M_G_CS_N<6>             
                                  94       GND                     
                                  95       M_G_DQ<36>              
                                  96       GND                     
                                  97       M_G_DQ<32>              
                                  98       GND                     
                                  99       M_G_DQS_DP<13>          
                                  100      M_G_DQS_DN<13>          
                                  101      GND                     
                                  102      M_G_DQ<38>              
                                  103      GND                     
                                  104      M_G_DQ<34>              
                                  105      GND                     
                                  106      M_G_DQ<44>              
                                  107      GND                     
                                  108      M_G_DQ<40>              
                                  109      GND                     
                                  110      M_G_DQS_DP<14>          
                                  111      M_G_DQS_DN<14>          
                                  112      GND                     
                                  113      M_G_DQ<46>              
                                  114      GND                     
                                  115      M_G_DQ<42>              
                                  116      GND                     
                                  117      M_G_DQ<52>              
                                  118      GND                     
                                  119      M_G_DQ<48>              
                                  120      GND                     
                                  121      M_G_DQS_DP<15>          
                                  122      M_G_DQS_DN<15>          
                                  123      GND                     
                                  124      M_G_DQ<54>              
                                  125      GND                     
                                  126      M_G_DQ<50>              
                                  127      GND                     
                                  128      M_G_DQ<60>              
                                  129      GND                     
                                  130      M_G_DQ<56>              
                                  131      GND                     
                                  132      M_G_DQS_DP<16>          
                                  133      M_G_DQS_DN<16>          
                                  134      GND                     
                                  135      M_G_DQ<62>              
                                  136      GND                     
                                  137      M_G_DQ<58>              
                                  138      GND                     
                                  139      PVPP_GHJ                
                                  140      GND                     
                                  141      SMB_DDR_GHJ_VPP_SCL     
                                  142      PVPP_GHJ                
                                  143      PVPP_GHJ                
                                  144      TP_CH_G_DIMM0_RFU_2     
                                  145      P12V_NVDIMM_GHJ         
                                  146      M_G_VREF                
                                  147      GND                     
                                  148      M_G_DQ<5>               
                                  149      GND                     
                                  150      M_G_DQ<1>               
                                  151      GND                     
                                  152      M_G_DQS_DN<0>           
                                  153      M_G_DQS_DP<0>           
                                  154      GND                     
                                  155      M_G_DQ<7>               
                                  156      GND                     
                                  157      M_G_DQ<3>               
                                  158      GND                     
                                  159      M_G_DQ<13>              
                                  160      GND                     
                                  161      M_G_DQ<9>               
                                  162      GND                     
                                  163      M_G_DQS_DN<1>           
                                  164      M_G_DQS_DP<1>           
                                  165      GND                     
                                  166      M_G_DQ<15>              
                                  167      GND                     
                                  168      M_G_DQ<11>              
                                  169      GND                     
                                  170      M_G_DQ<21>              
                                  171      GND                     
                                  172      M_G_DQ<17>              
                                  173      GND                     
                                  174      M_G_DQS_DN<2>           
                                  175      M_G_DQS_DP<2>           
                                  176      GND                     
                                  177      M_G_DQ<23>              
                                  178      GND                     
                                  179      M_G_DQ<19>              
                                  180      GND                     
                                  181      M_G_DQ<29>              
                                  182      GND                     
                                  183      M_G_DQ<25>              
                                  184      GND                     
                                  185      M_G_DQS_DN<3>           
                                  186      M_G_DQS_DP<3>           
                                  187      GND                     
                                  188      M_G_DQ<31>              
                                  189      GND                     
                                  190      M_G_DQ<27>              
                                  191      GND                     
                                  192      M_G_ECC<5>              
                                  193      GND                     
                                  194      M_G_ECC<1>              
                                  195      GND                     
                                  196      M_G_DQS_DN<8>           
                                  197      M_G_DQS_DP<8>           
                                  198      GND                     
                                  199      M_G_ECC<7>              
                                  200      GND                     
                                  201      M_G_ECC<3>              
                                  202      GND                     
                                  203      M_G_CKE<3>              
                                  204      PVDDQ_GHJ               
                                  205      TP_CH_G_DIMM0_RFU_0     
                                  206      PVDDQ_GHJ               
                                  207      M_G_BG<1>               
                                  208      M_G_ALERT_N             
                                  209      PVDDQ_GHJ               
                                  210      M_G_MA<11>              
                                  211      M_G_MA<7>               
                                  212      PVDDQ_GHJ               
                                  213      M_G_MA<5>               
                                  214      M_G_MA<4>               
                                  215      PVDDQ_GHJ               
                                  216      M_G_MA<2>               
                                  217      PVDDQ_GHJ               
                                  218      M_G_CLK_DP<3>           
                                  219      M_G_CLK_DN<3>           
                                  220      PVDDQ_GHJ               
                                  221      PVTT_GHJ                
                                  222      M_G_PAR                 
                                  223      PVDDQ_GHJ               
                                  224      M_G_BA<1>               
                                  225      M_G_MA<10>              
                                  226      PVDDQ_GHJ               
                                  227      TP_CH_G_DIMM0_RFU_1     
                                  228      M_G_MA<14>              
                                  229      PVDDQ_GHJ               
                                  230      FM_ADR_COMPLETE_GHJ_N   
                                  231      PVDDQ_GHJ               
                                  232      M_G_MA<13>              
                                  233      PVDDQ_GHJ               
                                  234      M_G_MA<17>              
                                  235      M_G_C<2>                
                                  236      PVDDQ_GHJ               
                                  237      M_G_CS_N<7>             
                                  238      GND                     
                                  239      GND                     
                                  240      M_G_DQ<37>              
                                  241      GND                     
                                  242      M_G_DQ<33>              
                                  243      GND                     
                                  244      M_G_DQS_DN<4>           
                                  245      M_G_DQS_DP<4>           
                                  246      GND                     
                                  247      M_G_DQ<39>              
                                  248      GND                     
                                  249      M_G_DQ<35>              
                                  250      GND                     
                                  251      M_G_DQ<45>              
                                  252      GND                     
                                  253      M_G_DQ<41>              
                                  254      GND                     
                                  255      M_G_DQS_DN<5>           
                                  256      M_G_DQS_DP<5>           
                                  257      GND                     
                                  258      M_G_DQ<47>              
                                  259      GND                     
                                  260      M_G_DQ<43>              
                                  261      GND                     
                                  262      M_G_DQ<53>              
                                  263      GND                     
                                  264      M_G_DQ<49>              
                                  265      GND                     
                                  266      M_G_DQS_DN<6>           
                                  267      M_G_DQS_DP<6>           
                                  268      GND                     
                                  269      M_G_DQ<55>              
                                  270      GND                     
                                  271      M_G_DQ<51>              
                                  272      GND                     
                                  273      M_G_DQ<61>              
                                  274      GND                     
                                  275      M_G_DQ<57>              
                                  276      GND                     
                                  277      M_G_DQS_DN<7>           
                                  278      M_G_DQS_DP<7>           
                                  279      GND                     
                                  280      M_G_DQ<63>              
                                  281      GND                     
                                  282      M_G_DQ<59>              
                                  283      GND                     
                                  284      PVPP_GHJ                
                                  285      SMB_DDR_GHJ_VPP_SDA     
                                  286      PVPP_GHJ                
                                  287      PVPP_GHJ                
                                  288      PVPP_GHJ                
J9U1             SCONN288_H44441003_PIP-SCONN,HA 1        P12V_NVDIMM_GHJ         
                                  2        GND                     
                                  3        M_H_DQ<4>               
                                  4        GND                     
                                  5        M_H_DQ<0>               
                                  6        GND                     
                                  7        M_H_DQS_DP<9>           
                                  8        M_H_DQS_DN<9>           
                                  9        GND                     
                                  10       M_H_DQ<6>               
                                  11       GND                     
                                  12       M_H_DQ<2>               
                                  13       GND                     
                                  14       M_H_DQ<12>              
                                  15       GND                     
                                  16       M_H_DQ<8>               
                                  17       GND                     
                                  18       M_H_DQS_DP<10>          
                                  19       M_H_DQS_DN<10>          
                                  20       GND                     
                                  21       M_H_DQ<14>              
                                  22       GND                     
                                  23       M_H_DQ<10>              
                                  24       GND                     
                                  25       M_H_DQ<20>              
                                  26       GND                     
                                  27       M_H_DQ<16>              
                                  28       GND                     
                                  29       M_H_DQS_DP<11>          
                                  30       M_H_DQS_DN<11>          
                                  31       GND                     
                                  32       M_H_DQ<22>              
                                  33       GND                     
                                  34       M_H_DQ<18>              
                                  35       GND                     
                                  36       M_H_DQ<28>              
                                  37       GND                     
                                  38       M_H_DQ<24>              
                                  39       GND                     
                                  40       M_H_DQS_DP<12>          
                                  41       M_H_DQS_DN<12>          
                                  42       GND                     
                                  43       M_H_DQ<30>              
                                  44       GND                     
                                  45       M_H_DQ<26>              
                                  46       GND                     
                                  47       M_H_ECC<4>              
                                  48       GND                     
                                  49       M_H_ECC<0>              
                                  50       GND                     
                                  51       M_H_DQS_DP<17>          
                                  52       M_H_DQS_DN<17>          
                                  53       GND                     
                                  54       M_H_ECC<6>              
                                  55       GND                     
                                  56       M_H_ECC<2>              
                                  57       GND                     
                                  58       M_GHJ_RST_N             
                                  59       PVDDQ_GHJ               
                                  60       M_H_CKE<2>              
                                  61       PVDDQ_GHJ               
                                  62       M_H_ACT_N               
                                  63       M_H_BG<0>               
                                  64       PVDDQ_GHJ               
                                  65       M_H_MA<12>              
                                  66       M_H_MA<9>               
                                  67       PVDDQ_GHJ               
                                  68       M_H_MA<8>               
                                  69       M_H_MA<6>               
                                  70       PVDDQ_GHJ               
                                  71       M_H_MA<3>               
                                  72       M_H_MA<1>               
                                  73       PVDDQ_GHJ               
                                  74       M_H_CLK_DP<2>           
                                  75       M_H_CLK_DN<2>           
                                  76       PVDDQ_GHJ               
                                  77       PVTT_GHJ                
                                  78       FM_DIMM_EVENT_COD_N     
                                  79       M_H_MA<0>               
                                  80       PVDDQ_GHJ               
                                  81       M_H_BA<0>               
                                  82       M_H_MA<16>              
                                  83       PVDDQ_GHJ               
                                  84       M_H_CS_N<4>             
                                  85       PVDDQ_GHJ               
                                  86       M_H_MA<15>              
                                  87       M_H_ODT<2>              
                                  88       PVDDQ_GHJ               
                                  89       M_H_CS_N<5>             
                                  90       PVDDQ_GHJ               
                                  91       M_H_ODT<3>              
                                  92       PVDDQ_GHJ               
                                  93       M_H_CS_N<6>             
                                  94       GND                     
                                  95       M_H_DQ<36>              
                                  96       GND                     
                                  97       M_H_DQ<32>              
                                  98       GND                     
                                  99       M_H_DQS_DP<13>          
                                  100      M_H_DQS_DN<13>          
                                  101      GND                     
                                  102      M_H_DQ<38>              
                                  103      GND                     
                                  104      M_H_DQ<34>              
                                  105      GND                     
                                  106      M_H_DQ<44>              
                                  107      GND                     
                                  108      M_H_DQ<40>              
                                  109      GND                     
                                  110      M_H_DQS_DP<14>          
                                  111      M_H_DQS_DN<14>          
                                  112      GND                     
                                  113      M_H_DQ<46>              
                                  114      GND                     
                                  115      M_H_DQ<42>              
                                  116      GND                     
                                  117      M_H_DQ<52>              
                                  118      GND                     
                                  119      M_H_DQ<48>              
                                  120      GND                     
                                  121      M_H_DQS_DP<15>          
                                  122      M_H_DQS_DN<15>          
                                  123      GND                     
                                  124      M_H_DQ<54>              
                                  125      GND                     
                                  126      M_H_DQ<50>              
                                  127      GND                     
                                  128      M_H_DQ<60>              
                                  129      GND                     
                                  130      M_H_DQ<56>              
                                  131      GND                     
                                  132      M_H_DQS_DP<16>          
                                  133      M_H_DQS_DN<16>          
                                  134      GND                     
                                  135      M_H_DQ<62>              
                                  136      GND                     
                                  137      M_H_DQ<58>              
                                  138      GND                     
                                  139      PVPP_GHJ                
                                  140      PVPP_GHJ                
                                  141      SMB_DDR_GHJ_VPP_SCL     
                                  142      PVPP_GHJ                
                                  143      PVPP_GHJ                
                                  144      TP_CH_H_DIMM0_RFU_2     
                                  145      P12V_NVDIMM_GHJ         
                                  146      M_H_VREF                
                                  147      GND                     
                                  148      M_H_DQ<5>               
                                  149      GND                     
                                  150      M_H_DQ<1>               
                                  151      GND                     
                                  152      M_H_DQS_DN<0>           
                                  153      M_H_DQS_DP<0>           
                                  154      GND                     
                                  155      M_H_DQ<7>               
                                  156      GND                     
                                  157      M_H_DQ<3>               
                                  158      GND                     
                                  159      M_H_DQ<13>              
                                  160      GND                     
                                  161      M_H_DQ<9>               
                                  162      GND                     
                                  163      M_H_DQS_DN<1>           
                                  164      M_H_DQS_DP<1>           
                                  165      GND                     
                                  166      M_H_DQ<15>              
                                  167      GND                     
                                  168      M_H_DQ<11>              
                                  169      GND                     
                                  170      M_H_DQ<21>              
                                  171      GND                     
                                  172      M_H_DQ<17>              
                                  173      GND                     
                                  174      M_H_DQS_DN<2>           
                                  175      M_H_DQS_DP<2>           
                                  176      GND                     
                                  177      M_H_DQ<23>              
                                  178      GND                     
                                  179      M_H_DQ<19>              
                                  180      GND                     
                                  181      M_H_DQ<29>              
                                  182      GND                     
                                  183      M_H_DQ<25>              
                                  184      GND                     
                                  185      M_H_DQS_DN<3>           
                                  186      M_H_DQS_DP<3>           
                                  187      GND                     
                                  188      M_H_DQ<31>              
                                  189      GND                     
                                  190      M_H_DQ<27>              
                                  191      GND                     
                                  192      M_H_ECC<5>              
                                  193      GND                     
                                  194      M_H_ECC<1>              
                                  195      GND                     
                                  196      M_H_DQS_DN<8>           
                                  197      M_H_DQS_DP<8>           
                                  198      GND                     
                                  199      M_H_ECC<7>              
                                  200      GND                     
                                  201      M_H_ECC<3>              
                                  202      GND                     
                                  203      M_H_CKE<3>              
                                  204      PVDDQ_GHJ               
                                  205      TP_CH_H_DIMM0_RFU_0     
                                  206      PVDDQ_GHJ               
                                  207      M_H_BG<1>               
                                  208      M_H_ALERT_N             
                                  209      PVDDQ_GHJ               
                                  210      M_H_MA<11>              
                                  211      M_H_MA<7>               
                                  212      PVDDQ_GHJ               
                                  213      M_H_MA<5>               
                                  214      M_H_MA<4>               
                                  215      PVDDQ_GHJ               
                                  216      M_H_MA<2>               
                                  217      PVDDQ_GHJ               
                                  218      M_H_CLK_DP<3>           
                                  219      M_H_CLK_DN<3>           
                                  220      PVDDQ_GHJ               
                                  221      PVTT_GHJ                
                                  222      M_H_PAR                 
                                  223      PVDDQ_GHJ               
                                  224      M_H_BA<1>               
                                  225      M_H_MA<10>              
                                  226      PVDDQ_GHJ               
                                  227      TP_CH_H_DIMM0_RFU_1     
                                  228      M_H_MA<14>              
                                  229      PVDDQ_GHJ               
                                  230      FM_ADR_COMPLETE_GHJ_N   
                                  231      PVDDQ_GHJ               
                                  232      M_H_MA<13>              
                                  233      PVDDQ_GHJ               
                                  234      M_H_MA<17>              
                                  235      M_H_C<2>                
                                  236      PVDDQ_GHJ               
                                  237      M_H_CS_N<7>             
                                  238      GND                     
                                  239      GND                     
                                  240      M_H_DQ<37>              
                                  241      GND                     
                                  242      M_H_DQ<33>              
                                  243      GND                     
                                  244      M_H_DQS_DN<4>           
                                  245      M_H_DQS_DP<4>           
                                  246      GND                     
                                  247      M_H_DQ<39>              
                                  248      GND                     
                                  249      M_H_DQ<35>              
                                  250      GND                     
                                  251      M_H_DQ<45>              
                                  252      GND                     
                                  253      M_H_DQ<41>              
                                  254      GND                     
                                  255      M_H_DQS_DN<5>           
                                  256      M_H_DQS_DP<5>           
                                  257      GND                     
                                  258      M_H_DQ<47>              
                                  259      GND                     
                                  260      M_H_DQ<43>              
                                  261      GND                     
                                  262      M_H_DQ<53>              
                                  263      GND                     
                                  264      M_H_DQ<49>              
                                  265      GND                     
                                  266      M_H_DQS_DN<6>           
                                  267      M_H_DQS_DP<6>           
                                  268      GND                     
                                  269      M_H_DQ<55>              
                                  270      GND                     
                                  271      M_H_DQ<51>              
                                  272      GND                     
                                  273      M_H_DQ<61>              
                                  274      GND                     
                                  275      M_H_DQ<57>              
                                  276      GND                     
                                  277      M_H_DQS_DN<7>           
                                  278      M_H_DQS_DP<7>           
                                  279      GND                     
                                  280      M_H_DQ<63>              
                                  281      GND                     
                                  282      M_H_DQ<59>              
                                  283      GND                     
                                  284      PVPP_GHJ                
                                  285      SMB_DDR_GHJ_VPP_SDA     
                                  286      PVPP_GHJ                
                                  287      PVPP_GHJ                
                                  288      PVPP_GHJ                
J9U2             SCONN288_H44441003_PIP-SCONN,HA 1        P12V_NVDIMM_GHJ         
                                  2        GND                     
                                  3        M_J_DQ<4>               
                                  4        GND                     
                                  5        M_J_DQ<0>               
                                  6        GND                     
                                  7        M_J_DQS_DP<9>           
                                  8        M_J_DQS_DN<9>           
                                  9        GND                     
                                  10       M_J_DQ<6>               
                                  11       GND                     
                                  12       M_J_DQ<2>               
                                  13       GND                     
                                  14       M_J_DQ<12>              
                                  15       GND                     
                                  16       M_J_DQ<8>               
                                  17       GND                     
                                  18       M_J_DQS_DP<10>          
                                  19       M_J_DQS_DN<10>          
                                  20       GND                     
                                  21       M_J_DQ<14>              
                                  22       GND                     
                                  23       M_J_DQ<10>              
                                  24       GND                     
                                  25       M_J_DQ<20>              
                                  26       GND                     
                                  27       M_J_DQ<16>              
                                  28       GND                     
                                  29       M_J_DQS_DP<11>          
                                  30       M_J_DQS_DN<11>          
                                  31       GND                     
                                  32       M_J_DQ<22>              
                                  33       GND                     
                                  34       M_J_DQ<18>              
                                  35       GND                     
                                  36       M_J_DQ<28>              
                                  37       GND                     
                                  38       M_J_DQ<24>              
                                  39       GND                     
                                  40       M_J_DQS_DP<12>          
                                  41       M_J_DQS_DN<12>          
                                  42       GND                     
                                  43       M_J_DQ<30>              
                                  44       GND                     
                                  45       M_J_DQ<26>              
                                  46       GND                     
                                  47       M_J_ECC<4>              
                                  48       GND                     
                                  49       M_J_ECC<0>              
                                  50       GND                     
                                  51       M_J_DQS_DP<17>          
                                  52       M_J_DQS_DN<17>          
                                  53       GND                     
                                  54       M_J_ECC<6>              
                                  55       GND                     
                                  56       M_J_ECC<2>              
                                  57       GND                     
                                  58       M_GHJ_RST_N             
                                  59       PVDDQ_GHJ               
                                  60       M_J_CKE<2>              
                                  61       PVDDQ_GHJ               
                                  62       M_J_ACT_N               
                                  63       M_J_BG<0>               
                                  64       PVDDQ_GHJ               
                                  65       M_J_MA<12>              
                                  66       M_J_MA<9>               
                                  67       PVDDQ_GHJ               
                                  68       M_J_MA<8>               
                                  69       M_J_MA<6>               
                                  70       PVDDQ_GHJ               
                                  71       M_J_MA<3>               
                                  72       M_J_MA<1>               
                                  73       PVDDQ_GHJ               
                                  74       M_J_CLK_DP<2>           
                                  75       M_J_CLK_DN<2>           
                                  76       PVDDQ_GHJ               
                                  77       PVTT_GHJ                
                                  78       FM_DIMM_EVENT_COD_N     
                                  79       M_J_MA<0>               
                                  80       PVDDQ_GHJ               
                                  81       M_J_BA<0>               
                                  82       M_J_MA<16>              
                                  83       PVDDQ_GHJ               
                                  84       M_J_CS_N<4>             
                                  85       PVDDQ_GHJ               
                                  86       M_J_MA<15>              
                                  87       M_J_ODT<2>              
                                  88       PVDDQ_GHJ               
                                  89       M_J_CS_N<5>             
                                  90       PVDDQ_GHJ               
                                  91       M_J_ODT<3>              
                                  92       PVDDQ_GHJ               
                                  93       M_J_CS_N<6>             
                                  94       GND                     
                                  95       M_J_DQ<36>              
                                  96       GND                     
                                  97       M_J_DQ<32>              
                                  98       GND                     
                                  99       M_J_DQS_DP<13>          
                                  100      M_J_DQS_DN<13>          
                                  101      GND                     
                                  102      M_J_DQ<38>              
                                  103      GND                     
                                  104      M_J_DQ<34>              
                                  105      GND                     
                                  106      M_J_DQ<44>              
                                  107      GND                     
                                  108      M_J_DQ<40>              
                                  109      GND                     
                                  110      M_J_DQS_DP<14>          
                                  111      M_J_DQS_DN<14>          
                                  112      GND                     
                                  113      M_J_DQ<46>              
                                  114      GND                     
                                  115      M_J_DQ<42>              
                                  116      GND                     
                                  117      M_J_DQ<52>              
                                  118      GND                     
                                  119      M_J_DQ<48>              
                                  120      GND                     
                                  121      M_J_DQS_DP<15>          
                                  122      M_J_DQS_DN<15>          
                                  123      GND                     
                                  124      M_J_DQ<54>              
                                  125      GND                     
                                  126      M_J_DQ<50>              
                                  127      GND                     
                                  128      M_J_DQ<60>              
                                  129      GND                     
                                  130      M_J_DQ<56>              
                                  131      GND                     
                                  132      M_J_DQS_DP<16>          
                                  133      M_J_DQS_DN<16>          
                                  134      GND                     
                                  135      M_J_DQ<62>              
                                  136      GND                     
                                  137      M_J_DQ<58>              
                                  138      GND                     
                                  139      PVPP_GHJ                
                                  140      GND                     
                                  141      SMB_DDR_GHJ_VPP_SCL     
                                  142      PVPP_GHJ                
                                  143      PVPP_GHJ                
                                  144      TP_CH_J_DIMM_J1_RFU_2   
                                  145      P12V_NVDIMM_GHJ         
                                  146      M_J_VREF                
                                  147      GND                     
                                  148      M_J_DQ<5>               
                                  149      GND                     
                                  150      M_J_DQ<1>               
                                  151      GND                     
                                  152      M_J_DQS_DN<0>           
                                  153      M_J_DQS_DP<0>           
                                  154      GND                     
                                  155      M_J_DQ<7>               
                                  156      GND                     
                                  157      M_J_DQ<3>               
                                  158      GND                     
                                  159      M_J_DQ<13>              
                                  160      GND                     
                                  161      M_J_DQ<9>               
                                  162      GND                     
                                  163      M_J_DQS_DN<1>           
                                  164      M_J_DQS_DP<1>           
                                  165      GND                     
                                  166      M_J_DQ<15>              
                                  167      GND                     
                                  168      M_J_DQ<11>              
                                  169      GND                     
                                  170      M_J_DQ<21>              
                                  171      GND                     
                                  172      M_J_DQ<17>              
                                  173      GND                     
                                  174      M_J_DQS_DN<2>           
                                  175      M_J_DQS_DP<2>           
                                  176      GND                     
                                  177      M_J_DQ<23>              
                                  178      GND                     
                                  179      M_J_DQ<19>              
                                  180      GND                     
                                  181      M_J_DQ<29>              
                                  182      GND                     
                                  183      M_J_DQ<25>              
                                  184      GND                     
                                  185      M_J_DQS_DN<3>           
                                  186      M_J_DQS_DP<3>           
                                  187      GND                     
                                  188      M_J_DQ<31>              
                                  189      GND                     
                                  190      M_J_DQ<27>              
                                  191      GND                     
                                  192      M_J_ECC<5>              
                                  193      GND                     
                                  194      M_J_ECC<1>              
                                  195      GND                     
                                  196      M_J_DQS_DN<8>           
                                  197      M_J_DQS_DP<8>           
                                  198      GND                     
                                  199      M_J_ECC<7>              
                                  200      GND                     
                                  201      M_J_ECC<3>              
                                  202      GND                     
                                  203      M_J_CKE<3>              
                                  204      PVDDQ_GHJ               
                                  205      TP_CH_J_DIMM_J1_RFU_0   
                                  206      PVDDQ_GHJ               
                                  207      M_J_BG<1>               
                                  208      M_J_ALERT_N             
                                  209      PVDDQ_GHJ               
                                  210      M_J_MA<11>              
                                  211      M_J_MA<7>               
                                  212      PVDDQ_GHJ               
                                  213      M_J_MA<5>               
                                  214      M_J_MA<4>               
                                  215      PVDDQ_GHJ               
                                  216      M_J_MA<2>               
                                  217      PVDDQ_GHJ               
                                  218      M_J_CLK_DP<3>           
                                  219      M_J_CLK_DN<3>           
                                  220      PVDDQ_GHJ               
                                  221      PVTT_GHJ                
                                  222      M_J_PAR                 
                                  223      PVDDQ_GHJ               
                                  224      M_J_BA<1>               
                                  225      M_J_MA<10>              
                                  226      PVDDQ_GHJ               
                                  227      TP_CH_J_DIMM_J1_RFU_1   
                                  228      M_J_MA<14>              
                                  229      PVDDQ_GHJ               
                                  230      FM_ADR_COMPLETE_GHJ_N   
                                  231      PVDDQ_GHJ               
                                  232      M_J_MA<13>              
                                  233      PVDDQ_GHJ               
                                  234      M_J_MA<17>              
                                  235      M_J_C<2>                
                                  236      PVDDQ_GHJ               
                                  237      M_J_CS_N<7>             
                                  238      PVPP_GHJ                
                                  239      GND                     
                                  240      M_J_DQ<37>              
                                  241      GND                     
                                  242      M_J_DQ<33>              
                                  243      GND                     
                                  244      M_J_DQS_DN<4>           
                                  245      M_J_DQS_DP<4>           
                                  246      GND                     
                                  247      M_J_DQ<39>              
                                  248      GND                     
                                  249      M_J_DQ<35>              
                                  250      GND                     
                                  251      M_J_DQ<45>              
                                  252      GND                     
                                  253      M_J_DQ<41>              
                                  254      GND                     
                                  255      M_J_DQS_DN<5>           
                                  256      M_J_DQS_DP<5>           
                                  257      GND                     
                                  258      M_J_DQ<47>              
                                  259      GND                     
                                  260      M_J_DQ<43>              
                                  261      GND                     
                                  262      M_J_DQ<53>              
                                  263      GND                     
                                  264      M_J_DQ<49>              
                                  265      GND                     
                                  266      M_J_DQS_DN<6>           
                                  267      M_J_DQS_DP<6>           
                                  268      GND                     
                                  269      M_J_DQ<55>              
                                  270      GND                     
                                  271      M_J_DQ<51>              
                                  272      GND                     
                                  273      M_J_DQ<61>              
                                  274      GND                     
                                  275      M_J_DQ<57>              
                                  276      GND                     
                                  277      M_J_DQS_DN<7>           
                                  278      M_J_DQS_DP<7>           
                                  279      GND                     
                                  280      M_J_DQ<63>              
                                  281      GND                     
                                  282      M_J_DQ<59>              
                                  283      GND                     
                                  284      PVPP_GHJ                
                                  285      SMB_DDR_GHJ_VPP_SDA     
                                  286      PVPP_GHJ                
                                  287      PVPP_GHJ                
                                  288      PVPP_GHJ                
JA9G1            CONN17_H71061002_PIP1-CONN,H71A L1       LED_LAN_0_R_N           
                                  L2       P3V3_STBY               
                                  L3       LED_LAN_2_R_N           
                                  L4       NIC_LED_ACT_ANODE_R     
                                  L5       LED_LAN_1_R_N           
                                  MH1      GND_NIC                 
                                  MH2      GND_NIC                 
                                  R1       GND_LAN_TRCT1234_C      
                                  R2       NIC_MDI_SPRV_RJ45_2_R_DN
                                  R3       NIC_MDI_SPRV_RJ45_2_R_DP
                                  R4       NIC_MDI_SPRV_RJ45_1_R_DP
                                  R5       NIC_MDI_SPRV_RJ45_1_R_DN
                                  R6       GND_LAN_TRCT1234_C      
                                  R7       GND_LAN_TRCT1234_C      
                                  R8       NIC_MDI_SPRV_RJ45_3_R_DP
                                  R9       NIC_MDI_SPRV_RJ45_3_R_DN
                                  R10      NIC_MDI_SPRV_RJ45_0_R_DN
                                  R11      NIC_MDI_SPRV_RJ45_0_R_DP
                                  R12      GND_LAN_TRCT1234_C      
L1A1             INDUCTOR_SM-0.12UH,IND,D92183-A 1        VR_PVDDQ_KLM_PH2_SW     
                                  2        PVDDQ_KLM               
L1A2             INDUCTOR_SM-0.12UH,IND,D92183-A 1        VR_PVDDQ_KLM_PH1_SW     
                                  2        PVDDQ_KLM               
L1B1             INDUCTOR_SM-100NH,IND,D92183-0B 1        P12V_STBY               
                                  2        VR_FET_SW_P12V_STBY_PVDDQ_KLM
L1B2             INDUCTOR_SM-100NH,IND,D92183-0A 1        P12V_STBY               
                                  2        VR_FET_SW_P12V_PVCCIN_CPU1_R
L1C1             INDUCTOR_SM-0.3UH,IND,D92183-0A 1        VR_PVSA_CPU1_PHASE_SW   
                                  2        PVSA_CPU1               
L1C2             INDUCTOR_SM-0.12UH,IND,D92183-A 1        VR_PVCCIN_CPU1_PHASE5   
                                  2        PVCCIN_CPU1             
L1D1             INDUCTOR_SM-0.12UH,IND,D92183-A 1        VR_PVCCIN_CPU1_PHASE4   
                                  2        PVCCIN_CPU1             
L1D2             INDUCTOR_SM-0.12UH,IND,D92183-A 1        VR_PVCCIN_CPU1_PHASE3   
                                  2        PVCCIN_CPU1             
L1D3             INDUCTOR_SM-0.12UH,IND,D92183-A 1        VR_PVCCIN_CPU1_PHASE2   
                                  2        PVCCIN_CPU1             
L1E1             INDUCTOR_SM-0.12UH,IND,D92183-A 1        VR_PVCCIN_CPU1_PHASE1   
                                  2        PVCCIN_CPU1             
L1F1             INDUCTOR_SM-100NH,IND,D92183-0B 1        P12V_STBY               
                                  2        VR_FET_SW_P12V_STBY_PVDDQ_GHJ
L1F2             INDUCTOR_SM-0.12UH,IND,D92183-A 1        VR_PVDDQ_GHJ_PH2_SW     
                                  2        PVDDQ_GHJ               
L1G1             INDUCTOR_SM-0.12UH,IND,D92183-A 1        VR_PVDDQ_GHJ_PH1_SW     
                                  2        PVDDQ_GHJ               
L1L1             CHOKE_4PIN_SM_B-67 OHM,EMPTY,7A 1        USB3_P01_RXN            
                                  2        USB3_P01_FB_RXN         
                                  3        USB3_P01_FB_RXP         
                                  4        USB3_P01_RXP            
L1M1             CHOKE_4PIN_SM_B-67 OHM,EMPTY,7A 1        USB3_P01_C_TXN          
                                  2        USB3_P01_FB_TXN         
                                  3        USB3_P01_FB_TXP         
                                  4        USB3_P01_C_TXP          
L1M2             CHOKE_4PIN_SMLF-90 OHM,EMPTY,7A 1        USB2_P01_DN             
                                  2        USB2_P01_DP             
                                  3        USB2_P01_ESD_DP         
                                  4        USB2_P01_ESD_DN         
L2M1             INDUCTOR_SMT-0.022UH,IND,72189A 1        P1V05_PCH_STBY          
                                  2        P1V05_PCH_STBY_KR_PLL   
L4A1             INDUCTOR_SM-0.47UH,IND,E13358-A 1        VR_PVPP_KLM_PHASE       
                                  2        PVPP_KLM                
L4C1             INDUCTOR_SM-100NH,IND,D92183-0A 1        P12V_STBY               
                                  2        VR_FET_SW_P12V_PVCCIN_CPU0_R
L4C2             INDUCTOR_SM-0.3UH,IND,D92183-0A 1        VR_PVSA_CPU0_PHASE_SW   
                                  2        PVSA_CPU0               
L4C3             INDUCTOR_SM-0.12UH,IND,D92183-A 1        VR_PVCCIN_CPU0_PHASE5   
                                  2        PVCCIN_CPU0             
L4D1             INDUCTOR_SM-0.12UH,IND,D92183-A 1        VR_PVCCIN_CPU0_PHASE4   
                                  2        PVCCIN_CPU0             
L4D2             INDUCTOR_SM-0.12UH,IND,D92183-A 1        VR_PVCCIN_CPU0_PHASE3   
                                  2        PVCCIN_CPU0             
L4D3             INDUCTOR_SM-0.12UH,IND,D92183-A 1        VR_PVCCIN_CPU0_PHASE2   
                                  2        PVCCIN_CPU0             
L4E1             INDUCTOR_SM-0.12UH,IND,D92183-A 1        VR_PVCCIN_CPU0_PHASE1   
                                  2        PVCCIN_CPU0             
L4E2             INDUCTOR_SM-150NH,IND,D92183-0A 1        VR_PVCCIO_CPU1_PH1_SW   
                                  2        PVCCIO_CPU1             
L4G1             INDUCTOR_SM-0.47UH,IND,E13358-A 1        VR_PVPP_GHJ_PHASE       
                                  2        PVPP_GHJ                
L7A1             INDUCTOR_SM-0.12UH,IND,D92183-A 1        VR_PVDDQ_DEF_PH1_SW     
                                  2        PVDDQ_DEF               
L7A2             INDUCTOR_SM-0.3UH,IND,D92183-0A 1        VR_PVNN_PCH_PH1_PHASE_SW
                                  2        PVNN_PCH_STBY           
L7A3             INDUCTOR_SM-0.12UH,IND,D92183-A 1        VR_PVDDQ_DEF_PH2_SW     
                                  2        PVDDQ_DEF               
L7A4             INDUCTOR_SM-0.3UH,IND,D92183-0A 1        VR_P1V05_PCH_STBY_PH1_PHASE_SW
                                  2        P1V05_PCH_STBY          
L7A5             INDUCTOR_SM-100NH,IND,D92183-0B 1        P12V_STBY               
                                  2        VR_FET_SW_P12V_STBY_PVDDQ_DEF
L7B1             INDUCTOR_SM-0.47UH,IND,E13358-A 1        VR_PVPP_DEF_PHASE       
                                  2        PVPP_DEF                
L7C1             INDUCTOR_SM-100NH,IND,D92183-0B 1        P12V_STBY               
                                  2        VR_FET_SW_P12V_STBY_PVCCIO_CPU0
L7C2             INDUCTOR_SM-150NH,IND,D92183-0A 1        VR_PVCCIO_CPU0_PH1_SW   
                                  2        PVCCIO_CPU0             
L7F1             INDUCTOR_SM-0.47UH,IND,E13358-A 1        VR_PVPP_ABC_PHASE       
                                  2        PVPP_ABC                
L7F2             INDUCTOR_SM-100NH,IND,D92183-0B 1        P12V_STBY               
                                  2        VR_FET_SW_P12V_STBY_PVDDQ_ABC
L7G1             INDUCTOR_SM-0.12UH,IND,D92183-A 1        VR_PVDDQ_ABC_PH1_SW     
                                  2        PVDDQ_ABC               
L7G2             INDUCTOR_SM-0.12UH,IND,D92183-A 1        VR_PVDDQ_ABC_PH2_SW     
                                  2        PVDDQ_ABC               
L8E1             INDUCTOR_SM-2.2UH,IND,E98761-0A 1        VR_P5V_STBY_PHASE       
                                  2        P5V_STBY                
L8F1             INDUCTOR_SM-1.00UH,IND,E98679-A 1        VR_P3V3_STBY_PHASE      
                                  2        P3V3_STBY               
Q1B1             MOSFET_N_LCC3-BSZ019N03LS,NFETA 1        P12V_FAN                
                                  4        P12V_FAN_SWITCH_G       
                                  5        P12V_STBY               
Q1D1             FET_N_DUAL_SMLF-2N7002DW,FET,DA 1        AGND_HSC                
                                  2        A_HSC_LOW_EN            
                                  3        A_HSC_ISET_S            
                                  4        AGND_HSC                
                                  5        A_HSC_HIGH_EN           
                                  6        A_HSC_ISET_S2           
Q1D2             FET_N_SOT23LF-2N7002,FET,C7925A 1        FM_OC_DETECT_EN_N       
                                  2        GND                     
                                  3        FM_OC_DETECT_EN         
Q1D3             NPN_SM-MMBT3904,IC,C52245-001 1        A_HSC_TEMP              
                                  2        GND                     
                                  3        A_HSC_TEMP              
Q1E1             PNP_TO92-MPS2907,IC,G73554-001 1        ISENSE_TMP421_2_BC      
                                  2        ISENSE_TMP421_2_E       
                                  3        ISENSE_TMP421_2_BC      
Q1L1             NPN_SM-MMBT3904,IC,C52245-001 1        FM_UART_SEL_N           
                                  2        GND                     
                                  3        FM_SOL_UART_CH_SEL      
Q1L2             FET_N_DUAL_SMLF-NTJD4001N,FET,A 1        P5V_STBY_DBG            
                                  2        FM_CPLD_DBG_PWR_EN      
                                  3        FM_CPLD_DBG_PWR_EN      
                                  4        GND                     
                                  5        FM_CPLD_DBG_PWR_EN_R_N  
                                  6        P5V_STBY                
Q1L3             NPN_SM-MMBT3904,IC,C52245-001 1        FM_DB_UART_SEL4_N       
                                  2        GND                     
                                  3        FM_DB_PRESENT           
Q1L4             FET_N_DUAL_SMLF-2N7002DW,FET,DA 1        GND                     
                                  2        FM_DB_PRESENT           
                                  3        TP_FET_Q56_3            
                                  4        TP_FET_Q56_4            
                                  5        TP_FET_Q56_4            
                                  6        FM_POST_CARD_PRES_BMC_N 
Q2P1             FET_N_SOT23LF-2N7002,FET,C7925A 1        FM_PMBUS_ALERT_BUF_EN_N 
                                  2        GND                     
                                  3        FM_PMBUS_ALERT_BUF_EN   
Q2P2             FET_N_SOT23-2N7002,FET,C79254-A 1        PWRGD_P5V_N             
                                  2        GND                     
                                  3        PWRGD_P5V_R             
Q2T1             NPN_SM-MMBT3904,IC,C52245-001 1        H_CPU0_FAST_WAKE_B_N    
                                  2        GND                     
                                  3        H_CPU0_FAST_WAKE        
Q2T2             FET_N_SOT23LF-2N7002,FET,C7925A 1        H_CPU0_FAST_WAKE        
                                  2        GND                     
                                  3        H_CPU0_FAST_WAKE_LVT3_N 
Q2U1             FET_N_DUAL_SMLF-NTJD4001N,FET,A 1        GND                     
                                  2        FM_SYS_THROTTLE_LVC3    
                                  3        H_CPU0_MEMDEF_MEMHOT_G_N
                                  4        GND                     
                                  5        FM_SYS_THROTTLE_LVC3    
                                  6        H_CPU0_MEMABC_MEMHOT_G_N
Q3U1             FET_N_DUAL_SMLF-NTJD4001N,FET,A 1        GND                     
                                  2        IRQ_PVDDQ_ABC_VRHOT_LVT3_N
                                  3        H_CPU0_MEMABC_MEMHOT_G_N
                                  4        GND                     
                                  5        H_CPU0_MEMABC_MEMHOT    
                                  6        H_CPU0_MEMABC_MEMHOT    
Q4B1             FET_N_DUAL_SMLF-NTJD4001N,FET,A 1        GND                     
                                  2        IRQ_PVDDQ_KLM_VRHOT_LVT3_N
                                  3        H_CPU1_MEMKLM_MEMHOT_G_N
                                  4        GND                     
                                  5        H_CPU1_MEMKLM_MEMHOT    
                                  6        H_CPU1_MEMKLM_MEMHOT    
Q4B2             FET_N_DUAL_SMLF-NTJD4001N,FET,A 1        GND                     
                                  2        FM_SYS_THROTTLE_LVC3    
                                  3        H_CPU1_MEMKLM_MEMHOT_G_N
                                  4        GND                     
                                  5        FM_SYS_THROTTLE_LVC3    
                                  6        H_CPU1_MEMGHJ_MEMHOT_G_N
Q4U1             FET_N_DUAL_SMLF-NTJD4001N,FET,A 1        GND                     
                                  2        FM_DIMM_EVENT_COD_N     
                                  3        FM_MEM_THERM_EVENT_LVT3_N
                                  4        GND                     
                                  5        FM_DIMM_EVENT_FET       
                                  6        FM_DIMM_EVENT_FET       
Q6F1             FET_N_SOT23-2N7002,FET,C79254-A 1        FM_ADR_COMPLETE_R       
                                  2        GND                     
                                  3        IRQ_DIMM_SAVE_N         
Q7D1             FET_N_SOT23-2N7002,FET,C79254-A 1        FM_THERMTRIP_DLY_R      
                                  2        GND                     
                                  3        FM_PCH_LVC1_THERMTRIP_N 
Q7E1             FET_N_DUAL_SMLF-NTJD4001N,FET,A 1        GND                     
                                  2        IRQ_PVDDQ_DEF_VRHOT_LVT3_N
                                  3        H_CPU0_MEMDEF_MEMHOT_G_N
                                  4        GND                     
                                  5        H_CPU0_MEMDEF_MEMHOT    
                                  6        H_CPU0_MEMDEF_MEMHOT    
Q7E2             FET_N_DUAL_SMLF-NTJD4001N,FET,A 1        GND                     
                                  2        IRQ_PVDDQ_GHJ_VRHOT_LVT3_N
                                  3        H_CPU1_MEMGHJ_MEMHOT_G_N
                                  4        GND                     
                                  5        H_CPU1_MEMGHJ_MEMHOT    
                                  6        H_CPU1_MEMGHJ_MEMHOT    
Q7E3             FET_N_DUAL_SMLF-NTJD4001N,FET,A 1        GND                     
                                  2        FM_SYS_THROTTLE_LVC3    
                                  3        H_CPU1_PROCHOT_G_N      
                                  4        GND                     
                                  5        FM_SYS_THROTTLE_LVC3    
                                  6        H_CPU0_PROCHOT_G_N      
Q7E4             FET_N_SOT23-2N7002,FET,C79254-A 1        FM_THROTTLE_R_N         
                                  2        GND                     
                                  3        FM_SYS_THROTTLE_LVC3    
Q7E5             FET_N_DUAL_SMLF-NTJD4001N,FET,A 1        GND                     
                                  2        IRQ_CPU0_PROCHOT_G_N    
                                  3        H_CPU0_PROCHOT_G_N      
                                  4        GND                     
                                  5        IRQ_CPU0_VRHOT          
                                  6        IRQ_CPU0_VRHOT          
Q7E6             FET_N_DUAL_SMLF-NTJD4001N,FET,A 1        GND                     
                                  2        IRQ_CPU1_PROCHOT_G_N    
                                  3        H_CPU1_PROCHOT_G_N      
                                  4        GND                     
                                  5        IRQ_CPU1_VRHOT          
                                  6        IRQ_CPU1_VRHOT          
Q7E7             MOSFET_N_LCC3-BSZ019N03LS,NFETA 1        P12V                    
                                  4        P12V_SWITCH_G           
                                  5        P12V_STBY               
Q7E8             FET_N_SOT23-2N7002,FET,C79254-A 1        FM_SYS_THROTTLE_LVC3    
                                  2        GND                     
                                  3        FM_PWRBRK_N             
Q8B1             MOSFET_N_LCC3-BSZ019N03LS,NFETA 1        P5V                     
                                  4        P5V_SWITCH_G            
                                  5        P5V_STBY                
Q8D1             NPN_DUAL_SSOPLF-MBT3904,XSTR,CA 1        GND                     
                                  2        IRQ_DIMM_SAVE_LVT3      
                                  3        IRQ_DIMM_SAVE_LVT3      
                                  4        GND                     
                                  5        IRQ_DIMM_SAVE_R_N       
                                  6        IRQ_DIMM_SAVE_LVT3_N    
Q8D2             FET_N_SOT23-2N7002,FET,C79254-A 1        RST_PLTRST_BUF_N        
                                  2        FM_PCH_BMC_THERMTRIP_EXI_STRAP_
                                  3        FM_PCH_BMC_THERMTRIP_N  
Q8E1             FET_N_SOT23LF-2N7002,FET,C7925A 1        RST_PLTRST_N            
                                  2        GND                     
                                  3        RST_PLTRST_TOP_SWAP     
Q8E2             FET_N_SOT23LF-2N7002,FET,C7925A 1        RST_RSMRST_DLY          
                                  2        GND                     
                                  3        IRQ_SML0_ALERT_N        
Q8F1             FET_N_SOT23LF-2N7002,FET,C7925A 1        FM_BACKUP_BIOS_SEL_N    
                                  2        GND                     
                                  3        FM_DUAL_BIOS_SEL_N      
Q8F2             FET_N_SOT23LF-2N7002,FET,C7925A 1        FM_FAST_PROCHOT_EN_N    
                                  2        GND                     
                                  3        FM_FAST_PROCHOT_EN      
Q8G1             MOSFET_N_LCC3-BSZ019N03LS,NFETA 1        P3V3                    
                                  4        P3V3_SWITCH_G           
                                  5        P3V3_STBY               
Q9A1             NPN_DUAL_SSOPLF-MBT3904,EMPTY,A 1        XDP_CPU_GTL_TCK_R2      
                                  2        XDP_CPU_TCK_BUF         
                                  3        P3V3                    
                                  4        XDP_CPU_TCK0            
                                  5        XDP_CPU_TCK_BUF         
                                  6        XDP_CPU_TCK_BUF         
Q9A2             FET_N_DUAL_SMLF-NTJD4001N,FET,A 1        GND                     
                                  2        FM_PWR_LED_N            
                                  3        FM_PWR_LED_K            
                                  4        GND                     
                                  5        FM_PWR_LED              
                                  6        FM_PWR_LED              
Q9A3             FET_N_SOT23LF-2N7002,FET,C7925A 1        FM_BIOS_TOP_SWAP_SPKR   
                                  2        GND                     
                                  3        FM_SPEAKER_PCH_N        
Q9B1             PNP_TO92-MPS2907,IC,G73554-001 1        ISENSE_TMP421_1_BC      
                                  2        ISENSE_TMP421_1_E       
                                  3        ISENSE_TMP421_1_BC      
Q9E1             FET_N_DUAL_SMLF-NTJD4001N,FET,A 1        GND                     
                                  2        FM_BMC_HEARTBEAT_N      
                                  3        FM_HEARTBEAT_LED_K      
                                  4        GND                     
                                  5        FM_HEARTBEAT_LED        
                                  6        FM_HEARTBEAT_LED        
Q9F1             FET_N_DUAL_SMLF-NTJD4001N,FET,A 1        GND                     
                                  2        FM_BMC_FAULT_LED_N      
                                  3        FM_RED_LED_CATHODE      
                                  4        GND                     
                                  5        FM_BMC_FAULT_LED        
                                  6        FM_BMC_FAULT_LED        
Q9G1             FET_N_DUAL_SMLF-NTJD4001N,FET,A 1        GND                     
                                  2        FM_BATTERY_SENSE_EN_N   
                                  3        P3V_BAT_SOURCE_R        
                                  4        A_P3V_BAT_SCALED        
                                  5        FM_BATTERY_SENSE_EN     
                                  6        FM_BATTERY_SENSE_EN     
Q9P1             FET_N_DUAL_SMLF-2N7002DW,FET,DA 1        GND                     
                                  2        A_HSC_LOW_GATE          
                                  3        IRQ_UV_DETECT_N         
                                  4        GND                     
                                  5        A_P12V_STBY_FPH_GATE    
                                  6        A_HSC_LOW_DRAIN         
Q9T1             NPN_SM-MMBT3904,IC,C52245-001 1        FM_MATED_IN_D2_N        
                                  2        GND                     
                                  3        FM_P12V_HOTSWAP0_EN     
R1A1             RES_0603-120.0,1%,1/10W,CHIP,GA 1        PVDDQ_KLM               
                                  2        GND                     
R1A2             RES_0402-68.1K,1%,1/16W,EMPTY,A 1        VR_PVDDQ_KLM_PH2_OCSET  
                                  2        GND                     
R1A3             RES_0402-68.1K,1%,1/16W,EMPTY,A 1        VR_PVDDQ_KLM_PH1_OCSET  
                                  2        GND                     
R1B1             RES_0402-1.00K,1%,1/16W,CHIP,GA 1        P3V3_STBY               
                                  2        IRQ_PVDDQ_KLM_VRHOT_LVT3_R_N
R1B2             RES_0402-1.00K,1%,1/16W,CHIP,GA 1        P3V3_STBY               
                                  2        PWRGD_PVDDQ_KLM_R       
R1B4             RES_0402-33.2,1%,1/16W,CHIP,G2A 1        IRQ_PVDDQ_KLM_VRHOT_LVT3_R_N
                                  2        IRQ_PVDDQ_KLM_VRHOT_LVT3_N
R1B5             RES_0402-22.1,1.0%,1/16W,CHIP,A 1        PWRGD_PVDDQ_KLM_R       
                                  2        PWRGD_PVDDQ_KLM         
R1B6             RES_0402-20.0,1%,1/16W,CHIP,G2A 1        SMB_VR_SCL_VDDQ_KLM     
                                  2        SMB_VR_STBY_LVC3_SCL    
R1B7             RES_0402-20.0,1%,1/16W,CHIP,G2A 1        SMB_VR_SDA_VDDQ_KLM     
                                  2        SMB_VR_STBY_LVC3_SDA    
R1B8             RES_0402-150.0,1%,1/16W,CHIP,GA 1        SVID_CLK1_CPU1_R        
                                  2        SVID_CLK_PVDDQ_KLM      
R1B9             RES_0402-1.5K,1%,1/16W,CHIP,G2A 1        VR_PVDDQ_KLM_VINSEN     
                                  2        GND                     
R1B10            RES_0402-0.0,5%,1/16W,CHIP,G21A 1        SVID_VDIO_PVDDQ_KLM     
                                  2        SVID_DIO1_CPU1_R        
R1B11            RES_0402-0.0,5%,1/16W,CHIP,G21A 1        SVID_ALERT_PVDDQ_KLM    
                                  2        SVID_ALERT1_CPU1_R_N    
R1B12            RES_0402-3.16K,1%,1/16W,CHIP,GA 1        VR_PVDDQ_KLM_XADDR1     
                                  2        GND                     
R1B13            RES_0402-2.26K,1.0%,1/16W,EMPTA 1        P3V3_STBY               
                                  2        PU_VR_PVDDQ_KLM_FAULT1  
R1B14            RES_0402-0.0,5%,1/16W,CHIP,G21A 1        VR_PVDDQ_KLM_AIINSEN_R  
                                  2        VR_PVDDQ_KLM_AIINSEN    
R1B15            RES_0402-5.36K,1.0%,1/16W,CHIPA 1        VR_PVDDQ_KLM_XADDR2     
                                  2        GND                     
R1B16            RES_0402-10.0,1%,1/16W,CHIP,G2A 1        VSENSE_PVDDQ_KLM_P      
                                  2        VR_PVDDQ_KLM_AVSP       
R1B20            RES_2010-0.001,1%,1W,CHIP,E309A 1        VR_FET_SW_P12V_PVCCIN_CPU1_R
                                  2        VR_FET_SW_P12V_STBY_PVCCIN_CPU1
R1B21            RES_0402-4.75K,1%,1/16W,CHIP,GA 1        P3V3_STBY               
                                  2        FAN_TACH2               
R1B22            RES_0402-100.0,1%,1/16W,CHIP,GA 1        FAN_TACH2               
                                  2        FAN_TACH2_CPU1_D2       
R1B23            RES_0402-100.0,1%,1/16W,CHIP,GA 1        FAN_TACH3               
                                  2        FAN_TACH3_CPU1_D2       
R1B24            RES_0402-4.75K,1%,1/16W,CHIP,GA 1        P3V3_STBY               
                                  2        FAN_TACH3               
R1C1             RES_0402-221,1.0%,1/16W,CHIP,GA 1        SVID_ALERT1_CPU1_N      
                                  2        SVID_ALERT1_CPU1_R_N    
R1C2             RES_0402-0.0,5%,1/16W,CHIP,G21A 1        SVID_DIO1_CPU1          
                                  2        SVID_DIO1_CPU1_R        
R1C3             RES_0402-0.0,5%,1/16W,CHIP,G21A 1        SVID_CLK1_CPU1          
                                  2        SVID_CLK1_CPU1_R        
R1C4             RES_0402-100.0,1%,1/16W,CHIP,GA 1        VSENSE_PVSA_CPU1_N      
                                  2        GND                     
R1C5             RES_0402-0.0,5%,1/16W,CHIP,G21A 1        VSENSE_PVSA_CPU1_N      
                                  2        VSENSE_PVSA_CPU1_SKT_VRTN
R1C6             RES_0402-1.00K,1%,1/16W,EMPTY,A 1        VSENSE_PVSA_CPU1_P      
                                  2        VSENSE_PVSA_CPU1_N      
R1C7             RES_0402-0.0,5%,1/16W,CHIP,G21A 1        VSENSE_PVSA_CPU1_P      
                                  2        VSENSE_PVSA_CPU1_SKT_VSEN
R1C9             RES_0402-0.0,5%,1/16W,EMPTY,G2A 1        IRQ_BOARD_BMC_ALERT_N   
                                  2        FAN_TACH2_R             
R1C10            RES_0402-0.0,5%,1/16W,EMPTY,G2A 1        SMB_LAN_STBY_LVC3_SDA   
                                  2        FAN_TACH3_R             
R1C11            RES_0402-0.0,5%,1/16W,EMPTY,G2A 1        SMB_LAN_STBY_LVC3_SCL   
                                  2        FAN_TACH1_R             
R1C12            RES_0402-100.0,1%,1/16W,CHIP,GA 1        VSENSE_PVSA_CPU1_P      
                                  2        PVSA_CPU1               
R1C13            RES_0402-100.0K,1%,1/16W,CHIP,B 1        VR_FET_SW_P12V_STBY_PVCCIN_CPU1
                                  2        VR_PVCCIN_CPU1_AVINSEN  
R1C14            RES_0402-0.0,5%,1/16W,CHIP,G21A 1        P3V3_STBY               
                                  2        VR_PVCCIN_CPU1_VDD      
R1C16            RES_0402-1.5K,1%,1/16W,CHIP,G2A 1        VR_PVCCIN_CPU1_AVINSEN  
                                  2        GND                     
R1C18            RES_0402-2.26K,1.0%,1/16W,EMPTA 1        P3V3_STBY               
                                  2        PU_VR_PVCCIN_CPU1_IMON  
R1C21            RES_0402-10.0,1%,1/16W,CHIP,G2A 1        VSENSE_PVSA_CPU1_P      
                                  2        VSENSE_PVSA_CPU1_BVSP   
R1C23            RES_0402-0.0,5%,1/16W,CHIP,G21A 1        SMB_VR_SDA_R1           
                                  2        SMB_VR_STBY_LVC3_SDA    
R1C25            RES_0402-0.0,5%,1/16W,CHIP,G21A 1        SMB_VR_SCL_R1           
                                  2        SMB_VR_STBY_LVC3_SCL    
R1C28            RES_0402-1.00K,1%,1/16W,CHIP,GA 1        P3V3_STBY               
                                  2        VR_VRRDY_PVCCIN_CPU1    
R1C30            RES_0402-22.1,1.0%,1/16W,CHIP,A 1        VR_VRRDY_PVCCIN_CPU1    
                                  2        PWRGD_PVCCIN_CPU1       
R1C31            RES_0402-0.0,5%,1/16W,EMPTY,G2A 1        FM_XRC_READY_N          
                                  2        FAN_TACH0_R             
R1C32            RES_0402-1.00K,1%,1/16W,CHIP,GA 1        GND                     
                                  2        PD_PIROM_CPU1_ADDR2     
R1C33            RES_0402-1.00K,1%,1/16W,CHIP,GA 1        GND                     
                                  2        PD_PIROM_CPU1_ADDR1     
R1C34            RES_0402-10.0K,1%,1/16W,CHIP,GA 1        P3V3_STBY               
                                  2        PU_PIROM_CPU1_ADDR0     
R1C35            RES_0402-3.32K,1%,1/16W,EMPTY,A 1        P3V3_STBY               
                                  2        FM_CPU1_SM_WP           
R1C36            RES_0402-1.00K,1%,1/16W,CHIP,GA 1        FM_CPU1_SM_WP           
                                  2        GND                     
R1C37            RES_0402-68.1K,1%,1/16W,EMPTY,A 1        VR_PVSA_CPU1_OCSET      
                                  2        GND                     
R1D1             RES_0402-33.2,1%,1/16W,CHIP,G2A 1        PWRGD_PVSA_CPU1_R       
                                  2        PWRGD_PVSA_CPU1         
R1D2             RES_0402-0.0,5%,1/16W,CHIP,G21A 1        SVID_VDIO_PVCCIN_CPU1   
                                  2        SVID_DIO0_CPU1_R        
R1D3             RES_0402-0.0,5%,1/16W,CHIP,G21A 1        SVID_VALERT_VCCIN_CPU1  
                                  2        SVID_ALERT0_CPU1_R_N    
R1D4             RES_0402-10.0,1%,1/16W,CHIP,G2A 1        VSENSE_PVCCIN_CPU1_P    
                                  2        VSENSE_PVCCIN_CPU1_AVSP 
R1D6             RES_0402-1.00K,1%,1/16W,CHIP,GA 1        P3V3_STBY               
                                  2        IRQ_PVCCIN_CPU1_VRHOT_LVC3_R_N
R1D7             RES_0402-2.26K,1.0%,1/16W,CHIPA 1        P3V3_STBY               
                                  2        FM_PVCCIN_CPU1_PWR_IN_ALERT_N
R1D8             RES_0402-1.00K,1%,1/16W,CHIP,GA 1        P3V3_STBY               
                                  2        PWRGD_PVSA_CPU1_R       
R1D9             RES_0402-150.0,1%,1/16W,CHIP,GA 1        SVID_CLK0_CPU1_R        
                                  2        SVID_VCLK_PVCCIN_CPU1   
R1D10            RES_0402-10.0K,1%,1/16W,CHIP,GA 1        P3V3_STBY               
                                  2        A_HSC_LOW_GATE          
R1D11            RES_0402-100.0K,1%,1/16W,CHIP,A 1        A_HSC_LOW_EN            
                                  2        AGND_HSC                
R1D12            RES_0402-10.0K,1%,1/16W,CHIP,GA 1        A_HSC_LOW               
                                  2        AGND_HSC                
R1D13            RES_0402-90.9K,1%,1/16W,CHIP,GA 1        A_HSC_ISET_S            
                                  2        A_HSC_ISET              
R1D14            RES_0402-105.0K,1%,1/16W,CHIP,A 1        A_HSC_CSOUT             
                                  2        A_HSC_LOW               
R1D15            RES_0402-100.0K,1%,1/16W,CHIP,A 1        P12V_PSU                
                                  2        A_HSC_OCP_SEL           
R1D16            RES_0402-69.8K,1%,1/16W,CHIP,GA 1        A_HSC_ISET              
                                  2        A_HSC_ISET_S2           
R1D18            RES_0402-100.0K,1%,1/16W,CHIP,A 1        A_HSC_HIGH_EN           
                                  2        AGND_HSC                
R1D19            RES_0402-10.0K,1%,1/16W,CHIP,GA 1        A_HSC_HIGH              
                                  2        AGND_HSC                
R1D20            RES_0402-150.0K,1%,1/16W,CHIP,A 1        A_HSC_CSOUT             
                                  2        A_HSC_HIGH              
R1D21            RES_0402-4.75K,1%,1/16W,CHIP,GA 1        P3V3_STBY               
                                  2        FM_OC_DETECT_EN         
R1D22            RES_0402-10.0K,1%,1/16W,CHIP,GA 1        P3V3_STBY               
                                  2        FM_OC_DETECT_N          
R1D23            RES_0402-10.0K,1%,1/16W,CHIP,GA 1        P3V3_STBY               
                                  2        IRQ_OC_DETECT_N         
R1D24            RES_0402-0.0,5%,1/16W,CHIP,G21A 1        SMB_BMC_PMBUS_STBY_LVC3_SCL
                                  2        SMB_3V3SB_HSC_SCL_R     
R1D25            RES_0402-0.0,5%,1/16W,CHIP,G21A 1        SMB_BMC_PMBUS_STBY_LVC3_SDA
                                  2        SMB_3V3SB_HSC_SDA_R     
R1D26            RES_0402-33.2,1%,1/16W,CHIP,G2A 1        IRQ_SML1_PMBUS_ALERT_R_N
                                  2        IRQ_SML1_PMBUS_ALERT_N  
R1D27            RES_0402-4.75K,1%,1/16W,EMPTY,A 1        A_HSC_VCAP              
                                  2        FM_P12V_HSC_ADR2        
R1D28            RES_0402-100.0,1%,1/16W,EMPTY,A 1        PD_HSC_RETRY_N          
                                  2        AGND_HSC                
R1D29            RES_0402-4.75K,1%,1/16W,EMPTY,A 1        A_HSC_VCAP              
                                  2        FM_P12V_HSC_ADR1        
R1D30            RES_0402-33.2,1%,1/16W,CHIP,G2A 1        IRQ_HSC_FAULT_R_N       
                                  2        IRQ_HSC_FAULT_N         
R1D31            RES_0402-6.19K,1%,1/16W,CHIP,GA 1        PWRGD_P12V_R            
                                  2        GND                     
R1D32            RES_0402-100.0K,1%,1/16W,CHIP,A 1        A_HSC_VCAP              
                                  2        A_HSC_ISTART            
R1D33            RES_0402-33.2,1%,1/16W,CHIP,G2A 1        PWRGD_P12V_R            
                                  2        PWRGD_P12V_HSC          
R1D34            RES_0402-16K,1.0%,1/16W,CHIP,GA 1        A_HSC_ISTART            
                                  2        AGND_HSC                
R1D35            RES_0402-4.75K,1%,1/16W,CHIP,GA 1        P3V3_STBY               
                                  2        FM_OC_DETECT_EN_N       
R1D36            RES_0402-1.00K,1%,1/16W,CHIP,GA 1        P12V_STBY               
                                  2        A_HSC_VOUT              
R1D37            RES_0402-100.0K,1%,1/16W,CHIP,A 1        A_HSC_VCAP              
                                  2        A_HSC_ISET              
R1D39            RES_0402-100.0K,1%,1/16W,CHIP,A 1        A_HSC_VCAP              
                                  2        A_HSC_PSET              
R1D40            RES_0402-40.2K,1%,1/16W,CHIP,GA 1        A_HSC_PSET              
                                  2        AGND_HSC                
R1D41            RES_0805-0.0,5%,1/8W,CHIP,G221A 1        GND                     
                                  2        AGND_HSC                
R1D42            RES_0402-11K,1%,1/16W,CHIP,G21A 1        A_HSC_UV                
                                  2        AGND_HSC                
R1D43            RES_0402-7.5K,1%,1/16W,CHIP,G2A 1        A_HSC_OV                
                                  2        AGND_HSC                
R1D44            RES_0402-0.0,5%,1/16W,CHIP,G21A 1        A_HSC_MOP               
                                  2        A_HSC_HSP               
R1D45            RES_0402-0.0,5%,1/16W,CHIP,G21A 1        A_HSC_MON               
                                  2        A_HSC_HSN               
R1D46            RES_0402-10.0,1%,1/16W,CHIP,G2A 1        P12V_HSC_SENP0          
                                  2        A_HSC_HSP               
R1D47            RES_0402-10.0,1%,1/16W,CHIP,G2A 1        P12V_HSC_SENN0          
                                  2        A_HSC_HSN               
R1D48            RES_0402-10.0,1%,1/16W,CHIP,G2A 1        A_HSC_GATE              
                                  2        A_HSC_GATE3_R           
R1D49            RES_PWR_6PAD-0.001,1%,3W,CHIP,A 1        P12V_PSU                
                                  2        P12V_MB0_SW             
                                  3        P12V_HSC_SENP0          
                                  4        P12V_HSC_SENN0          
                                  5        P12V_PSU                
                                  6        P12V_MB0_SW             
R1D51            RES_0402-10.0,1%,1/16W,CHIP,G2A 1        A_HSC_C                 
                                  2        A_HSC_GATE              
R1D52            RES_0402-68.1K,1%,1/16W,EMPTY,A 1        VR_PVCCIN_CPU1_PH5_OCSET
                                  2        GND                     
R1D53            RES_0402-2.26K,1.0%,1/16W,EMPTA 1        P3V3_STBY               
                                  2        PU_VR_PVCCIN_CPU1_FLT1_SMBALT_N
R1D54            RES_0402-68.1K,1%,1/16W,EMPTY,A 1        VR_PVCCIN_CPU1_PH4_OCSET
                                  2        GND                     
R1D55            RES_0402-68.1K,1%,1/16W,EMPTY,A 1        VR_PVCCIN_CPU1_PH3_OCSET
                                  2        GND                     
R1E1             RES_0402-10.0,1%,1/16W,CHIP,G2A 1        A_HSC_GATE              
                                  2        A_HSC_GATE1_R           
R1E3             RES_0603-100.0,1%,1/10W,CHIP,GA 1        PVCCIN_CPU1             
                                  2        GND                     
R1E4             RES_0402-100.0,1%,1/16W,CHIP,GA 1        VSENSE_PVCCIN_CPU1_P    
                                  2        PVCCIN_CPU1             
R1E5             RES_0402-1.00K,1%,1/16W,EMPTY,A 1        VSENSE_PVCCIN_CPU1_P    
                                  2        VSENSE_PVCCIN_CPU1_N    
R1E6             RES_0402-0.0,5%,1/16W,CHIP,G21A 1        VSENSE_PVCCIN_CPU1_P    
                                  2        VSENSE_PVCCIN_CPU1_SKT_VSEN
R1E7             RES_0402-0.0,5%,1/16W,CHIP,G21A 1        VSENSE_PVCCIN_CPU1_N    
                                  2        VSENSE_PVCCIN_CPU1_SKT_VRTN
R1E8             RES_0402-100.0,1%,1/16W,CHIP,GA 1        VSENSE_PVCCIN_CPU1_N    
                                  2        GND                     
R1E9             RES_0402-1.00K,1%,1/16W,CHIP,GA 1        P3V3_STBY               
                                  2        PU_TMP421_2_A0          
R1E10            RES_0402-1.00K,1%,1/16W,CHIP,GA 1        P3V3_STBY               
                                  2        PD_TMP421_2_A1          
R1E11            RES_0402-10.0K,1%,1/16W,EMPTY,A 1        P3V3_STBY               
                                  2        FM_ENABLE_FAN_POWER     
R1E12            RES_0402-4.75K,1%,1/16W,CHIP,GA 1        P5V_STBY                
                                  2        FAN_PWM_OUT_SYS0_R      
R1E13            RES_0402-68.1K,1%,1/16W,EMPTY,A 1        VR_PVCCIN_CPU1_PH2_OCSET
                                  2        GND                     
R1E14            RES_0402-68.1K,1%,1/16W,EMPTY,A 1        VR_PVCCIN_CPU1_PH1_OCSET
                                  2        GND                     
R1F1             RES_0402-4.75K,1%,1/16W,CHIP,GA 1        P3V3_STBY               
                                  2        FAN_TACH0               
R1F2             RES_0402-100.0,1%,1/16W,CHIP,GA 1        FAN_TACH0               
                                  2        FAN_TACH0_CPU0_D2       
R1F3             RES_1206-0.002,1%,1W,CHIP,G521A 1        P12V_NVDIMM_GHJ         
                                  2        P12V_STBY               
R1F4             RES_0402-2,1.0%,1/16W,CHIP,G21A 1        M_G_CPU_VREF            
                                  2        M_G_VREF                
R1F5             RES_0402-1.00K,1%,1/16W,CHIP,GA 1        PVDDQ_GHJ               
                                  2        M_G_VREF                
R1F6             RES_0402-1.00K,1%,1/16W,CHIP,GA 1        M_G_VREF                
                                  2        GND                     
R1F8             RES_0402-0.0,5%,1/16W,CHIP,G21A 1        FAN_TACH0               
                                  2        FAN_TACH0_R             
R1F9             RES_0402-0.0,5%,1/16W,EMPTY,G2A 1        FM_BMC_READY_N          
                                  2        FAN_PWM_OUT_SYS0_R1     
R1G1             RES_0402-2,1.0%,1/16W,CHIP,G21A 1        M_H_CPU_VREF            
                                  2        M_H_VREF                
R1G2             RES_0402-1.00K,1%,1/16W,CHIP,GA 1        PVDDQ_GHJ               
                                  2        M_H_VREF                
R1G3             RES_0402-1.00K,1%,1/16W,CHIP,GA 1        M_H_VREF                
                                  2        GND                     
R1G5             RES_0402-10.0,1%,1/16W,CHIP,G2A 1        VSENSE_PVDDQ_GHJ_P      
                                  2        VR_PVDDQ_GHJ_AVSP       
R1G6             RES_0402-2.26K,1.0%,1/16W,EMPTA 1        P3V3_STBY               
                                  2        PU_VR_PVDDQ_GHJ_FAULT1  
R1G7             RES_0402-150.0,1%,1/16W,CHIP,GA 1        SVID_CLK1_CPU1_R        
                                  2        SVID_CLK_PVDDQ_GHJ      
R1G8             RES_0402-33.2,1%,1/16W,CHIP,G2A 1        IRQ_PVDDQ_GHJ_VRHOT_LVT3_R_N
                                  2        IRQ_PVDDQ_GHJ_VRHOT_LVT3_N
R1G9             RES_0402-0.0,5%,1/16W,CHIP,G21A 1        SVID_ALERT_PVDDQ_GHJ    
                                  2        SVID_ALERT1_CPU1_R_N    
R1G10            RES_0402-0.0,5%,1/16W,CHIP,G21A 1        SVID_VDIO_PVDDQ_GHJ     
                                  2        SVID_DIO1_CPU1_R        
R1G11            RES_0402-1.00K,1%,1/16W,CHIP,GA 1        P3V3_STBY               
                                  2        IRQ_PVDDQ_GHJ_VRHOT_LVT3_R_N
R1G12            RES_0402-22.1,1.0%,1/16W,CHIP,A 1        PWRGD_PVDDQ_GHJ_R       
                                  2        PWRGD_PVDDQ_GHJ         
R1G14            RES_0402-2,1.0%,1/16W,CHIP,G21A 1        M_J_CPU_VREF            
                                  2        M_J_VREF                
R1G15            RES_0402-1.00K,1%,1/16W,CHIP,GA 1        PVDDQ_GHJ               
                                  2        M_J_VREF                
R1G16            RES_0402-1.00K,1%,1/16W,CHIP,GA 1        P3V3_STBY               
                                  2        PWRGD_PVDDQ_GHJ_R       
R1G17            RES_0402-1.00K,1%,1/16W,CHIP,GA 1        M_J_VREF                
                                  2        GND                     
R1G19            RES_0402-0.0,5%,1/16W,CHIP,G21A 1        SMB_VR_SCL_VDDQ_GHJ     
                                  2        SMB_VR_STBY_LVC3_SCL    
R1G20            RES_0603-120.0,1%,1/10W,CHIP,GA 1        PVDDQ_GHJ               
                                  2        GND                     
R1G21            RES_0402-0.0,5%,1/16W,CHIP,G21A 1        SMB_VR_SDA_VDDQ_GHJ     
                                  2        SMB_VR_STBY_LVC3_SDA    
R1G22            RES_0402-5.36K,1.0%,1/16W,CHIPA 1        VR_PVDDQ_GHJ_XADDR2     
                                  2        GND                     
R1G23            RES_0402-4.02K,1%,1/16W,CHIP,GA 1        VR_PVDDQ_GHJ_XADDR1     
                                  2        GND                     
R1G24            RES_0402-1.5K,1%,1/16W,CHIP,G2A 1        VR_PVDDQ_GHJ_VINSEN     
                                  2        GND                     
R1G25            RES_0402-68.1K,1%,1/16W,EMPTY,A 1        VR_PVDDQ_GHJ_PH2_OCSET  
                                  2        GND                     
R1G26            RES_0402-68.1K,1%,1/16W,EMPTY,A 1        VR_PVDDQ_GHJ_PH1_OCSET  
                                  2        GND                     
R1G27            RES_0402-0.0,5%,1/16W,CHIP,G21A 1        VR_PVDDQ_GHJ_VD12       
                                  2        VR_PVDDQ_GHJ_AIREF2     
R1G28            RES_0402-0.0,5%,1/16W,CHIP,G21A 1        VR_PVDDQ_GHJ_VD12       
                                  2        VR_PVDDQ_GHJ_AIREF1     
R1L1             RES_0402-2.0K,1%,1/16W,CHIP,G2A 1        P3V3                    
                                  2        PU_DATAIN1_SATA_2       
R1L2             RES_0402-10.0,1%,1/16W,CHIP,G2A 1        FM_CPLD_DBG_PWR_EN_N    
                                  2        FM_CPLD_DBG_PWR_EN_R_N  
R1L3             RES_0402-1.00K,1%,1/16W,CHIP,GA 1        PD_SATA2_CONTROLLER_TYPE
                                  2        GND                     
R1L4             RES_0402-40.2K,1%,1/16W,CHIP,GA 1        FM_UART_SWITCH_N        
                                  2        FM_UART_SEL_N           
R1L5             RES_0402-1.00K,1%,1/16W,CHIP,GA 1        P3V3_STBY               
                                  2        FM_SOL_UART_CH_SEL      
R1L6             RES_0402-0.0,5%,1/16W,CHIP,G21A 1        FM_UART_SWITCH_N        
                                  2        FM_DB_UART_SEL0_N       
R1L7             RES_0402-4.75K,1%,1/16W,CHIP,GA 1        P3V3_STBY               
                                  2        FM_BMC_CPLD_MP_RST_N    
R1L8             RES_0402-470.0,5%,1/16W,CHIP,GA 1        P5V_STBY                
                                  2        FP_ID_LED_XOR_R         
R1L9             RES_0402-100.0K,1%,1/16W,CHIP,A 1        P12V_STBY               
                                  2        FM_CPLD_DBG_PWR_EN      
R1L11            RES_0402-10.0,1%,1/16W,CHIP,G2A 1        LED_POSTCODE_7          
                                  2        LED_POSTCODE_7_R        
R1L12            RES_0402-0.0,5%,1/16W,CHIP,G21A 1        PWRGD_P3V3              
                                  2        PWRGD_P3V3_R            
R1L13            RES_0402-1.00K,1%,1/16W,CHIP,GA 1        XDP_SYSPWROK            
                                  2        P3V3_STBY               
R1L14            RES_0402-10.0,1%,1/16W,CHIP,G2A 1        LED_POSTCODE_6          
                                  2        LED_POSTCODE_6_R        
R1L15            RES_0402-150.0,1%,1/16W,CHIP,GA 1        PVCCIO_CPU0             
                                  2        XDP_CPU_TMS             
R1L16            RES_0402-49.9,1%,1/16W,CHIP,G2A 1        PWRGD_P3V3_R1           
                                  2        PWRGD_P3V3              
R1L17            RES_0402-150.0,1%,1/16W,CHIP,GA 1        XDP_CPU_PWR_DEBUG_N     
                                  2        PVCCIO_CPU0             
R1L18            RES_0402-10.0,1%,1/16W,CHIP,G2A 1        LED_POSTCODE_5          
                                  2        LED_POSTCODE_5_R        
R1L19            RES_0402-4.75K,1%,1/16W,EMPTY,A 1        P3V3_STBY               
                                  2        FM_DEBUG_RST_BTN_N      
R1L20            RES_0402-10.0,1%,1/16W,CHIP,G2A 1        LED_POSTCODE_4          
                                  2        LED_POSTCODE_4_R        
R1L21            RES_0402-64.9,1.0%,1/16W,CHIP,A 1        P3V3                    
                                  2        FP_LED_HDD_ACTIVITY_AND_R_N
R1L22            RES_0402-200.0,1%,1/16W,CHIP,GA 1        FM_DEBUG_RST_BTN_N      
                                  2        FP_RST_BTN_R_N          
R1L23            RES_0402-1.00K,1%,1/16W,CHIP,GA 1        XDP_PWRGD_RST_N         
                                  2        P3V3_STBY               
R1L24            RES_0402-10.0,1%,1/16W,CHIP,G2A 1        LED_POSTCODE_3          
                                  2        LED_POSTCODE_3_R        
R1L25            RES_0402-10.0,1%,1/16W,CHIP,G2A 1        LED_POSTCODE_2          
                                  2        LED_POSTCODE_2_R        
R1L26            RES_0402-33.2,1%,1/16W,CHIP,G2A 1        FM_PWR_BTN_R_N          
                                  2        FM_PWR_BTN_N            
R1L27            RES_0402-4.75K,1%,1/16W,CHIP,GA 1        P3V3_STBY               
                                  2        FP_PWR_BTN_R_N          
R1L28            RES_0402-4.75K,1%,1/16W,CHIP,GA 1        P3V3_STBY               
                                  2        FM_DEBUG_RST_BTN_R1_N   
R1L29            RES_0402-33.2,1%,1/16W,CHIP,G2A 1        FM_DEBUG_RST_BTN_R1_N   
                                  2        FM_DEBUG_RST_BTN_N      
R1L30            RES_0402-10.0,1%,1/16W,CHIP,G2A 1        LED_POSTCODE_1          
                                  2        LED_POSTCODE_1_R        
R1L31            RES_0402-200.0,1%,1/16W,CHIP,GA 1        FP_PWR_BTN_R_N          
                                  2        FP_PWR_BTN_R1_N         
R1L32            RES_0402-10.0,1%,1/16W,CHIP,G2A 1        LED_POSTCODE_0          
                                  2        LED_POSTCODE_0_R        
R1L33            RES_0402-221,1.0%,1/16W,CHIP,GA 1        FM_BEEP_LED_P           
                                  2        P3V3_STBY               
R1L36            RES_0402-1.00K,1%,1/16W,CHIP,GA 1        P3V3_STBY               
                                  2        FM_DB_PRESENT           
R1L37            RES_0402-301.0,1%,1/16W,CHIP,GA 1        P5V_STBY                
                                  2        LED_P5V_STBY            
R1L38            RES_0402-1.00K,1%,1/16W,CHIP,GA 1        P3V3_STBY               
                                  2        FM_POST_CARD_PRES_BMC_N 
R1L39            RES_0402-100.0,1%,1/16W,CHIP,GA 1        P1V05_PCH_STBY          
                                  2        XDP_PRDY_N              
R1L40            RES_0402-0.0,5%,1/16W,CHIP,G21A 1        USB3_P01_RXP            
                                  2        USB3_P01_FB_RXP         
R1L41            RES_0402-100.0,1%,1/16W,CHIP,GA 1        P1V05_PCH_STBY          
                                  2        XDP_PREQ_N              
R1L42            RES_0402-0.0,5%,1/16W,CHIP,G21A 1        USB3_P01_RXN            
                                  2        USB3_P01_FB_RXN         
R1L43            RES_0402-330,5%,1/16W,CHIP,G21A 1        FM_UARTSW_LSB_R_N       
                                  2        P3V3_STBY               
R1L44            RES_0402-330,5%,1/16W,CHIP,G21A 1        FM_UARTSW_MSB_R_N       
                                  2        P3V3_STBY               
R1M1             RES_0402-0.0,5%,1/16W,CHIP,G21A 1        USB3_P01_C_TXP          
                                  2        USB3_P01_FB_TXP         
R1M2             RES_0402-0.0,5%,1/16W,CHIP,G21A 1        USB3_P01_C_TXN          
                                  2        USB3_P01_FB_TXN         
R1M3             RES_0402-100.0,1%,1/16W,CHIP,GA 1        PVCCIO_CPU0             
                                  2        XDP_CPU_PRDY_N          
R1M4             RES_0402-100.0,1%,1/16W,CHIP,GA 1        PVCCIO_CPU0             
                                  2        XDP_CPU_PREQ_N          
R1M5             RES_0402-0.0,5%,1/16W,CHIP,G21A 1        USB2_P01_DP             
                                  2        USB2_P01_ESD_DP         
R1M6             RES_0402-0.0,5%,1/16W,CHIP,G21A 1        USB2_P01_DN             
                                  2        USB2_P01_ESD_DN         
R1M8             RES_0402-20.0,1%,1/16W,CHIP,G2A 1        SMB_SENSOR_TMP421_1_SCL 
                                  2        SMB_SENSOR_STBY_LVC3_SCL
R1M9             RES_0402-20.0,1%,1/16W,CHIP,G2A 1        SMB_SENSOR_TMP421_1_SDA 
                                  2        SMB_SENSOR_STBY_LVC3_SDA
R1M10            RES_0402-0.0,5%,1/16W,CHIP,G21A 1        LED_PCH_SATA_HDD_N      
                                  2        LED_SATA_ACT_R_N        
R1M11            RES_0402-10.0K,1%,1/16W,CHIP,GA 1        P3V3                    
                                  2        LED_SATA_ACT_R_N        
R1M12            RES_0402-10.0K,1%,1/16W,CHIP,GA 1        P3V3                    
                                  2        LED_SAS_ACT_R_N         
R1M13            RES_0402-0.0,5%,1/16W,CHIP,G21A 1        LED_PCH_SSATA_HDD_N     
                                  2        LED_SAS_ACT_R_N         
R1M14            RES_0402-200.0,1%,1/16W,CHIP,GA 1        RST_PCIE_CPU_DEV0_N     
                                  2        RST_PCIE_CPU_DEV0_R_N   
R1M15            RES_0402-0.0,5%,1/16W,CHIP,G21A 1        RMII_BMC_OCP_CRSDV      
                                  2        RMII_BMC_OCP_CRSDV_R    
R1M16            RES_0402-0.0,5%,1/16W,CHIP,G21A 1        RMII_BMC_OCP_RXD1       
                                  2        RMII_BMC_OCP_RXD1_R     
R1M17            RES_0402-0.0,5%,1/16W,CHIP,G21A 1        RMII_BMC_OCP_RXD0       
                                  2        RMII_BMC_OCP_RXD0_R     
R1M18            RES_0402-0.0,5%,1/16W,CHIP,G21A 1        RMII_BMC_OCP_RXER_R     
                                  2        RMII_BMC_OCP_RXER       
R1M19            RES_0402-1.00K,1%,1/16W,CHIP,GA 1        P1V8_MCP_CPU0           
                                  2        JTAG_MCP_TMS            
R1M20            RES_0402-1.00K,1%,1/16W,CHIP,GA 1        P1V8_MCP_CPU0           
                                  2        JTAG_MCP_MUX_TDI        
R1M21            RES_0402-1.00K,1%,1/16W,CHIP,GA 1        P1V8_MCP_CPU0           
                                  2        JTAG_MCP_TRST_N         
R1M22            RES_0402-49.9,1%,1/16W,CHIP,G2A 1        JTAG_MCP_TMS_R1         
                                  2        JTAG_MCP_TMS            
R1M23            RES_0402-1.00K,1%,1/16W,EMPTY,A 1        JTAG_MCP_TRST_N         
                                  2        GND                     
R1M24            RES_0402-10.0K,1%,1/16W,CHIP,GA 1        P3V3_STBY               
                                  2        FM_OC0_USB_N            
R1M25            RES_0402-10.0K,1%,1/16W,CHIP,GA 1        FM_USB_P0_EN_BOOT_BIOS_STRAP_N
                                  2        GND                     
R1R1             RES_0402-0.0,5%,1/16W,CHIP,G21A 1        RST_PLTRST_N            
                                  2        RST_PLTRST_SPRV_R_N     
R1R3             RES_0402-3.32K,1%,1/16W,CHIP,GA 1        P3V3_STBY               
                                  2        PU_NV_WP_N              
R1R4             RES_0402-10.0K,1%,1/16W,CHIP,GA 1        P3V3_STBY               
                                  2        RMII_BMC_PCH_SPRNGVLLE_TXD0
R1R5             RES_0402-4.75K,1%,1/16W,CHIP,GA 1        P3V3_STBY               
                                  2        FM_FAST_PROCHOT_THROTTLE_DLY_BU
R1R6             RES_0402-3.32K,1%,1/16W,EMPTY,A 1        SPI_NIC_MOSI            
                                  2        GND                     
R1R7             RES_0402-20.0K,1%,1/16W,CHIP,GA 1        P3V3_STBY               
                                  2        SPI_NIC_MOSI            
R1R8             RES_0402-0.0,5%,1/16W,CHIP,G21A 1        FM_THROTTLE_R1_N        
                                  2        FM_THROTTLE_N           
R1R9             RES_0402-3.32K,1%,1/16W,CHIP,GA 1        P3V3_STBY               
                                  2        PU_NV_HOLD_N            
R1R10            RES_0402-10.0K,1%,1/16W,CHIP,GA 1        P3V3_STBY               
                                  2        RMII_SPRNGVLLE_BMC_PCH_RXD0
R1R11            RES_0402-4.75K,1%,1/16W,CHIP,GA 1        FM_BMC_DISABLE          
                                  2        P3V3_STBY               
R1R12            RES_0402-10.0K,1%,1/16W,CHIP,GA 1        CLK_50M_CKMNG_SPRVLLE   
                                  2        GND                     
R1R13            RES_0402-10.0K,1%,1/16W,CHIP,GA 1        P3V3_STBY               
                                  2        RMII_SPRNGVLLE_BMC_PCH_RXD1
R1R15            RES_0603-0,5.0%,1/10W,CHIP,G22A 1        P0V9_LAN                
                                  2        P0V9_LAN_I210           
R1R16            RES_0402-2.21K,1%,1/16W,CHIP,GA 1        P3V3_STBY               
                                  2        SMB_PCH_MEZZ_LOM2_SCL   
R1R17            RES_0402-2.21K,1%,1/16W,CHIP,GA 1        P3V3_STBY               
                                  2        SMB_PCH_MEZZ_LOM2_SDA   
R1R18            RES_0402-2.21K,1%,1/16W,CHIP,GA 1        P3V3_STBY               
                                  2        SMB_PCH_MEZZ_LOM0_SCL   
R1R19            RES_0402-2.21K,1%,1/16W,CHIP,GA 1        P3V3_STBY               
                                  2        SMB_PCH_MEZZ_LOM0_SDA   
R1R20            RES_0402-2.21K,1%,1/16W,CHIP,GA 1        P3V3_STBY               
                                  2        SMB_PCH_MEZZ_LOM1_SCL   
R1R21            RES_0402-2.21K,1%,1/16W,CHIP,GA 1        P3V3_STBY               
                                  2        SMB_PCH_MEZZ_LOM1_SDA   
R1R22            RES_0402-2.21K,1%,1/16W,CHIP,GA 1        P3V3_STBY               
                                  2        SMB_PCH_MEZZ_LOM3_SDA   
R1R23            RES_0402-2.21K,1%,1/16W,CHIP,GA 1        P3V3_STBY               
                                  2        SMB_PCH_MEZZ_LOM3_SCL   
R1T1             RES_0402-10.0K,1%,1/16W,CHIP,GA 1        RMII_BMC_PCH_SPRNGVLLE_CRSDV
                                  2        GND                     
R1T2             RES_0402-665,1.0%,1/16W,CHIP,GA 1        P3V3_STBY               
                                  2        SMB_SLOTX24_STBY_LVC3_SCL_R
R1T3             RES_0402-665,1.0%,1/16W,CHIP,GA 1        P3V3_STBY               
                                  2        SMB_SLOTX24_STBY_LVC3_SDA_R
R1T4             RES_0402-2.7K,1%,1/16W,CHIP,G2A 1        P3V3_STBY               
                                  2        FM_BOARD_REV_ID0        
R1T5             RES_0402-2.7K,1%,1/16W,EMPTY,GA 1        P3V3_STBY               
                                  2        FM_BOARD_REV_ID2        
R1T6             RES_0402-2.7K,1%,1/16W,EMPTY,GA 1        P3V3_STBY               
                                  2        FM_BOARD_REV_ID1        
R1T7             RES_0402-20.0,1%,1/16W,CHIP,G2A 1        SMB_SLOTX24_STBY_LVC3_SCL_R
                                  2        SMB_SLOTX24_BMC_STBY_LVC3_SCL
R1T8             RES_0402-20.0,1%,1/16W,CHIP,G2A 1        SMB_SLOTX24_STBY_LVC3_SDA_R
                                  2        SMB_SLOTX24_BMC_STBY_LVC3_SDA
R1T9             RES_0402-22.1,1.0%,1/16W,CHIP,A 1        PWRGD_P1V538_BMC_STBY_R 
                                  2        PWRGD_P1V538_BMC_STBY   
R1T10            RES_0402-1.00K,1%,1/16W,EMPTY,A 1        FM_BOARD_REV_ID0        
                                  2        GND                     
R1T11            RES_0402-1.00K,1%,1/16W,CHIP,GA 1        FM_BOARD_REV_ID2        
                                  2        GND                     
R1T12            RES_0402-1.00K,1%,1/16W,CHIP,GA 1        FM_BOARD_REV_ID1        
                                  2        GND                     
R1T13            RES_0402-4.75K,1%,1/16W,EMPTY,A 1        FM_ROMA<23>             
                                  2        P3V3_STBY               
R1T14            RES_0402-4.75K,1%,1/16W,CHIP,GA 1        FM_ROMA<12>             
                                  2        P3V3_STBY               
R1T15            RES_0402-0.0,5%,1/16W,EMPTY,G2A 1        FM_BMC_ONCTL_N          
                                  2        FM_BMC_ONCTL_R_N        
R1T16            RES_0402-4.75K,1%,1/16W,EMPTY,A 1        FM_ROMA<5>              
                                  2        P3V3_STBY               
R1T17            RES_0402-4.75K,1%,1/16W,EMPTY,A 1        FM_ROMA<21>             
                                  2        P3V3_STBY               
R1T18            RES_0402-4.75K,1%,1/16W,EMPTY,A 1        FM_ROMA<18>             
                                  2        P3V3_STBY               
R1T19            RES_0402-4.75K,1%,1/16W,EMPTY,A 1        FM_ROMA<9>              
                                  2        P3V3_STBY               
R1T20            RES_0402-4.75K,1%,1/16W,EMPTY,A 1        FM_ROMA<17>             
                                  2        P3V3_STBY               
R1T21            RES_0402-4.75K,1%,1/16W,EMPTY,A 1        FM_ROMA<13>             
                                  2        P3V3_STBY               
R1T22            RES_0402-4.75K,1%,1/16W,EMPTY,A 1        FM_ROMA<16>             
                                  2        P3V3_STBY               
R1T23            RES_0402-0.0,5%,1/16W,EMPTY,G2A 1        FM_BMC_ONCTL_R_N        
                                  2        GND                     
R1T24            RES_0402-0.0,5%,1/16W,EMPTY,G2A 1        FM_FLASH_DESC_OVERRIDE_R
                                  2        FM_FLASH_DESC_OVERRIDE  
R1T25            RES_0402-8.2K,1%,1/16W,CHIP,G2A 1        A_USB2VRES              
                                  2        GND                     
R1T26            RES_0402-22.1,1.0%,1/16W,CHIP,A 1        SPI_BMC_BT_CS_N         
                                  2        SPI_BMC_BT_CS_R_N       
R1T27            RES_0402-240,1.0%,1/16W,CHIP,GA 1        A_M_BMC_ZQ              
                                  2        GND                     
R1T28            RES_0402-22.1,1.0%,1/16W,CHIP,A 1        RMII_BMC_PCH_SPRNGVLLE_TXD0_R
                                  2        RMII_BMC_PCH_SPRNGVLLE_TXD0
R1T29            RES_0402-1.00K,1%,1/16W,CHIP,GA 1        M_BMC_DDR3_MVREF        
                                  2        GND                     
R1T30            RES_0402-1.00K,1%,1/16W,CHIP,GA 1        P1V538_BMC_STBY         
                                  2        M_BMC_DDR3_MVREF        
R1T32            RES_0603-0,5.0%,1/10W,CHIP,G22A 1        P1V5_LAN                
                                  2        P1V5_LAN_I210           
R1T33            RES_0603-0,5.0%,1/10W,EMPTY,G2A 1        P1V5_LAN                
                                  2        P3V3_STBY_P1V5_LAN_I210 
R1T34            RES_0603-0,5.0%,1/10W,CHIP,G22A 1        P3V3_STBY               
                                  2        P3V3_STBY_P1V5_LAN_I210 
R1T35            RES_0402-0.0,5%,1/16W,EMPTY,G2A 1        FM_CPU0_PROCHOT_LVT3_N  
                                  2        FM_CPU0_PROCHOT_PCH_N   
R1T36            RES_0402-0.0,5%,1/16W,CHIP,G21A 1        FM_CPU0_PROCHOT_LVT3_N  
                                  2        FM_CPU0_PROCHOT_LVT3_BMC_N
R1T37            RES_0402-0.0,5%,1/16W,CHIP,G21A 1        FM_CPU1_PROCHOT_LVT3_N  
                                  2        FM_CPU1_PROCHOT_LVT3_BMC_N
R1T38            RES_0402-0.0,5%,1/16W,EMPTY,G2A 1        FM_CPU1_PROCHOT_LVT3_N  
                                  2        FM_CPU1_PROCHOT_PCH_N   
R1U1             RES_0402-100.0K,1%,1/16W,CHIP,A 1        FAN_TACH0               
                                  2        GND                     
R1U2             RES_0402-100.0K,1%,1/16W,CHIP,A 1        FAN_TACH1               
                                  2        GND                     
R1U3             RES_0402-0.0,5%,1/16W,CHIP,G21A 1        GND                     
                                  2        GND_NIC                 
R1U4             RES_0402-100.0K,1%,1/16W,CHIP,A 1        FAN_TACH2               
                                  2        GND                     
R1U5             RES_0402-100.0K,1%,1/16W,CHIP,A 1        FAN_TACH3               
                                  2        GND                     
R1U6             RES_0402-10.0K,1%,1/16W,CHIP,GA 1        FM_BIOS_SPI_BMC_CTRL    
                                  2        GND                     
R1U7             RES_0402-10.0K,1%,1/16W,CHIP,GA 1        GND                     
                                  2        PD_SP_ENTEST            
R1U8             RES_0402-0.0,5%,1/16W,CHIP,G21A 1        SMB_VR_STBY_LVC3_SDA_R  
                                  2        SMB_VR_STBY_LVC3_SDA    
R1U9             RES_0402-20.0,1%,1/16W,CHIP,G2A 1        SMB_SMLINK0_STBY_LVC3_SCL_R
                                  2        SMB_SMLINK0_STBY_LVC3_SCL
R1U10            RES_0402-20.0,1%,1/16W,CHIP,G2A 1        SMB_SMLINK0_STBY_LVC3_SDA_R
                                  2        SMB_SMLINK0_STBY_LVC3_SDA
R1U11            RES_0402-0.0,5%,1/16W,CHIP,G21A 1        SMB_VR_STBY_LVC3_SCL_R  
                                  2        SMB_VR_STBY_LVC3_SCL    
R1U12            RES_0402-51,5.0%,1/16W,CHIP,G2A 1        SGPIO_BMC_LD_R_N        
                                  2        SGPIO_BMC_LD_N          
R1U13            RES_0402-51,5.0%,1/16W,CHIP,G2A 1        SGPIO_BMC_DOUT_R        
                                  2        SGPIO_BMC_DOUT          
R1U14            RES_0402-51,5.0%,1/16W,CHIP,G2A 1        SGPIO_BMC_CLK_R         
                                  2        SGPIO_BMC_CLK           
R1U15            RES_0402-1.00K,1%,1/16W,EMPTY,A 1        FM_BOARD_SKU_ID3        
                                  2        GND                     
R1U16            RES_0402-1.00K,1%,1/16W,EMPTY,A 1        FM_BOARD_SKU_ID1        
                                  2        GND                     
R1U17            RES_0402-1.00K,1%,1/16W,CHIP,GA 1        FM_BOARD_SKU_ID2        
                                  2        GND                     
R1U18            RES_0402-1.00K,1%,1/16W,CHIP,GA 1        FM_BOARD_SKU_ID0        
                                  2        GND                     
R1U19            RES_0402-20.0,1%,1/16W,CHIP,G2A 1        SMB_SMLINK0_STBY_LVC3_SCL
                                  2        SMB_SPRINGVILLE_STBY_LVC3_SCL
R1U20            RES_0402-20.0,1%,1/16W,CHIP,G2A 1        SMB_SMLINK0_STBY_LVC3_SDA
                                  2        SMB_SPRINGVILLE_STBY_LVC3_SDA
R1U21            RES_0402-2.7K,1%,1/16W,CHIP,G2A 1        P3V3_STBY               
                                  2        FM_BOARD_SKU_ID3        
R1U22            RES_0402-2.7K,1%,1/16W,CHIP,G2A 1        P3V3_STBY               
                                  2        FM_BOARD_SKU_ID1        
R1U23            RES_0402-2.7K,1%,1/16W,EMPTY,GA 1        P3V3_STBY               
                                  2        FM_BOARD_SKU_ID0        
R1U24            RES_0402-2.7K,1%,1/16W,EMPTY,GA 1        P3V3_STBY               
                                  2        FM_BOARD_SKU_ID2        
R1U25            RES_0402-20.0,1%,1/16W,CHIP,G2A 1        SMB_SENSOR_PCH_STBY_LVC3_SCL
                                  2        SMB_SENSOR_STBY_LVC3_SCL
R1U26            RES_0402-5.11K,1%,1/16W,CHIP,GA 1        P3V3                    
                                  2        A_P3V3_SCALED           
R1U27            RES_0402-8.2K,1%,1/16W,CHIP,G2A 1        A_P3V3_SCALED           
                                  2        GND                     
R1U28            RES_0402-3.48K,1.0%,1/16W,CHIPA 1        A_P5V_SCALED            
                                  2        GND                     
R1U29            RES_0402-5.11K,1%,1/16W,CHIP,GA 1        P5V                     
                                  2        A_P5V_SCALED            
R1U30            RES_0402-1.00K,1%,1/16W,CHIP,GA 1        PD_DIR_2                
                                  2        GND                     
R1U31            RES_0402-20.0,1%,1/16W,CHIP,G2A 1        SMB_SENSOR_PCH_STBY_LVC3_SDA
                                  2        SMB_SENSOR_STBY_LVC3_SDA
R1U32            RES_0402-5.11K,1%,1/16W,CHIP,GA 1        P12V_STBY               
                                  2        A_P12V_STBY_SCALED      
R1U33            RES_0402-1.00K,1%,1/16W,CHIP,GA 1        A_P12V_STBY_SCALED      
                                  2        GND                     
R1U34            RES_0402-33.2,1%,1/16W,CHIP,G2A 1        H_CPU1_MEMKLM_MEMHOT_LVT3_K_N
                                  2        H_CPU1_MEMKLM_MEMHOT_LVT3_N
R1U35            RES_0402-150.0,1%,1/16W,CHIP,GA 1        PVCCIO_CPU1             
                                  2        H_CPU1_MEMKLM_MEMHOT_G_N
R1U36            RES_0402-33.2,1%,1/16W,CHIP,G2A 1        H_CPU1_MEMGHJ_MEMHOT_LVT3_K_N
                                  2        H_CPU1_MEMGHJ_MEMHOT_LVT3_N
R1U37            RES_0402-100.0,1%,1/16W,CHIP,GA 1        P0V7_GTL2014_2          
                                  2        GND                     
R1U38            RES_0402-8.2K,1%,1/16W,CHIP,G2A 1        A_P3V3_STBY_SCALED      
                                  2        GND                     
R1U39            RES_0402-5.11K,1%,1/16W,CHIP,GA 1        P3V3_STBY               
                                  2        A_P3V3_STBY_SCALED      
R1U40            RES_0402-33.2,1%,1/16W,CHIP,G2A 1        IRQ_VM_INT_R_N          
                                  2        IRQ_VM_INT_N            
R1U41            RES_0402-150.0,1%,1/16W,CHIP,GA 1        PVCCIO_CPU1             
                                  2        H_CPU1_MEMGHJ_MEMHOT_G_N
R1U43            RES_0402-49.9,1%,1/16W,CHIP,G2A 1        PVCCIO_CPU0             
                                  2        P0V7_GTL2014_2          
R1U44            RES_0402-3.48K,1.0%,1/16W,CHIPA 1        A_P5V_STBY_SCALED       
                                  2        GND                     
R1U45            RES_0402-4.75K,1%,1/16W,CHIP,GA 1        FM_ADC128_A0            
                                  2        GND                     
R1U46            RES_0402-33.2,1%,1/16W,CHIP,G2A 1        H_CPU0_MEMABC_MEMHOT_LVT3_K_N
                                  2        H_CPU0_MEMABC_MEMHOT_LVT3_N
R1U47            RES_0402-5.11K,1%,1/16W,CHIP,GA 1        P5V_STBY                
                                  2        A_P5V_STBY_SCALED       
R1U48            RES_0402-4.75K,1%,1/16W,CHIP,GA 1        FM_ADC128_A1            
                                  2        GND                     
R1U49            RES_0402-2.7K,1%,1/16W,CHIP,G2A 1        P3V3_STBY               
                                  2        FM_BATTERY_SENSE_EN     
R1U50            RES_0402-200.0K,1%,1/16W,CHIP,A 1        A_P3V_BAT_R             
                                  2        P3V_BAT_SOURCE_R        
R1U51            RES_0402-0.0,5%,1/16W,CHIP,G21A 1        GND                     
                                  2        GND_NIC                 
R1U52            RES_0402-1.5K,1%,1/16W,CHIP,G2A 1        P3V3_STBY               
                                  2        USB_PCH_BMC_P4_DN       
R1U53            RES_0402-0.0,5%,1/16W,CHIP,G21A 1        H_CPU1_MEMGHJ_MEMHOT_G_N
                                  2        H_CPU1_MEMGHJ_MEMHOT_G_R_N
R1U54            RES_0402-0.0,5%,1/16W,CHIP,G21A 1        H_CPU1_MEMGHJ_MEMHOT_LVT3_N
                                  2        H_CPU1_MEMGHJ_MEMHOT_LVT3_BMC_N
R1U55            RES_0402-0.0,5%,1/16W,EMPTY,G2A 1        H_CPU1_MEMGHJ_MEMHOT_G_N
                                  2        H_CPU1_MEMGHJ_MEMHOT_G_PCH_N
R1U56            RES_0402-0.0,5%,1/16W,EMPTY,G2A 1        H_CPU0_MEMDEF_MEMHOT_G_PCH_N
                                  2        H_CPU0_MEMDEF_MEMHOT_G_N
R1U57            RES_0402-0.0,5%,1/16W,EMPTY,G2A 1        H_CPU1_MEMGHJ_MEMHOT_LVT3_K_N
                                  2        H_CPU1_MEMGHJ_MEMHOT_G_PCH_N
R1U58            RES_0402-0.0,5%,1/16W,CHIP,G21A 1        H_CPU0_MEMDEF_MEMHOT_G_N
                                  2        H_CPU0_MEMDEF_MEMHOT_G_R_N
R1U59            RES_0402-0.0,5%,1/16W,CHIP,G21A 1        H_CPU0_ABC_MEMHOT_LVT3_R_N
                                  2        H_CPU0_MEMABC_MEMHOT_LVT3_K_N
R1U60            RES_0402-0.0,5%,1/16W,CHIP,G21A 1        H_CPU1_MEMKLM_MEMHOT_G_N
                                  2        H_CPU1_MEMKLM_MEMHOT_G_R_N
R1U61            RES_0402-0.0,5%,1/16W,EMPTY,G2A 1        H_CPU1_MEMKLM_MEMHOT_LVT3_K_N
                                  2        H_CPU1_MEMKLM_MEMHOT_G_PCH_N
R1U62            RES_0402-0.0,5%,1/16W,EMPTY,G2A 1        H_CPU1_MEMKLM_MEMHOT_G_N
                                  2        H_CPU1_MEMKLM_MEMHOT_G_PCH_N
R1U63            RES_0402-1.00K,1%,1/16W,CHIP,GA 1        PD_RST_RTCRST_N         
                                  2        GND                     
R1U64            RES_0402-1.00K,1%,1/16W,CHIP,GA 1        PD_IE_DEBUG_MODE        
                                  2        GND                     
R2L1             RES_0402-0.0,5%,1/16W,CHIP,G21A 1        VR_PVNN_P1V05_PCH_VD12  
                                  2        VR_PVNN_PCH_AIREF1      
R2L4             RES_0402-2.0K,1%,1/16W,CHIP,G2A 1        P3V3_STBY               
                                  2        SGPIO_PCH_SSATA_DOUT0_R 
R2L5             RES_0402-2.0K,1%,1/16W,CHIP,G2A 1        P3V3_STBY               
                                  2        SGPIO_PCH_SSATA_LOAD_R  
R2L6             RES_0402-2.0K,1%,1/16W,CHIP,G2A 1        P3V3_STBY               
                                  2        SGPIO_PCH_SSATA_CLOCK_R 
R2L7             RES_0402-0.0,5%,1/16W,CHIP,G21A 1        VR_PVNN_P1V05_PCH_VD12  
                                  2        VR_P1V05_PCH_BIREF1     
R2L8             RES_0603-10.0,1%,1/10W,CHIP,G2A 1        VSENSE_P1V05_PCH_STBY_AVSP
                                  2        VR_P1V05_PCH_STBY_AVSP  
R2L9             RES_0402-4.02K,1%,1/16W,CHIP,GA 1        VR_PVNN_PCH_XADDR1      
                                  2        GND                     
R2L10            RES_0402-1.5K,1%,1/16W,CHIP,G2A 1        VR_PVNN_PCH_VINSEN      
                                  2        GND                     
R2L11            RES_0402-2.0K,1%,1/16W,CHIP,G2A 1        P3V3_STBY               
                                  2        SGPIO_PCH_SATA_CLOCK_R  
R2L12            RES_0402-2.0K,1%,1/16W,CHIP,G2A 1        P3V3_STBY               
                                  2        SGPIO_PCH_SATA_LOAD_R   
R2L14            RES_0402-0.0,5%,1/16W,CHIP,G21A 1        P3V3_STBY               
                                  2        VR_PVNN_PCH_VDD         
R2L15            RES_0402-2.0K,1%,1/16W,CHIP,G2A 1        P3V3_STBY               
                                  2        SGPIO_PCH_SATA_DOUT0_R  
R2L16            RES_0402-22.1,1.0%,1/16W,CHIP,A 1        PWRGD_PVNN_PCH_R        
                                  2        PWRGD_PVNN_P1V05_PCH    
R2L17            RES_0402-0.0,5%,1/16W,CHIP,G21A 1        PWRGD_P1V8_PCH_STBY     
                                  2        VR_PVNN_PCH_VREN        
R2L18            RES_0402-1.00K,1%,1/16W,CHIP,GA 1        PD_SATA0_CONTROLLER_TYPE_R
                                  2        GND                     
R2L19            RES_0402-49.9K,1%,1/16W,CHIP,GA 1        VR_P1V8_PCH_STBY_FB     
                                  2        GND                     
R2L20            RES_0402-63.4K,1.0%,1/16W,CHIPA 1        P1V8_PCH_STBY           
                                  2        VR_P1V8_PCH_STBY_FB     
R2L21            RES_0402-2.0K,1%,1/16W,CHIP,G2A 1        P3V3                    
                                  2        PU_DATAIN1_SATA_0_R     
R2L22            RES_0402-1.00K,1%,1/16W,CHIP,GA 1        PD_SATA1_CONTROLLER_TYPE_R
                                  2        GND                     
R2L23            RES_0402-2.0K,1%,1/16W,CHIP,G2A 1        P3V3                    
                                  2        PU_DATAIN1_SATA_1_R     
R2L24            RES_0402-2.26K,1.0%,1/16W,EMPTA 1        P3V3_STBY               
                                  2        PU_VR_PVNN_PCH_FAULT1   
R2L25            RES_0402-100.0K,1%,1/16W,EMPTYA 1        P3V3_STBY               
                                  2        VID_PCH_CORE_PVNN_AUX_VID_1
R2L26            RES_0402-100.0K,1%,1/16W,EMPTYA 1        P3V3_STBY               
                                  2        VID_PCH_CORE_PVNN_AUX_VID_0
R2M1             RES_0402-33.2,1%,1/16W,CHIP,G2A 1        FM_CPLD_ADR_TRIGGER_N   
                                  2        FM_CPLD_ADR_TRIGGER_R_N 
R2M2             RES_0402-4.75K,1%,1/16W,CHIP,GA 1        P3V3_STBY               
                                  2        FM_ADR_SMI_GPIO_N       
R2M3             RES_0402-33.2,1%,1/16W,CHIP,G2A 1        FM_PCH_PLD_DATA_R       
                                  2        FM_PCH_PLD_DATA         
R2M4             RES_0402-1.00K,1%,1/16W,CHIP,GA 1        P3V3_STBY               
                                  2        IRQ_HSC_FAULT_N         
R2M5             RES_0402-4.75K,1%,1/16W,CHIP,GA 1        P3V3_STBY               
                                  2        FM_BMC_CPLD_GPO         
R2M6             RES_0402-1.0K,0.1%,1/16W,CHIP,A 1        A_KR1_RBIAS             
                                  2        P1V05_PCH_STBY_KR_PLL   
R2M7             RES_0402-33.2,1%,1/16W,CHIP,G2A 1        FM_ADR_MODE_SEL_R       
                                  2        FM_ADR_MODE_SEL         
R2M8             RES_0402-1.5K,1%,1/16W,CHIP,G2A 1        P3V3_STBY               
                                  2        FM_CPU0_RC_ERROR_N      
R2N1             RES_0402-33.2,1%,1/16W,CHIP,G2A 1        FM_CPU_CATERR_DLY_LVT3_R_N
                                  2        FM_CPU_CATERR_DLY_LVT3_N
R2N4             RES_0402-1.0K,0.1%,1/16W,CHIP,A 1        P1V05_PCH_STBY_KR_PLL   
                                  2        A_KR0_RBIAS             
R2N5             RES_0402-665,1.0%,1/16W,CHIP,GA 1        P3V3_STBY               
                                  2        SMB_SMLINK0_STBY_LVC3_SCL
R2N6             RES_0402-10.0K,1%,1/16W,CHIP,GA 1        P3V3_STBY               
                                  2        FM_GBE_LOM_DISABLE_N    
R2N7             RES_0402-4.75K,1%,1/16W,CHIP,GA 1        P3V3_STBY               
                                  2        IRQ_BOARD_BMC_ALERT_N   
R2N8             RES_0402-665,1.0%,1/16W,CHIP,GA 1        P3V3_STBY               
                                  2        SMB_SMLINK0_STBY_LVC3_SDA
R2N9             RES_0402-10.0K,1%,1/16W,CHIP,GA 1        P3V3_STBY               
                                  2        PU_10GBE_LOM_PCI_DISABLE_N
R2N10            RES_0402-4.75K,1%,1/16W,CHIP,GA 1        P3V3_STBY               
                                  2        FM_PCH_BMC_THERMTRIP_EXI_STRAP_
R2N12            RES_0402-10.0K,1%,1/16W,EMPTY,A 1        GND                     
                                  2        PWRGD_SYS_PWROK         
R2N13            RES_0402-10.0K,1%,1/16W,CHIP,GA 1        FM_BIOS_PREFRB2_GOOD    
                                  2        GND                     
R2N14            RES_0402-1.00K,1%,1/16W,EMPTY,A 1        P3V3_STBY               
                                  2        FM_USB_P0_EN_BOOT_BIOS_STRAP_N
R2N16            RES_0402-10.0K,1%,1/16W,CHIP,GA 1        P3V3_STBY               
                                  2        PU_IRQ_VRALERT_N        
R2N17            RES_0402-2.7K,1%,1/16W,EMPTY,GA 1        P3V3_STBY               
                                  2        FM_BOARD_SKU_ID4        
R2N18            RES_0402-1.00K,1%,1/16W,CHIP,GA 1        FM_BOARD_SKU_ID4        
                                  2        GND                     
R2N19            RES_0402-49.9,1%,1/16W,CHIP,G2A 1        SGPIO_PCH_SSATA_LOAD    
                                  2        SGPIO_PCH_SSATA_LOAD_R  
R2N20            RES_0402-0.0,5%,1/16W,CHIP,G21A 1        SMB_LAN_STBY_LVC3_SDA_R2
                                  2        SMB_LAN_STBY_LVC3_SDA   
R2N21            RES_0402-0.0,5%,1/16W,CHIP,G21A 1        SMB_LAN_STBY_LVC3_SCL_R2
                                  2        SMB_LAN_STBY_LVC3_SCL   
R2N22            RES_0402-49.9,1%,1/16W,CHIP,G2A 1        SGPIO_PCH_SSATA_CLOCK   
                                  2        SGPIO_PCH_SSATA_CLOCK_R 
R2N23            RES_0402-10.0K,1%,1/16W,CHIP,GA 1        P3V3_STBY               
                                  2        FM_QAT_EN_N             
R2N24            RES_0402-1.00K,1%,1/16W,EMPTY,A 1        FM_QAT_EN_N             
                                  2        GND                     
R2N25            RES_0402-51.1,1.0%,1/16W,CHIP,A 1        FM_NMI_EVENT_N          
                                  2        FM_BMC_NMI_N            
R2N26            RES_0402-33.2,1%,1/16W,CHIP,G2A 1        FM_ADR_COMPLETE         
                                  2        FM_ADR_COMPLETE_R1      
R2N27            RES_0402-4.75K,1%,1/16W,CHIP,GA 1        P3V3                    
                                  2        FM_BMC_NMI_N            
R2N28            RES_0402-10.0K,1%,1/16W,CHIP,GA 1        P3V3_STBY               
                                  2        FM_PASSWORD_CLEAR_N     
R2N29            RES_0402-1.5K,1%,1/16W,CHIP,G2A 1        P3V3_STBY               
                                  2        FM_CPU1_RC_ERROR_N      
R2N31            RES_0402-49.9,1%,1/16W,CHIP,G2A 1        SGPIO_PCH_SATA_CLOCK    
                                  2        SGPIO_PCH_SATA_CLOCK_R  
R2N32            RES_0402-4.75K,1%,1/16W,CHIP,GA 1        P3V3_STBY               
                                  2        FM_BIOS_SMI_ACTIVE_N    
R2P1             RES_0402-0.0,5%,1/16W,CHIP,G21A 1        RMII_SPRNGVLLE_BMC_PCH_RXD1
                                  2        RMII_SPRNGVLLE_BMC_PCH_RXD1_R1
R2P2             RES_0402-1.00K,1%,1/16W,CHIP,GA 1        SPI_PCH_IO2             
                                  2        XDP_DEBUG_CONSENT_N     
R2P3             RES_0402-4.75K,1%,1/16W,CHIP,GA 1        P3V3_STBY               
                                  2        IRQ_FORCE_NM_THROTTLE_R_N
R2P4             RES_0402-33.2,1%,1/16W,CHIP,G2A 1        IRQ_FORCE_NM_THROTTLE_R_N
                                  2        IRQ_FORCE_NM_THROTTLE_N 
R2P5             RES_0402-4.75K,1%,1/16W,CHIP,GA 1        P3V3_STBY               
                                  2        FM_PMBUS_ALERT_BUF_EN   
R2P8             RES_0402-560,5%,1/16W,CHIP,G21A 1        P3V3_STBY               
                                  2        IRQ_SML1_PMBUS_ALERT_N  
R2P11            RES_0402-1.00K,1%,1/16W,EMPTY,A 1        FM_PMBUS_ALERT_BUF_EN_N 
                                  2        GND                     
R2P12            RES_0402-0.0,5%,1/16W,EMPTY,G2A 1        IRQ_DIMM_SAVE_LVT3_N    
                                  2        FM_ADR_SMI_GPIO_N       
R2P13            RES_0402-4.75K,1%,1/16W,CHIP,GA 1        P3V3_STBY               
                                  2        FM_PMBUS_ALERT_BUF_EN_N 
R2P14            RES_0402-0.0,5%,1/16W,CHIP,G21A 1        FM_M2_DET_LVC3          
                                  2        FM_SSATA_PCIE_M2_SEL    
R2P15            RES_0402-10.0K,1%,1/16W,CHIP,GA 1        P3V3                    
                                  2        FM_M2_SSD_PEDET         
R2P16            RES_0402-10.0K,1%,1/16W,CHIP,GA 1        P3V3_STBY               
                                  2        FM_M2_DET_LVC3          
R2P17            RES_0402-4.75K,1%,1/16W,CHIP,GA 1        P3V3_STBY               
                                  2        FM_PCH_BMC_THERMTRIP_N  
R2P18            RES_0402-10.0K,1%,1/16W,CHIP,GA 1        P3V3_STBY               
                                  2        PWRGD_P5V_N             
R2P19            RES_0402-10.0K,1%,1/16W,CHIP,GA 1        P3V3_STBY               
                                  2        FM_DIS_ADR_DLY          
R2P20            RES_0402-100.0,1%,1/16W,CHIP,GA 1        PWRGD_P5V_R             
                                  2        PWRGD_P5V               
R2P21            RES_0402-10.0K,1%,1/16W,CHIP,GA 1        P3V3_STBY               
                                  2        PWRGD_P5V_R             
R2P22            RES_0402-10.0K,1%,1/16W,CHIP,GA 1        P3V3_STBY               
                                  2        FM_CPU1_RC_EN           
R2R1             RES_0402-10.0K,1%,1/16W,CHIP,GA 1        P3V3_STBY               
                                  2        PU_RST_PERST_BIT0       
R2R2             RES_0402-33.2,1%,1/16W,CHIP,G2A 1        RST_RSMRST_R_N          
                                  2        RST_RSMRST_N            
R2R3             RES_0402-10.0K,1%,1/16W,CHIP,GA 1        P3V3_STBY               
                                  2        FM_PLD_DEBUG_MODE_N     
R2R4             RES_0402-0.0,5%,1/16W,CHIP,G21A 1        FM_ADR_SMI_GPIO_R_N     
                                  2        FM_ADR_SMI_GPIO_N       
R2R5             RES_0402-1.00K,1%,1/16W,CHIP,GA 1        P3V3_STBY               
                                  2        FM_PCH_PLD_DATA         
R2R6             RES_0402-51,5.0%,1/16W,CHIP,G2A 1        SGPIO_BMC_DIN_R         
                                  2        SGPIO_BMC_DIN           
R2R7             RES_0402-4.75K,1%,1/16W,CHIP,GA 1        P3V3_STBY               
                                  2        FM_FORCE_ADR_N          
R2R8             RES_0402-100.0,1%,1/16W,CHIP,GA 1        FM_MEZZ_PRSNTB1_N       
                                  2        GND                     
R2R9             RES_0402-200.0,1%,1/16W,CHIP,GA 1        FP_NMI_BTN_OUT_R_N      
                                  2        FP_NMI_BTN_OUT_N        
R2R10            RES_0402-33.2,1%,1/16W,CHIP,G2A 1        FP_NMI_BTN_R_N          
                                  2        FP_NMI_BTN_N            
R2R11            RES_0402-1.00K,1%,1/16W,EMPTY,A 1        SPI_PCH_IO2             
                                  2        GND                     
R2R12            RES_0402-0.0,5%,1/16W,CHIP,G21A 1        SPI_PCH_IO2             
                                  2        SPI_PCH_IO2_R1          
R2T1             RES_0402-1.00K,1%,1/16W,CHIP,GA 1        SPI_PCH_IO3             
                                  2        GND                     
R2T2             RES_0402-0.0,5%,1/16W,CHIP,G21A 1        SPI_PCH_IO3             
                                  2        SPI_PCH_IO3_R1          
R2T3             RES_0402-4.75K,1%,1/16W,CHIP,GA 1        P3V3_STBY               
                                  2        FM_FAST_PROCHOT_EN_N    
R2T4             RES_0402-1.0K,0.1%,1/16W,CHIP,A 1        P3V3_STBY               
                                  2        GND                     
R2T5             RES_0402-1.00K,1%,1/16W,CHIP,GA 1        P3V3_STBY               
                                  2        H_CPU0_FAST_WAKE        
R2T6             RES_0402-4.75K,1%,1/16W,CHIP,GA 1        P3V3_STBY               
                                  2        FM_BACKUP_BIOS_SEL_N    
R2T7             RES_0402-1.00K,1%,1/16W,CHIP,GA 1        P3V3_STBY               
                                  2        H_CPU0_FAST_WAKE_LVT3_N 
R2T8             RES_0402-10.0K,1%,1/16W,CHIP,GA 1        P3V3_STBY               
                                  2        SPI_SWITCH_CS0_N        
R2T9             RES_0402-75,1.0%,1/16W,CHIP,G2A 1        SPI_CS0_SECONDARY_N     
                                  2        SPI_CS0_SECONDARY_R_N   
R2T11            RES_0402-4.75K,1%,1/16W,CHIP,GA 1        P3V3_STBY               
                                  2        FM_DUAL_BIOS_SEL_N      
R2T12            RES_0402-10.0K,1%,1/16W,EMPTY,A 1        PD_PEREXT               
                                  2        GND                     
R2T13            RES_0402-200.0,1%,1/16W,CHIP,GA 1        SPI_CS0_PRIMARY_N       
                                  2        SPI_CS0_PRIMARY_R_N     
R2T15            RES_0402-100.0K,1%,1/16W,CHIP,A 1        CLK_24M_BMC_LPC         
                                  2        GND                     
R2T16            RES_0402-75,1.0%,1/16W,CHIP,G2A 1        H_CPU_ERR0_GTL_R_N      
                                  2        H_CPU_ERR0_GTL_N        
R2T17            RES_0402-0.0,5%,1/16W,CHIP,G21A 1        H_CPU0_ERR0_G_N         
                                  2        H_CPU_ERR0_GTL_R_N      
R2T18            RES_0402-49.9,1%,1/16W,CHIP,G2A 1        RST_BMC_SYSRST_BTN_OUT_B_R_N
                                  2        RST_BMC_SYSRST_BTN_OUT_B_N
R2T19            RES_0402-200.0,1%,1/16W,CHIP,GA 1        PVCCIO_CPU0             
                                  2        H_CPU_ERR0_GTL_R_N      
R2T20            RES_0402-0.0,5%,1/16W,CHIP,G21A 1        H_CPU1_ERR0_G_N         
                                  2        H_CPU_ERR0_GTL_R_N      
R2T21            RES_0603-2.2,1.0%,1/10W,CHIP,GA 1        P3V3_STBY_MNG           
                                  2        P3V3_STBY_MNG_CPU       
R2T22            RES_0402-10.0K,1%,1/16W,CHIP,GA 1        P3V3_STBY               
                                  2        RST_BMC_SYSRST_BTN_OUT_B_R_N
R2T23            RES_0603-2.2,1.0%,1/10W,CHIP,GA 1        P3V3_STBY_MNG           
                                  2        P3V3_STBY_MNG_RGMII     
R2T24            RES_0402-33.2,1%,1/16W,CHIP,G2A 1        IRQ_LPC_SERIRQ_N        
                                  2        IRQ_LPC_SERIRQ_R        
R2T25            RES_0402-1.00K,1%,1/16W,CHIP,GA 1        PD_CKMNG_OE             
                                  2        GND                     
R2T26            RES_0402-200.0,1%,1/16W,CHIP,GA 1        PVCCIO_CPU0             
                                  2        H_CPU_ERR1_GTL_R_N      
R2T27            RES_0402-0.0,5%,1/16W,CHIP,G21A 1        H_CPU1_ERR1_G_N         
                                  2        H_CPU_ERR1_GTL_R_N      
R2T28            RES_0402-33.2,1%,1/16W,CHIP,G2A 1        FM_PCH_PWRBTN_R_N       
                                  2        FM_PCH_PWRBTN_N         
R2T29            RES_0402-2.21K,1%,1/16W,CHIP,GA 1        P3V3_STBY               
                                  2        IRQ_OOB_MGMT_RISER_ALERT_N
R2T30            RES_0402-33.2,1%,1/16W,CHIP,G2A 1        FM_CPU_ERR0_LVT3_K_N    
                                  2        FM_CPU_ERR0_LVT3_N      
R2T31            RES_0402-75,1.0%,1/16W,CHIP,G2A 1        H_CPU_ERR1_GTL_R_N      
                                  2        H_CPU_ERR1_GTL_N        
R2T32            RES_0402-0.0,5%,1/16W,CHIP,G21A 1        H_CPU0_ERR1_G_N         
                                  2        H_CPU_ERR1_GTL_R_N      
R2T33            RES_0402-33.2,1%,1/16W,CHIP,G2A 1        FM_CPU_ERR1_LVT3_K_N    
                                  2        FM_CPU_ERR1_LVT3_N      
R2T34            RES_0402-4.75K,1%,1/16W,CHIP,GA 1        P3V3_STBY               
                                  2        FM_BMC_PWRBTN_OUT_N     
R2T35            RES_0402-4.75K,1%,1/16W,CHIP,GA 1        P3V3_STBY               
                                  2        RST_BMC_SYSRST_BTN_OUT_N
R2T36            RES_0402-49.9,1%,1/16W,CHIP,G2A 1        PVCCIO_CPU0             
                                  2        P0V7_GTL2104_5_VREF     
R2T37            RES_0402-200.0,1%,1/16W,CHIP,GA 1        PVCCIO_CPU0             
                                  2        H_CPU_ERR2_G_R_N        
R2T38            RES_0402-33.2,1%,1/16W,CHIP,G2A 1        FM_CPU0_PROCHOT_LVT3_K_N
                                  2        FM_CPU0_PROCHOT_LVT3_N  
R2T39            RES_0402-100.0,1%,1/16W,CHIP,GA 1        P0V7_GTL2104_5_VREF     
                                  2        GND                     
R2T40            RES_0402-0.0,5%,1/16W,CHIP,G21A 1        H_CPU0_ERR2_G_N         
                                  2        H_CPU_ERR2_G_R_N        
R2T41            RES_0402-22.1,1.0%,1/16W,CHIP,A 1        IRQ_FORCE_NM_THROTTLE_N 
                                  2        FM_BMC_SYS_THROTTLE_R_N 
R2T42            RES_0402-22.1,1.0%,1/16W,CHIP,A 1        CLK_50M_CKMNG_OCP_R     
                                  2        CLK_50M_CKMNG_OCP       
R2T43            RES_0402-75,1.0%,1/16W,CHIP,G2A 1        H_CPU_ERR2_G_R_N        
                                  2        H_CPU_ERR2_GTL_N        
R2T44            RES_0402-0.0,5%,1/16W,CHIP,G21A 1        H_CPU1_ERR2_G_N         
                                  2        H_CPU_ERR2_G_R_N        
R2T45            RES_0402-22.1,1.0%,1/16W,CHIP,A 1        RMII_BMC_PCH_SPRNGVLLE_TXD1_R
                                  2        RMII_BMC_PCH_SPRNGVLLE_TXD1
R2T46            RES_0402-22.1,1.0%,1/16W,CHIP,A 1        CLK_50M_CKMNG_BMC_1_R   
                                  2        CLK_50M_CKMNG_BMC_1     
R2T47            RES_0402-33.2,1%,1/16W,CHIP,G2A 1        CLK_25M_CPLD_R          
                                  2        CLK_25M_CPLD            
R2T49            RES_0402-20.0,1%,1/16W,CHIP,G2A 1        SMB_BMC_PMBUS_STBY_LVC3_SDA_R
                                  2        SMB_BMC_PMBUS_STBY_LVC3_SDA
R2T50            RES_0402-1.00K,1%,1/16W,CHIP,GA 1        PD_GTL2104_4_DIR        
                                  2        GND                     
R2T52            RES_0603-2.2,1.0%,1/10W,CHIP,GA 1        P3V3_STBY_MNG           
                                  2        P3V3_STBY_MNG_RMII      
R2T53            RES_0402-665,1.0%,1/16W,CHIP,GA 1        P3V3_STBY               
                                  2        SMB_BMC_PMBUS_STBY_LVC3_SDA
R2T54            RES_0402-665,1.0%,1/16W,CHIP,GA 1        P3V3_STBY               
                                  2        SMB_BMC_PMBUS_STBY_LVC3_SCL
R2T55            RES_0402-20.0,1%,1/16W,CHIP,G2A 1        SMB_PMBUS_BMC_STBY_LVC3_SDA_R1
                                  2        SMB_BMC_PMBUS_STBY_LVC3_SDA
R2T56            RES_0402-20.0,1%,1/16W,CHIP,G2A 1        SMB_PMBUS_BMC_STBY_LVC3_SCL_R1
                                  2        SMB_BMC_PMBUS_STBY_LVC3_SCL
R2T57            RES_0402-0.0,5%,1/16W,EMPTY,G2A 1        H_CPU_ERR0_PCH_N        
                                  2        H_CPU_ERR0_GTL_R_N      
R2T58            RES_0402-0.0,5%,1/16W,EMPTY,G2A 1        H_CPU_ERR0_PCH_N        
                                  2        FM_CPU_ERR0_LVT3_K_N    
R2T59            RES_0402-0.0,5%,1/16W,EMPTY,G2A 1        H_CPU0_PROCHOT_G_N      
                                  2        H_CPU0_PROCHOT_G_PCH_N  
R2T60            RES_0402-0.0,5%,1/16W,CHIP,G21A 1        H_CPU0_PROCHOT_G_N      
                                  2        H_CPU0_PROCHOT_G_R_N    
R2T61            RES_0402-0.0,5%,1/16W,EMPTY,G2A 1        H_CPU_ERR1_PCH_N        
                                  2        H_CPU_ERR1_GTL_R_N      
R2T62            RES_0402-0.0,5%,1/16W,EMPTY,G2A 1        H_CPU_ERR1_PCH_N        
                                  2        FM_CPU_ERR1_LVT3_K_N    
R2T63            RES_0402-0.0,5%,1/16W,EMPTY,G2A 1        FM_CPU_ERR1_LVT3_N      
                                  2        FM_CPU_ERR1_PCH_N       
R2T64            RES_0402-0.0,5%,1/16W,CHIP,G21A 1        FM_CPU_ERR1_LVT3_N      
                                  2        FM_CPU_ERR1_LVT3_BMC_N  
R2T65            RES_0402-0.0,5%,1/16W,CHIP,G21A 1        FM_CPU_ERR0_LVT3_R_N    
                                  2        FM_CPU_ERR0_LVT3_K_N    
R2T66            RES_0402-0.0,5%,1/16W,CHIP,G21A 1        FM_CPU_ERR1_LVT3_R_N    
                                  2        FM_CPU_ERR1_LVT3_K_N    
R2T67            RES_0402-0.0,5%,1/16W,CHIP,G21A 1        FM_CPU0_PROCHOT_LVT3_R_N
                                  2        FM_CPU0_PROCHOT_LVT3_K_N
R2T68            RES_0402-0.0,5%,1/16W,CHIP,G21A 1        H_CPU1_PROCHOT_G_N      
                                  2        H_CPU1_PROCHOT_G_R_N    
R2T69            RES_0402-0.0,5%,1/16W,EMPTY,G2A 1        H_CPU1_PROCHOT_G_N      
                                  2        H_CPU1_PROCHOT_G_PCH_N  
R2T71            RES_0402-0.0,5%,1/16W,EMPTY,G2A 1        FM_CPU0_PROCHOT_LVT3_K_N
                                  2        H_CPU0_PROCHOT_G_PCH_N  
R2T72            RES_0402-150.0,1%,1/16W,CHIP,GA 1        PVCCIO_CPU0             
                                  2        H_CPU0_PROCHOT_G_N      
R2T73            RES_0402-150.0,1%,1/16W,CHIP,GA 1        PVCCIO_CPU1             
                                  2        H_CPU1_PROCHOT_G_N      
R2U1             RES_0402-20.0,1%,1/16W,CHIP,G2A 1        SMB_BMC_PMBUS_STBY_LVC3_SCL_R
                                  2        SMB_BMC_PMBUS_STBY_LVC3_SCL
R2U2             RES_0402-4.75K,1%,1/16W,CHIP,GA 1        P3V3_STBY               
                                  2        RST_PCH_SYSRST_BTN_OUT_N
R2U3             RES_0402-665,1.0%,1/16W,CHIP,GA 1        P3V3_STBY               
                                  2        SMB_LAN_STBY_LVC3_SCL   
R2U4             RES_0402-4.75K,1%,1/16W,CHIP,GA 1        P3V3_STBY               
                                  2        FM_CPLD_BMC_PWRDN_N     
R2U5             RES_0402-2.26K,1.0%,1/16W,CHIPA 1        P3V3_STBY               
                                  2        SMB_OCP_FRU_STBY_LVC3_SCL_R
R2U6             RES_0402-20.0,1%,1/16W,CHIP,G2A 1        SMB_LAN_STBY_LVC3_SCL_R1
                                  2        SMB_LAN_STBY_LVC3_SCL   
R2U7             RES_0402-20.0,1%,1/16W,CHIP,G2A 1        SMB_OCP_FRU_STBY_LVC3_SCL_R
                                  2        SMB_OCP_FRU_STBY_LVC3_SCL
R2U8             RES_0402-20.0,1%,1/16W,EMPTY,GA 1        SMB_LAN_STBY_LVC3_SCL   
                                  2        SMB_OCP_FRU_STBY_LVC3_SCL
R2U9             RES_0402-20.0,1%,1/16W,CHIP,G2A 1        SMB_LAN_STBY_LVC3_SDA_R1
                                  2        SMB_LAN_STBY_LVC3_SDA   
R2U10            RES_0402-20.0,1%,1/16W,CHIP,G2A 1        SMB_OCP_FRU_STBY_LVC3_SDA_R
                                  2        SMB_OCP_FRU_STBY_LVC3_SDA
R2U11            RES_0402-665,1.0%,1/16W,CHIP,GA 1        P3V3_STBY               
                                  2        SMB_LAN_STBY_LVC3_SDA   
R2U12            RES_0402-20.0,1%,1/16W,EMPTY,GA 1        SMB_LAN_STBY_LVC3_SDA   
                                  2        SMB_OCP_FRU_STBY_LVC3_SDA
R2U13            RES_0402-2.26K,1.0%,1/16W,CHIPA 1        P3V3_STBY               
                                  2        SMB_OCP_FRU_STBY_LVC3_SDA_R
R2U14            RES_0402-0.0,5%,1/16W,EMPTY,G2A 1        P3E_CPU0_PE1_SS_R_RXP<0>
                                  2        P3E_CPU0_PE1_SS_RXP<0>  
R2U15            RES_0402-0.0,5%,1/16W,EMPTY,G2A 1        P3E_CPU0_PE1_SS_R_RXN<0>
                                  2        P3E_CPU0_PE1_SS_RXN<0>  
R2U16            RES_0402-0.0,5%,1/16W,EMPTY,G2A 1        P3E_CPU0_PE1_SS_R_RXP<1>
                                  2        P3E_CPU0_PE1_SS_RXP<1>  
R2U17            RES_0402-0.0,5%,1/16W,EMPTY,G2A 1        P3E_CPU0_PE1_SS_R_RXN<1>
                                  2        P3E_CPU0_PE1_SS_RXN<1>  
R2U18            RES_0402-0.0,5%,1/16W,EMPTY,G2A 1        P3E_CPU0_PE1_SS_R_RXP<2>
                                  2        P3E_CPU0_PE1_SS_RXP<2>  
R2U19            RES_0402-0.0,5%,1/16W,EMPTY,G2A 1        P3E_CPU0_PE1_SS_R_RXN<2>
                                  2        P3E_CPU0_PE1_SS_RXN<2>  
R2U20            RES_0402-0.0,5%,1/16W,EMPTY,G2A 1        P3E_CPU0_PE1_SS_R_RXP<3>
                                  2        P3E_CPU0_PE1_SS_RXP<3>  
R2U21            RES_0402-0.0,5%,1/16W,EMPTY,G2A 1        P3E_CPU0_PE1_SS_R_RXN<3>
                                  2        P3E_CPU0_PE1_SS_RXN<3>  
R2U22            RES_0402-0.0,5%,1/16W,EMPTY,G2A 1        P3E_CPU0_PE1_SS_R_RXP<4>
                                  2        P3E_CPU0_PE1_SS_RXP<4>  
R2U23            RES_0402-0.0,5%,1/16W,EMPTY,G2A 1        P3E_CPU0_PE1_SS_R_RXN<4>
                                  2        P3E_CPU0_PE1_SS_RXN<4>  
R2U24            RES_0402-0.0,5%,1/16W,EMPTY,G2A 1        P3E_CPU0_PE1_SS_R_RXP<5>
                                  2        P3E_CPU0_PE1_SS_RXP<5>  
R2U25            RES_0402-0.0,5%,1/16W,EMPTY,G2A 1        P3E_CPU0_PE1_SS_R_RXN<5>
                                  2        P3E_CPU0_PE1_SS_RXN<5>  
R2U26            RES_0402-0.0,5%,1/16W,EMPTY,G2A 1        P3E_CPU0_PE1_SS_R_RXP<6>
                                  2        P3E_CPU0_PE1_SS_RXP<6>  
R2U27            RES_0402-0.0,5%,1/16W,EMPTY,G2A 1        P3E_CPU0_PE1_SS_R_RXN<6>
                                  2        P3E_CPU0_PE1_SS_RXN<6>  
R2U28            RES_0402-0.0,5%,1/16W,EMPTY,G2A 1        P3E_CPU0_PE1_SS_R_RXP<7>
                                  2        P3E_CPU0_PE1_SS_RXP<7>  
R2U29            RES_0402-0.0,5%,1/16W,EMPTY,G2A 1        P3E_CPU0_PE1_SS_R_RXN<7>
                                  2        P3E_CPU0_PE1_SS_RXN<7>  
R2U30            RES_0402-4.75K,1%,1/16W,CHIP,GA 1        P3V3_STBY               
                                  2        FM_UV_ADR_TRIGGER_EN    
R2U31            RES_0402-20.0,1%,1/16W,CHIP,G2A 1        SMB_SLOTX24_BMC_STBY_LVC3_SDA
                                  2        SMB_SLOTX24_STBY_LVC3_SDA_R2
R2U32            RES_0402-20.0,1%,1/16W,CHIP,G2A 1        SMB_SLOTX24_BMC_STBY_LVC3_SCL
                                  2        SMB_SLOTX24_STBY_LVC3_SCL_R2
R2U33            RES_0402-20.0,1%,1/16W,CHIP,G2A 1        SMB_HOST_STBY_LVC3_SDA_R
                                  2        SMB_HOST_STBY_LVC3_SDA  
R2U34            RES_0402-20.0,1%,1/16W,CHIP,G2A 1        SMB_HOST_STBY_LVC3_SCL_R
                                  2        SMB_HOST_STBY_LVC3_SCL  
R2U35            RES_0402-20.0,1%,1/16W,EMPTY,GA 1        SMB_SLOTX24_PCH_STBY_LVC3_SDA
                                  2        SMB_SLOTX24_STBY_LVC3_SDA_R2
R2U36            RES_0402-20.0,1%,1/16W,EMPTY,GA 1        SMB_SLOTX24_PCH_STBY_LVC3_SCL
                                  2        SMB_SLOTX24_STBY_LVC3_SCL_R2
R2U37            RES_0402-0.0,5%,1/16W,CHIP,G21A 1        RST_PCIE_RISER1_PERST_N 
                                  2        RST_PCIE_RISER1_PERST_R_N
R2U38            RES_0402-665,1.0%,1/16W,CHIP,GA 1        P3V3_STBY               
                                  2        SMB_SENSOR_STBY_LVC3_SCL
R2U39            RES_0402-665,1.0%,1/16W,CHIP,GA 1        P3V3_STBY               
                                  2        SMB_SENSOR_STBY_LVC3_SDA
R2U40            RES_0402-150.0,1%,1/16W,CHIP,GA 1        PVCCIO_CPU0             
                                  2        H_CPU0_MEMABC_MEMHOT_G_N
R2U41            RES_0402-150.0,1%,1/16W,CHIP,GA 1        PVCCIO_CPU0             
                                  2        H_CPU0_MEMDEF_MEMHOT_G_N
R2U42            RES_0402-221,1.0%,1/16W,CHIP,GA 1        FAN_PWM_OUT_SYS0_BUF    
                                  2        FAN_PWM_OUT_SYS0_R      
R2U43            RES_0402-1.00K,1%,1/16W,CHIP,GA 1        P3V_BAT_SOURCE          
                                  2        A_P3V_BAT_R             
R2U44            RES_0402-221,1.0%,1/16W,CHIP,GA 1        FAN_PWM_OUT_SYS1_BUF    
                                  2        FAN_PWM_OUT_SYS1_R      
R2U45            RES_0402-0.0,5%,1/16W,EMPTY,G2A 1        H_CPU1_MEMKLM_MEMHOT_LVT3_N
                                  2        H_CPU1_MEMKLM_MEMHOT_PCH_N
R2U46            RES_0402-0.0,5%,1/16W,CHIP,G21A 1        H_CPU1_MEMKLM_MEMHOT_LVT3_N
                                  2        H_CPU1_MEMKLM_MEMHOT_LVT3_BMC_N
R2U47            RES_0402-0.0,5%,1/16W,CHIP,G21A 1        H_CPU0_MEMABC_MEMHOT_LVT3_N
                                  2        H_CPU0_MEMABC_MEMHOT_LVT3_BMC_N
R2U48            RES_0402-4.75K,1%,1/16W,CHIP,GA 1        P3V3_STBY               
                                  2        FM_SLT_CFG2_R           
R2U49            RES_0402-0.0,5%,1/16W,EMPTY,G2A 1        H_CPU0_MEMABC_MEMHOT_G_PCH_N
                                  2        H_CPU0_MEMABC_MEMHOT_LVT3_K_N
R2U50            RES_0402-0.0,5%,1/16W,EMPTY,G2A 1        FM_SLT_CFG2_R           
                                  2        FM_PWRBRK_SLOT_N        
R2U51            RES_0402-0.0,5%,1/16W,EMPTY,G2A 1        H_CPU0_MEMABC_MEMHOT_G_PCH_N
                                  2        H_CPU0_MEMABC_MEMHOT_G_N
R3B1             RES_0402-221,1.0%,1/16W,CHIP,GA 1        SVID_ALERT0_CPU1_N      
                                  2        SVID_ALERT0_CPU1_R_N    
R3B2             RES_0402-49.9,1%,1/16W,CHIP,G2A 1        SVID_ALERT0_CPU1_R_N    
                                  2        PVCCIO_CPU1             
R3B3             RES_0402-0.0,5%,1/16W,CHIP,G21A 1        SVID_DIO0_CPU1          
                                  2        SVID_DIO0_CPU1_R        
R3B4             RES_0402-100.0,1%,1/16W,CHIP,GA 1        SVID_DIO0_CPU1_R        
                                  2        PVCCIO_CPU1             
R3B5             RES_0402-0.0,5%,1/16W,CHIP,G21A 1        SVID_CLK0_CPU1          
                                  2        SVID_CLK0_CPU1_R        
R3D1             RES_0402-90.9,1%,1/16W,CHIP,G2A 1        A_CPU1_KLM_RCOMP0       
                                  2        GND                     
R3D2             RES_0402-90.9,1%,1/16W,CHIP,G2A 1        A_CPU1_KLM_RCOMP1       
                                  2        GND                     
R3D3             RES_0402-100.0,1%,1/16W,CHIP,GA 1        A_CPU1_KLM_RCOMP2       
                                  2        GND                     
R3D4             RES_0402-49.9,1%,1/16W,CHIP,G2A 1        A_CPU1_MCP01_RBIAS      
                                  2        GND                     
R3D9             RES_0402-49.9,1%,1/16W,CHIP,G2A 1        PD_CPU1_TEST12          
                                  2        GND                     
R3D12            RES_0402-240,1.0%,1/16W,CHIP,GA 1        GND                     
                                  2        PD_CPU1_TXT_PLTEN       
R3D13            RES_0402-240,1.0%,1/16W,EMPTY,A 1        GND                     
                                  2        PD_CPU1_BIST_ENABLE     
R3D14            RES_0603-2.2,1.0%,1/10W,CHIP,GA 1        P3V3_DB1200             
                                  2        P3V3_DB1200_A           
R3D15            RES_0402-49.9,1%,1/16W,CHIP,G2A 1        PVCCIO_CPU1             
                                  2        PWRGD_CPU1_G            
R3D16            RES_0402-240,1.0%,1/16W,EMPTY,A 1        PVCCIO_CPU1             
                                  2        H_CPU1_BMCINIT          
R3D17            RES_0402-240,1.0%,1/16W,EMPTY,A 1        PVCCIO_CPU1             
                                  2        PU_CPU1_SOCKET_ID_1     
R3D18            RES_0402-0.0,5%,1/16W,CHIP,G21A 1        H_CPU0_FAST_WAKE_N      
                                  2        H_CPU1_FAST_WAKE_N      
R3D19            RES_0402-49.9,1%,1/16W,CHIP,G2A 1        A_CPU1_UPI01_RBIAS      
                                  2        GND                     
R3D20            RES_0402-49.9,1%,1/16W,CHIP,G2A 1        PVCCIO_CPU1             
                                  2        RST_CPU1_G_N            
R3D21            RES_0402-64.9,1.0%,1/16W,CHIP,A 1        PVDDQ_GHJ               
                                  2        PWRGD_CPU1_DRAMPWROK_GHJ_G
R3D22            RES_0402-240,1.0%,1/16W,EMPTY,A 1        PVCCIO_CPU1             
                                  2        PU_CPU1_FRMAGENT        
R3D23            RES_0402-240,1.0%,1/16W,EMPTY,A 1        PVCCIO_CPU1             
                                  2        PU_CPU1_TXT_AGENT       
R3D24            RES_0402-240,1.0%,1/16W,CHIP,GA 1        PVCCIO_CPU1             
                                  2        PU_CPU1_SOCKET_ID_0     
R3D25            RES_0402-240,1.0%,1/16W,EMPTY,A 1        PVCCIO_CPU1             
                                  2        PU_CPU1_EAR_N           
R3D26            RES_0402-240,1.0%,1/16W,EMPTY,A 1        PVCCIO_CPU1             
                                  2        PU_CPU1_SAFE_MODE_BOOT  
R3D27            RES_0402-249,0.1%,1/16W,CHIP,GA 1        VSENSE_PMAX_CPU1        
                                  2        GND                     
R3D28            RES_0402-100.0,1%,1/16W,CHIP,GA 1        VSENSE_PVCCIO_CPU1_AVSN 
                                  2        GND                     
R3D31            RES_0402-0.0,5%,1/16W,EMPTY,G2A 1        FM_CPU_BMC_INIT         
                                  2        H_CPU1_BMCINIT          
R3D32            RES_0402-10.0,1%,1/16W,EMPTY,GA 1        PVCCIO_CPU1             
                                  2        VSENSE_PMAX_CPU1        
R3E1             RES_0402-100.0,1%,1/16W,CHIP,GA 1        VSENSE_PVCCIO_CPU1_AVSP 
                                  2        PVCCIO_CPU1             
R3F1             RES_0402-0.0,5%,1/16W,EMPTY,G2A 1        CLK_322M_156M_CPU1_OSC_VRM_DN
                                  2        CLK_156M_OSC_CPU1_HFI_DN
R3F2             RES_0402-0.0,5%,1/16W,CHIP,G21A 1        CLK_156M_OSC_BRD_CPU1_DN
                                  2        CLK_156M_OSC_CPU1_HFI_DN
R3F3             RES_0402-0.0,5%,1/16W,EMPTY,G2A 1        CLK_322M_156M_CPU1_OSC_VRM_DP
                                  2        CLK_156M_OSC_CPU1_HFI_DP
R3F4             RES_0402-0.0,5%,1/16W,CHIP,G21A 1        CLK_156M_OSC_BRD_CPU1_DP
                                  2        CLK_156M_OSC_CPU1_HFI_DP
R3F5             RES_0402-0.0,5%,1/16W,EMPTY,G2A 1        CLK_322M_156M_CPU1_OSC_VRM_DN
                                  2        CLK_322M_OSC_CPU1_RC_DN 
R3F6             RES_0402-0.0,5%,1/16W,EMPTY,G2A 1        CLK_322M_156M_CPU1_OSC_VRM_DP
                                  2        CLK_322M_OSC_CPU1_RC_DP 
R3L1             RES_0402-1.0,1%,1/16W,CHIP,G21A 1        VR_PVNN_PCH_PH1_VCIN    
                                  2        P5V_STBY                
R3L4             RES_0402-1.0,1%,1/16W,CHIP,G21A 1        VR_P1V05_PCH_STBY_PH1_VCIN
                                  2        P5V_STBY                
R3L6             RES_0402-1.0,1%,1/16W,CHIP,G21A 1        VR_PVDDQ_DEF_PH1_VCIN   
                                  2        P5V_STBY                
R3L8             RES_0402-1.0,1%,1/16W,CHIP,G21A 1        VR_PVDDQ_DEF_PH2_VCIN   
                                  2        P5V_STBY                
R3L9             RES_0402-0.0,5%,1/16W,CHIP,G21A 1        VR_PVDDQ_DEF_VD12       
                                  2        VR_PVDDQ_DEF_AIREF1     
R3L10            RES_0402-0.0,5%,1/16W,CHIP,G21A 1        VR_PVDDQ_DEF_VD12       
                                  2        VR_PVDDQ_DEF_AIREF2     
R3L11            RES_0402-100.0,1%,1/16W,EMPTY,A 1        PVCCIO_CPU0             
                                  2        SVID_DIO1_CPU0_R        
R3L12            RES_0402-100.0K,1%,1/16W,CHIP,B 1        VR_FET_SW_P12V_STBY_PVDDQ_DEF
                                  2        VR_PVDDQ_DEF_VINSEN     
R3L13            RES_0402-49.9,1%,1/16W,CHIP,G2A 1        PVCCIO_CPU0             
                                  2        SVID_CLK1_CPU0_R        
R3L14            RES_0402-68.1K,1%,1/16W,EMPTY,A 1        VR_P1V05_PCH_STBY_OCSET 
                                  2        GND                     
R3L15            RES_0402-68.1K,1%,1/16W,EMPTY,A 1        VR_PVNN_PCH_STBY_OCSET  
                                  2        GND                     
R3M1             RES_0402-0.0,5%,1/16W,CHIP,G21A 1        P3V3_STBY               
                                  2        VR_PVDDQ_DEF_VDD        
R3M3             RES_0402-22.1,1.0%,1/16W,CHIP,A 1        PWRGD_PVDDQ_DEF_R       
                                  2        PWRGD_PVDDQ_DEF         
R3M5             RES_0402-100.0K,1%,1/16W,EMPTYA 1        P3V3_STBY               
                                  2        VR_PVDDQ_DEF_VREN       
R3M6             RES_0402-0.0,5%,1/16W,CHIP,G21A 1        FM_PVDDQ_DEF_EN         
                                  2        VR_PVDDQ_DEF_VREN       
R3M8             RES_0402-100.0K,1%,1/16W,CHIP,A 1        P2E_SSB_BMC_RX_C_DP     
                                  2        GND                     
R3M9             RES_0402-100.0K,1%,1/16W,CHIP,A 1        P2E_SSB_BMC_RX_C_DN     
                                  2        GND                     
R3M10            RES_0402-1.00K,1%,1/16W,CHIP,GA 1        XDP_PCH_CPU_TCK0        
                                  2        GND                     
R3M11            RES_0402-100.0,1%,1/16W,CHIP,GA 1        A_PCIE_RCOMP_P          
                                  2        A_PCIE_RCOMP_N          
R3M12            RES_0402-100.0,1%,1/16W,CHIP,GA 1        A_PCIEUP_RCOMP_P        
                                  2        A_PCIEUP_RCOMP_N        
R3N1             RES_0402-169,1.0%,1/16W,CHIP,GA 1        A_PCH_XCLK_BIASREF      
                                  2        GND                     
R3N2             RES_0402-4.75K,1%,1/16W,EMPTY,A 1        P3V3_STBY               
                                  2        FM_FLASH_DESC_OVERRIDE  
R3N3             RES_0402-2.0K,1%,1/16W,CHIP,G2A 1        GND                     
                                  2        PWRGD_PCH_PWROK         
R3N4             RES_0402-20.0K,1%,1/16W,CHIP,GA 1        P3V3_RTC_STBY           
                                  2        RST_SRTCRST_N           
R3N7             RES_0402-1.0,1%,1/16W,CHIP,G21A 1        VR_PVCCIO_CPU0_PH1_VCIN 
                                  2        P5V_STBY                
R3N9             RES_0402-10.0,1%,1/16W,CHIP,G2A 1        H_PM_SYNC1_GTL_R        
                                  2        H_PM_SYNC_GTL           
R3N10            RES_0402-10.0K,1%,1/16W,CHIP,GA 1        P3V3_STBY               
                                  2        FM_INTRUDER_HDR_PCH_N   
R3N11            RES_0402-4.75K,1%,1/16W,CHIP,GA 1        P3V3_STBY               
                                  2        FM_MP_PS_REDUNDANT_LOST_N
R3N12            RES_0402-4.75K,1%,1/16W,CHIP,GA 1        P3V3_STBY               
                                  2        FM_MP_PS_FAIL_N         
R3N13            RES_0402-4.75K,1%,1/16W,CHIP,GA 1        P3V3_STBY               
                                  2        IRQ_LVC3_WAKE_N         
R3N14            RES_0402-49.9,1%,1/16W,EMPTY,GA 1        H_PM_SYNC_GTL           
                                  2        GND                     
R3N15            RES_0402-1.00K,1%,1/16W,CHIP,GA 1        P1V05_PCH_STBY          
                                  2        FM_PRSNT_2_4_N          
R3N16            RES_0402-1.00K,1%,1/16W,CHIP,GA 1        P1V05_PCH_STBY          
                                  2        FM_PRSNT_2_5_N          
R3N17            RES_0402-1.00K,1%,1/16W,EMPTY,A 1        P3V3_STBY               
                                  2        SPI_PCH_IO3             
R3N19            RES_0402-10.0,1%,1/16W,CHIP,G2A 1        VSENSE_PVCCIO_CPU0_AVSP 
                                  2        VR_PVCCIO_CPU0_AVSP     
R3N20            RES_0402-100.0,1%,1/16W,CHIP,GA 1        VSENSE_PVCCIO_CPU0_AVSN 
                                  2        GND                     
R3N21            RES_0402-100.0,1%,1/16W,CHIP,GA 1        VSENSE_PVCCIO_CPU0_AVSP 
                                  2        PVCCIO_CPU0             
R3N22            RES_0402-4.02K,1%,1/16W,CHIP,GA 1        VR_PVCCIO_CPU0_XADDR2   
                                  2        GND                     
R3N23            RES_0402-2.26K,1.0%,1/16W,EMPTA 1        P3V3_STBY               
                                  2        PU_VR_PVCCIO_CPU0_FAULT1
R3N24            RES_0402-33.2,1%,1/16W,CHIP,G2A 1        LPC_LAD2_IO2            
                                  2        LPC_LAD2_IO2_R          
R3N25            RES_0402-33.2,1%,1/16W,CHIP,G2A 1        LPC_LAD3_IO3            
                                  2        LPC_LAD3_IO3_R          
R3N26            RES_0402-33.2,1%,1/16W,CHIP,G2A 1        LPC_LAD0_IO0            
                                  2        LPC_LAD0_IO0_R          
R3N27            RES_0402-33.2,1%,1/16W,CHIP,G2A 1        LPC_LFRAME_N_CS0_N      
                                  2        LPC_LFRAME_N_CS0_R_N    
R3N28            RES_0402-33.2,1%,1/16W,CHIP,G2A 1        LPC_LAD1_IO1            
                                  2        LPC_LAD1_IO1_R          
R3N29            RES_0402-16K,1.0%,1/16W,CHIP,GA 1        VR_PVCCIOMCP_CPU0_XADDR1
                                  2        GND                     
R3N30            RES_0402-0.0,5%,1/16W,EMPTY,G2A 1        H_CPU0_MEMABC_MEMHOT_LVT3_N
                                  2        H_CPU0_MEMABC_MEMHOT_PCH_N
R3N31            RES_0402-3.16K,1%,1/16W,CHIP,GA 1        VR_PVCCIO_CPU0_XADDR1   
                                  2        GND                     
R3P1             RES_0402-0.0,5%,1/16W,CHIP,G21A 1        SVID_ALERT_PVCCIO_CPU0  
                                  2        SVID_ALERT0_CPU0_R_N    
R3P2             RES_0402-0.0,5%,1/16W,CHIP,G21A 1        RMII_BMC_PCH_SPRNGVLLE_CRSDV
                                  2        RMII_BMC_PCH_SPRNGVLLE_CRSDV_R1
R3P3             RES_0402-0.0,5%,1/16W,CHIP,G21A 1        RMII_SPRNGVLLE_BMC_PCH_RXD0
                                  2        RMII_SPRNGVLLE_BMC_PCH_RXD0_R1
R3P5             RES_0402-1.00K,1%,1/16W,CHIP,GA 1        P1V05_PCH_STBY          
                                  2        FM_PRSNT_2_2_N          
R3P6             RES_0402-1.00K,1%,1/16W,CHIP,GA 1        P1V05_PCH_STBY          
                                  2        FM_PRSNT_2_3_N          
R3P7             RES_0402-1.00K,1%,1/16W,CHIP,GA 1        P1V05_PCH_STBY          
                                  2        FM_PRSNT_2_1_N          
R3P8             RES_0402-1.00K,1%,1/16W,CHIP,GA 1        P1V05_PCH_STBY          
                                  2        FM_PRSNT_2_6_N          
R3P11            RES_0402-0.0,5%,1/16W,CHIP,G21A 1        SVID_DIO0_CPU0_R        
                                  2        SVID_VDIO_PVCCIO_CPU0   
R3P12            RES_0402-100.0K,1%,1/16W,CHIP,B 1        VR_FET_SW_P12V_STBY_PVCCIO_CPU0
                                  2        VR_PVCCIO_CPU0_VINSEN   
R3P13            RES_0402-100.0,1%,1/16W,EMPTY,A 1        PVCCIO_CPU0             
                                  2        SVID_DIO0_CPU0_R        
R3P15            RES_0402-150.0,1%,1/16W,CHIP,GA 1        SVID_CLK0_CPU0_R        
                                  2        SVID_CLK_PVCCIO_CPU0    
R3P16            RES_0402-1.5K,1%,1/16W,CHIP,G2A 1        VR_PVCCIO_CPU0_VINSEN   
                                  2        GND                     
R3P17            RES_0402-49.9,1%,1/16W,EMPTY,GA 1        PVCCIO_CPU0             
                                  2        SVID_CLK0_CPU0_R        
R3P18            RES_0402-1.00K,1%,1/16W,CHIP,GA 1        P3V3_STBY               
                                  2        IRQ_PVCCIO_CPU0_VRHOT_N 
R3P20            RES_0402-22.1,1.0%,1/16W,CHIP,A 1        PWRGD_PVCCIO_CPU0_R     
                                  2        PWRGD_PVCCIO_CPU0       
R3P21            RES_0402-100.0K,1%,1/16W,EMPTYA 1        P3V3_STBY               
                                  2        VR_PVCCIO_CPU0_EN       
R3P22            RES_0402-0.0,5%,1/16W,CHIP,G21A 1        P3V3_STBY               
                                  2        VR_PVCCIO_CPU0_VDD      
R3P23            RES_0402-20.0,1%,1/16W,CHIP,G2A 1        SMB_VR_STBY_LVC3_SDA    
                                  2        SMB_VR_SDA_PVCCIO_CPU0  
R3P24            RES_0402-20.0,1%,1/16W,CHIP,G2A 1        SMB_VR_STBY_LVC3_SCL    
                                  2        SMB_VR_SCL_PVCCIO_CPU0  
R3P25            RES_0402-1.00K,1%,1/16W,CHIP,GA 1        P3V3_STBY               
                                  2        PWRGD_PVCCIO_CPU0_R     
R3P26            RES_0402-0.0,5%,1/16W,CHIP,G21A 1        FM_PVCCIO_CPU0_EN       
                                  2        VR_PVCCIO_CPU0_EN       
R3P29            RES_0402-64.9,1.0%,1/16W,CHIP,A 1        PVDDQ_DEF               
                                  2        PWRGD_CPU0_DRAMPWROK_DEF_G
R3P32            RES_0402-1.00K,1%,1/16W,CHIP,GA 1        GND                     
                                  2        PD_GTL2014_1_VREF       
R3P34            RES_0402-0.0,5%,1/16W,CHIP,G21A 1        RST_CPU0_LVC3_R1_N      
                                  2        RST_CPU0_LVC3_N         
R3P35            RES_0402-0.0,5%,1/16W,CHIP,G21A 1        RST_CPU1_LVC3_R1_N      
                                  2        RST_CPU1_LVC3_N         
R3P36            RES_0402-1.00K,1%,1/16W,CHIP,GA 1        P3V3_STBY               
                                  2        PU_GTL2014_1_DIR        
R3P38            RES_0402-64.9,1.0%,1/16W,CHIP,A 1        PVDDQ_ABC               
                                  2        PWRGD_CPU0_DRAMPWROK_ABC_G
R3P41            RES_0402-75,1.0%,1/16W,CHIP,G2A 1        PVCCIO_CPU1             
                                  2        H_CPU1_THERMTRIP_G_N    
R3P42            RES_0402-33.2,1%,1/16W,CHIP,G2A 1        FM_CPU1_THERMTRIP_LVT3_R_N
                                  2        FM_CPU1_THERMTRIP_LVT3_N
R3P43            RES_0402-33.2,1%,1/16W,CHIP,G2A 1        FM_CPU_CATERR_LVT3_R2_N 
                                  2        FM_CPU_CATERR_LVT3_N    
R3P44            RES_0402-4.75K,1%,1/16W,CHIP,GA 1        P3V3_STBY               
                                  2        PWRGD_DSW_PWROK         
R3P45            RES_0402-49.9,1%,1/16W,CHIP,G2A 1        PVCCIO_CPU0             
                                  2        P0V7_GTL2104_VREF_1     
R3P46            RES_0402-33.2,1%,1/16W,CHIP,G2A 1        FM_CPU1_FIVR_FAULT_R_LVT3
                                  2        FM_CPU1_FIVR_FAULT_LVT3 
R3P48            RES_0402-90.9K,1%,1/16W,CHIP,GA 1        P12V_STBY               
                                  2        VSENSE_P12V_ADM1085     
R3P49            RES_0402-100.0,1%,1/16W,CHIP,GA 1        P0V7_GTL2104_VREF_1     
                                  2        GND                     
R3P50            RES_0402-10.0K,1%,1/16W,EMPTY,A 1        P3V3_STBY               
                                  2        PWRGD_P3V3_STBY         
R3P51            RES_0402-6.34K,1%,1/16W,CHIP,GA 1        VSENSE_P12V_ADM1085     
                                  2        GND                     
R3P53            RES_0402-4.75K,1%,1/16W,CHIP,GA 1        P1V05_PCH_STBY          
                                  2        FM_OCP_MEZZC_PRES_N     
R3P54            RES_0402-3.32K,1%,1/16W,EMPTY,A 1        P3V3_STBY               
                                  2        FM_CPU0_SM_WP           
R3P56            RES_0402-1.00K,1%,1/16W,CHIP,GA 1        FM_CPU0_SM_WP           
                                  2        GND                     
R3P57            RES_0402-0.0,5%,1/16W,CHIP,G21A 1        VR_PVCCIO_CPU0_VD12     
                                  2        VR_PVCCIO_CPU0_AIREF1   
R3P58            RES_0402-0.0,5%,1/16W,CHIP,G21A 1        H_CPU1_CATERR_G_N       
                                  2        H_CPU_CATERR_G_N        
R3P59            RES_0402-0.0,5%,1/16W,CHIP,G21A 1        H_CPU0_CATERR_G_N       
                                  2        H_CPU_CATERR_G_N        
R3P60            RES_0402-240,1.0%,1/16W,CHIP,GA 1        PVCCIO_CPU0             
                                  2        SMB_DDR_DEF_SCL_G       
R3P61            RES_0402-2.26K,1.0%,1/16W,CHIPA 1        P3V3_STBY               
                                  2        FM_MB_SLOT_ID2          
R3P62            RES_0402-4.75K,1%,1/16W,EMPTY,A 1        P3V3_STBY               
                                  2        FM_FLASH_ATTACH_CFG_STRAP
R3P63            RES_0402-0.0,5%,1/16W,EMPTY,G2A 1        H_CPU1_MEMGHJ_MEMHOT_LVT3_N
                                  2        H_CPU1_MEMGHJ_MEMHOT_PCH_N
R3P64            RES_0402-1.00K,1%,1/16W,EMPTY,A 1        FM_FLASH_ATTACH_CFG_STRAP
                                  2        GND                     
R3R1             RES_0402-1.00K,1%,1/16W,CHIP,GA 1        PD_GTL2104_DIR_1        
                                  2        GND                     
R3R2             RES_0402-1.00K,1%,1/16W,CHIP,GA 1        H_CPU1_FIVR_FAULT_G     
                                  2        GND                     
R3R3             RES_0402-33.2,1%,1/16W,CHIP,G2A 1        PWRGD_CPUPWRGD_R1       
                                  2        PWRGD_CPUPWRGD          
R3R4             RES_0402-4.75K,1%,1/16W,CHIP,GA 1        P3V3                    
                                  2        H_CPU0_MEMDEF_MEMHOT    
R3R5             RES_0402-665,1.0%,1/16W,CHIP,GA 1        PVPP_DEF                
                                  2        SMB_DDR_DEF_VPP_SCL_R   
R3R7             RES_0402-10.0,1%,1/16W,CHIP,G2A 1        SMB_DDR_DEF_SCL_G_R     
                                  2        SMB_DDR_DEF_SCL_G       
R3R8             RES_0402-20.0,1%,1/16W,CHIP,G2A 1        SMB_DDR_DEF_VPP_SCL_R   
                                  2        SMB_DDR_DEF_VPP_SCL     
R3R9             RES_0402-20.0,1%,1/16W,CHIP,G2A 1        SMB_DDR_DEF_VPP_SDA_R   
                                  2        SMB_DDR_DEF_VPP_SDA     
R3R10            RES_0402-4.75K,1%,1/16W,CHIP,GA 1        P3V3                    
                                  2        H_CPU1_MEMGHJ_MEMHOT    
R3R11            RES_0402-10.0K,1%,1/16W,EMPTY,A 1        FM_JTAG_PLD_EN_DEBUG    
                                  2        GND                     
R3R12            RES_0402-665,1.0%,1/16W,CHIP,GA 1        PVPP_DEF                
                                  2        SMB_DDR_DEF_VPP_SDA_R   
R3R13            RES_0402-240,1.0%,1/16W,CHIP,GA 1        PVCCIO_CPU0             
                                  2        SMB_DDR_DEF_SDA_G       
R3R14            RES_0402-10.0,1%,1/16W,CHIP,G2A 1        SMB_DDR_DEF_SDA_G_R     
                                  2        SMB_DDR_DEF_SDA_G       
R3R15            RES_0402-1.00K,1%,1/16W,CHIP,GA 1        P3V3_STBY               
                                  2        FM_JTAG_PLD_EN_DEBUG    
R3R16            RES_0402-4.75K,1%,1/16W,CHIP,GA 1        PVPP_ABC                
                                  2        RST_CD_CPU0_POR_N       
R3T1             RES_0402-33.2,1%,1/16W,CHIP,G2A 1        SPI_BIOS_SOCKET_IO3     
                                  2        PU_BIOS_SPI_HOLD1_N     
R3T2             RES_0402-33.2,1%,1/16W,CHIP,G2A 1        SPI_SWITCH_MISO         
                                  2        SPI_MISO_R1             
R3T3             RES_0402-4.75K,1%,1/16W,EMPTY,A 1        P3V3_STBY               
                                  2        PU_SPI1_RST             
R3T4             RES_0402-10.0K,1%,1/16W,CHIP,GA 1        P3V3_STBY               
                                  2        PU_BIOS_SPI_HOLD1_N     
R3T5             RES_0402-4.75K,1%,1/16W,CHIP,GA 1        P3V3_STBY               
                                  2        SPI_CS0_SECONDARY_R_N   
R3T9             RES_0402-10.0K,1%,1/16W,EMPTY,A 1        PU_BIOS_SPI_WP1_N       
                                  2        GND                     
R3T10            RES_0402-33.2,1%,1/16W,CHIP,G2A 1        SPI_SWITCH_MOSI         
                                  2        SPI_SWITCH_MOSI_R1      
R3T11            RES_0402-49.9,1%,1/16W,EMPTY,GA 1        PVCCIO_CPU0             
                                  2        SVID_CLK1_CPU0_R        
R3T12            RES_0402-10.0K,1%,1/16W,CHIP,GA 1        P3V3_STBY               
                                  2        PU_BIOS_SPI_WP1_N       
R3T13            RES_0402-0.0,5%,1/16W,CHIP,G21A 1        P3V3_STBY               
                                  2        VR_PVDDQ_ABC_VDD        
R3T14            RES_0402-10.0K,1%,1/16W,CHIP,GA 1        FM_BIOS_USB_RECOVERY    
                                  2        GND                     
R3U1             RES_0402-33.2,1%,1/16W,CHIP,G2A 1        SPI_BIOS_SOCKET_IO2     
                                  2        PU_BIOS_SPI_WP1_N       
R3U2             RES_0402-100.0,1%,1/16W,CHIP,GA 1        PVCCIO_CPU0             
                                  2        SVID_DIO1_CPU0_R        
R3U3             RES_0402-0.0,5%,1/16W,CHIP,G21A 1        VR_PVDDQ_ABC_VD12       
                                  2        VR_PVDDQ_ABC_AIREF2     
R3U4             RES_0603-120.0,1%,1/10W,CHIP,GA 1        PVDDQ_ABC               
                                  2        GND                     
R3U6             RES_0402-1.0,1%,1/16W,CHIP,G21A 1        VR_PVDDQ_ABC_PH1_VCIN   
                                  2        P5V_STBY                
R3U9             RES_0402-1.0,1%,1/16W,CHIP,G21A 1        VR_PVDDQ_ABC_PH2_VCIN   
                                  2        P5V_STBY                
R3U10            RES_0402-0.0,5%,1/16W,CHIP,G21A 1        VR_PVDDQ_ABC_VD12       
                                  2        VR_PVDDQ_ABC_AIREF1     
R4A1             RES_0402-51.1,1.0%,1/16W,CHIP,A 1        GND                     
                                  2        PVTT_DEF                
R4A2             RES_0402-0.0,5%,1/16W,CHIP,G21A 1        PWRGD_PVDDQ_DEF         
                                  2        FM_PVTT_DEF_EN_R        
R4A3             RES_0402-0.0,5%,1/16W,CHIP,G21A 1        PWRGD_PVDDQ_KLM         
                                  2        FM_PVTT_KLM_EN_R        
R4A4             RES_0402-33.2,1%,1/16W,CHIP,G2A 1        PWRGD_PVTT_KLM_CPU1_R   
                                  2        PWRGD_PVTT_CPU1         
R4A5             RES_0402-10.0K,1%,1/16W,CHIP,GA 1        P3V3                    
                                  2        PWRGD_PVTT_KLM_CPU1_R   
R4A6             RES_0402-33.2,1%,1/16W,CHIP,G2A 1        PWRGD_PVTT_DEF_CPU0_R   
                                  2        PWRGD_PVTT_CPU0         
R4A7             RES_0402-2.2,5%,1/16W,EMPTY,G2A 1        VR_PVPP_KLM_SNUB        
                                  2        GND                     
R4A8             RES_0402-0.0,5%,1/16W,CHIP,G21A 1        SMB_LAN_STBY_LVC3_SDA   
                                  2        SMB_PIROM_CPU0_SDA      
R4A9             RES_0402-0.0,5%,1/16W,CHIP,G21A 1        SMB_LAN_STBY_LVC3_SCL   
                                  2        SMB_PIROM_CPU0_SCL      
R4B1             RES_0402-0.0,5%,1/16W,CHIP,G21A 1        FM_PVPP_CPU1_EN         
                                  2        FM_PVPP_PVDDQ_CPU1_EN_KLM
R4B2             RES_0603-120.0,1%,1/10W,CHIP,GA 1        PVPP_KLM                
                                  2        GND                     
R4B3             RES_0402-0.0,5%,1/16W,CHIP,G21A 1        PVPP_KLM                
                                  2        VSENSE_PVPP_KLM         
R4B4             RES_0402-6.34K,1%,1/16W,CHIP,GA 1        VR_FB_PVPP_KLM          
                                  2        AGND_PVPP_KLM           
R4B5             RES_0402-20.0K,1%,1/16W,CHIP,GA 1        VSENSE_PVPP_KLM         
                                  2        VR_FB_PVPP_KLM          
R4B6             RES_0402-7.87K,1.0%,1/16W,CHIPA 1        VR_PVPP_KLM_ISET        
                                  2        AGND_PVPP_KLM           
R4B7             RES_0402-22.1,1.0%,1/16W,CHIP,A 1        PWRGD_PVPP_KLM_R        
                                  2        PWRGD_PVPP_KLM          
R4B8             RES_0402-7.87K,1.0%,1/16W,CHIPA 1        VR_COMP_RC_PVPP_KLM     
                                  2        VR_FB_PVPP_KLM          
R4B9             RES_0402-1.0K,0.1%,1/16W,CHIP,A 1        VSENSE_PVPP_KLM         
                                  2        VR_COMP_PVPP_KLM        
R4B10            RES_0402-1.00K,1%,1/16W,CHIP,GA 1        P3V3_STBY               
                                  2        PWRGD_PVPP_KLM_R        
R4B11            RES_0402-0.0,5%,1/16W,CHIP,G21A 1        VR_PVDDQ_DEF_AIINSEN_R  
                                  2        VR_PVDDQ_DEF_AIINSEN    
R4B12            RES_1206-0.002,1%,1W,CHIP,G521A 1        P12V_NVDIMM_DEF         
                                  2        P12V_STBY               
R4B13            RES_0402-0.0,5%,1/16W,CHIP,G21A 1        VR_PVPP_KLM_BOOT        
                                  2        VR_PVPP_KLM_BOOT_R      
R4B14            RES_0402-0.0,5%,1/16W,CHIP,G21A 1        GND                     
                                  2        AGND_PVPP_KLM           
R4C1             RES_0402-100.0,1%,1/16W,CHIP,GA 1        VSENSE_PVSA_CPU0_N      
                                  2        GND                     
R4C2             RES_0402-0.0,5%,1/16W,CHIP,G21A 1        VSENSE_PVSA_CPU0_N      
                                  2        VSENSE_PVSA_CPU0_SKT_VRTN
R4C3             RES_0402-1.00K,1%,1/16W,EMPTY,A 1        VSENSE_PVSA_CPU0_P      
                                  2        VSENSE_PVSA_CPU0_N      
R4C4             RES_0402-0.0,5%,1/16W,CHIP,G21A 1        VSENSE_PVSA_CPU0_P      
                                  2        VSENSE_PVSA_CPU0_SKT_VSEN
R4C5             RES_0402-100.0,1%,1/16W,CHIP,GA 1        VSENSE_PVSA_CPU0_P      
                                  2        PVSA_CPU0               
R4C6             RES_2010-0.001,1%,1W,CHIP,E309A 1        VR_FET_SW_P12V_PVCCIN_CPU0_R
                                  2        VR_FET_SW_P12V_STBY_PVCCIN_CPU0
R4C8             RES_0402-1.00K,1%,1/16W,CHIP,GA 1        P3V3_STBY               
                                  2        PU_GTL2014_2_DIR        
R4C9             RES_0402-1.00K,1%,1/16W,CHIP,GA 1        GND                     
                                  2        PD_GTL2014_2_VREF       
R4C10            RES_0402-240,1.0%,1/16W,CHIP,GA 1        PVCCIO_CPU1             
                                  2        PU_CPU1_TSC_SYNC        
R4C11            RES_0402-3.16K,1%,1/16W,CHIP,GA 1        VR_PVCCMCP_CPU1_XADDR2  
                                  2        GND                     
R4C12            RES_0402-8.06K,1%,1/16W,CHIP,GA 1        VR_PVCCIOMCP_CPU1_XADDR1
                                  2        GND                     
R4C13            RES_0402-68.1K,1%,1/16W,EMPTY,A 1        VR_PVSA_CPU0_OCSET      
                                  2        GND                     
R4D1             RES_0402-27.4,1%,1/16W,CHIP,G2A 1        CLK_100M_CPU1_BCLK1_R_DN
                                  2        CLK_100M_CPU1_BCLK1_DN  
R4D2             RES_0402-27.4,1%,1/16W,CHIP,G2A 1        CLK_100M_CPU1_BCLK1_R_DP
                                  2        CLK_100M_CPU1_BCLK1_DP  
R4D3             RES_0402-27.4,1%,1/16W,CHIP,G2A 1        CLK_100M_CPU1_BCLK0_R_DN
                                  2        CLK_100M_CPU1_BCLK0_DN  
R4D4             RES_0402-27.4,1%,1/16W,CHIP,G2A 1        CLK_100M_CPU1_BCLK0_R_DP
                                  2        CLK_100M_CPU1_BCLK0_DP  
R4D5             RES_0402-27.4,1%,1/16W,CHIP,G2A 1        CLK_100M_CPU0_RC_REFCLK1_R_DN
                                  2        CLK_100M_CPU0_RC_REFCLK1_DN
R4D6             RES_0402-27.4,1%,1/16W,CHIP,G2A 1        CLK_100M_CPU0_RC_REFCLK1_R_DP
                                  2        CLK_100M_CPU0_RC_REFCLK1_DP
R4D7             RES_0402-27.4,1%,1/16W,CHIP,G2A 1        CLK_100M_CPU0_RC_REFCLK0_R_DN
                                  2        CLK_100M_CPU0_RC_REFCLK0_DN
R4D8             RES_0402-27.4,1%,1/16W,CHIP,G2A 1        CLK_100M_CPU0_RC_REFCLK0_R_DP
                                  2        CLK_100M_CPU0_RC_REFCLK0_DP
R4D9             RES_0402-27.4,1%,1/16W,CHIP,G2A 1        CLK_100M_CPU1_BCLK2_R_DP
                                  2        CLK_100M_CPU1_BCLK2_DP  
R4D10            RES_0402-27.4,1%,1/16W,CHIP,G2A 1        CLK_100M_CPU0_PE_REFCLK_R_DN
                                  2        CLK_100M_CPU0_PE_REFCLK_DN
R4D11            RES_0402-27.4,1%,1/16W,CHIP,G2A 1        CLK_100M_CPU1_BCLK2_R_DN
                                  2        CLK_100M_CPU1_BCLK2_DN  
R4D12            RES_0402-27.4,1%,1/16W,CHIP,G2A 1        CLK_100M_CPU0_PE_REFCLK_R_DP
                                  2        CLK_100M_CPU0_PE_REFCLK_DP
R4D13            RES_0402-27.4,1%,1/16W,CHIP,G2A 1        CLK_100M_CPU1_PE_REFCLK_R_DP
                                  2        CLK_100M_CPU1_PE_REFCLK_DP
R4D14            RES_0402-27.4,1%,1/16W,CHIP,G2A 1        CLK_100M_CPU0_BCLK2_R_DN
                                  2        CLK_100M_CPU0_BCLK2_DN  
R4D16            RES_0402-27.4,1%,1/16W,CHIP,G2A 1        CLK_100M_CPU1_PE_REFCLK_R_DN
                                  2        CLK_100M_CPU1_PE_REFCLK_DN
R4D17            RES_0402-27.4,1%,1/16W,CHIP,G2A 1        CLK_100M_CPU0_BCLK2_R_DP
                                  2        CLK_100M_CPU0_BCLK2_DP  
R4D18            RES_0402-42.2,1.0%,1/16W,EMPTYA 1        CLK_100M_CPU0_BCLK1_DN  
                                  2        GND                     
R4D19            RES_0402-27.4,1%,1/16W,CHIP,G2A 1        CLK_100M_CPU1_RC_REFCLK0_R_DP
                                  2        CLK_100M_CPU1_RC_REFCLK0_DP
R4D20            RES_0402-27.4,1%,1/16W,CHIP,G2A 1        CLK_100M_CPU0_BCLK1_R_DN
                                  2        CLK_100M_CPU0_BCLK1_DN  
R4D21            RES_0402-27.4,1%,1/16W,CHIP,G2A 1        CLK_100M_CPU1_RC_REFCLK0_R_DN
                                  2        CLK_100M_CPU1_RC_REFCLK0_DN
R4D22            RES_0402-27.4,1%,1/16W,CHIP,G2A 1        CLK_100M_CPU0_BCLK1_R_DP
                                  2        CLK_100M_CPU0_BCLK1_DP  
R4D23            RES_0402-27.4,1%,1/16W,CHIP,G2A 1        CLK_100M_CPU1_RC_REFCLK1_R_DP
                                  2        CLK_100M_CPU1_RC_REFCLK1_DP
R4D24            RES_0402-42.2,1.0%,1/16W,EMPTYA 1        CLK_100M_CPU0_BCLK1_DP  
                                  2        GND                     
R4D25            RES_0402-27.4,1%,1/16W,CHIP,G2A 1        CLK_100M_CPU0_BCLK0_R_DN
                                  2        CLK_100M_CPU0_BCLK0_DN  
R4D26            RES_0402-0.0,5%,1/16W,CHIP,G21A 1        P3V3_STBY               
                                  2        VR_PVCCIN_CPU0_VDD      
R4D27            RES_0402-100.0K,1%,1/16W,CHIP,B 1        VR_FET_SW_P12V_STBY_PVCCIN_CPU0
                                  2        VR_PVCCIN_CPU0_AVINSEN  
R4D28            RES_0402-27.4,1%,1/16W,CHIP,G2A 1        CLK_100M_CPU1_RC_REFCLK1_R_DN
                                  2        CLK_100M_CPU1_RC_REFCLK1_DN
R4D29            RES_0402-27.4,1%,1/16W,CHIP,G2A 1        CLK_100M_CPU0_BCLK0_R_DP
                                  2        CLK_100M_CPU0_BCLK0_DP  
R4D31            RES_0402-2.26K,1.0%,1/16W,EMPTA 1        P3V3_STBY               
                                  2        PU_VR_PVCCIN_CPU0_IMON  
R4D32            RES_0402-1.5K,1%,1/16W,CHIP,G2A 1        VR_PVCCIN_CPU0_AVINSEN  
                                  2        GND                     
R4D35            RES_0402-10.0K,1%,1/16W,EMPTY,A 1        P3V3_DB1200             
                                  2        FM_DB1200_SMB_SA0       
R4D36            RES_0402-33.2,1%,1/16W,CHIP,G2A 1        SMB_HOST_STBY_LVC3_SDA  
                                  2        SMB_HOST_STBY_LVC3_SDA_R2
R4D37            RES_0402-33.2,1%,1/16W,CHIP,G2A 1        SMB_HOST_STBY_LVC3_SCL  
                                  2        SMB_HOST_STBY_LVC3_SCL_R2
R4D38            RES_0402-10.0K,1%,1/16W,EMPTY,A 1        P3V3_DB1200             
                                  2        FM_DB1200_SMB_SA1       
R4D39            RES_0402-10.0,1%,1/16W,CHIP,G2A 1        VSENSE_PVSA_CPU0_P      
                                  2        VSENSE_PVSA_CPU0_BVSP   
R4D40            RES_0402-4.75K,1%,1/16W,CHIP,GA 1        P3V3_DB1200             
                                  2        FM_100M_N               
R4D41            RES_0402-4.75K,1%,1/16W,CHIP,GA 1        P3V3_DB1200             
                                  2        FM_HBW_BYPASS_LOWBW_N   
R4D42            RES_0402-1.00K,1%,1/16W,CHIP,GA 1        P3V3_STBY               
                                  2        PWRGD_PVCCIO_CPU1_R     
R4D43            RES_0402-20.0,1%,1/16W,CHIP,G2A 1        SMB_VR_STBY_LVC3_SCL    
                                  2        SMB_VR_SCL_PVCCIO_CPU1  
R4D44            RES_0402-20.0,1%,1/16W,CHIP,G2A 1        SMB_VR_STBY_LVC3_SDA    
                                  2        SMB_VR_SDA_PVCCIO_CPU1  
R4D45            RES_0402-0.0,5%,1/16W,CHIP,G21A 1        VR_PVCCIO_CPU1_VD12     
                                  2        VR_PVCCIO_CPU1_AIREF1   
R4D46            RES_0402-22.1,1.0%,1/16W,CHIP,A 1        PWRGD_PVCCIO_CPU1_R     
                                  2        PWRGD_PVCCIO_CPU1       
R4D47            RES_0402-0.0,5%,1/16W,CHIP,G21A 1        P3V3_STBY               
                                  2        VR_PVCCIO_CPU1_VDD      
R4D49            RES_0402-1.00K,1%,1/16W,CHIP,GA 1        P3V3_STBY               
                                  2        IRQ_PVCCIO_CPU1_VRHOT_N 
R4D50            RES_0402-0.0,5%,1/16W,CHIP,G21A 1        SMB_VR_SDA_R            
                                  2        SMB_VR_STBY_LVC3_SDA    
R4D51            RES_0402-150.0,1%,1/16W,CHIP,GA 1        SVID_CLK0_CPU1_R        
                                  2        SVID_CLK_PVCCIO_CPU1    
R4D53            RES_0402-0.0,5%,1/16W,CHIP,G21A 1        SMB_VR_SCL_R            
                                  2        SMB_VR_STBY_LVC3_SCL    
R4D54            RES_0402-0.0,5%,1/16W,CHIP,G21A 1        SVID_DIO0_CPU1_R        
                                  2        SVID_VDIO_PVCCIO_CPU1   
R4D56            RES_0402-0.0,5%,1/16W,CHIP,G21A 1        SVID_ALERT_PVCCIO_CPU1  
                                  2        SVID_ALERT0_CPU1_R_N    
R4D57            RES_0402-1.5K,1%,1/16W,CHIP,G2A 1        VR_PVCCIO_CPU1_VINSEN   
                                  2        GND                     
R4D58            RES_0402-1.00K,1%,1/16W,CHIP,GA 1        P3V3_STBY               
                                  2        VR_VRRDY_PVCCIN_CPU0    
R4D60            RES_0402-100.0K,1%,1/16W,CHIP,B 1        VR_FET_SW_P12V_STBY_PVCCIN_CPU0
                                  2        VR_PVCCIO_CPU1_VINSEN   
R4D63            RES_0402-22.1,1.0%,1/16W,CHIP,A 1        VR_VRRDY_PVCCIN_CPU0    
                                  2        PWRGD_PVCCIN_CPU0       
R4D64            RES_0402-3.16K,1%,1/16W,CHIP,GA 1        VR_PVCCIO_CPU1_XADDR1   
                                  2        GND                     
R4D65            RES_0402-33.2,1%,1/16W,CHIP,G2A 1        PWRGD_PVSA_CPU0_R       
                                  2        PWRGD_PVSA_CPU0         
R4D66            RES_0402-0.0,5%,1/16W,CHIP,G21A 1        SVID_VDIO_PVCCIN_CPU0   
                                  2        SVID_DIO0_CPU0_R        
R4D67            RES_0402-0.0,5%,1/16W,CHIP,G21A 1        SVID_VALERT_VCCIN_CPU0  
                                  2        SVID_ALERT0_CPU0_R_N    
R4D68            RES_0402-68.1K,1%,1/16W,EMPTY,A 1        VR_PVCCIN_CPU0_PH5_OCSET
                                  2        GND                     
R4D69            RES_0402-4.75K,1%,1/16W,CHIP,GA 1        P3V3                    
                                  2        FM_CPU1_MCP_CLK_EN_N    
R4D70            RES_0402-4.75K,1%,1/16W,CHIP,GA 1        P3V3                    
                                  2        FM_CPU0_MCP_CLK_EN_N    
R4D71            RES_0402-68.1K,1%,1/16W,EMPTY,A 1        VR_PVCCIN_CPU0_PH4_OCSET
                                  2        GND                     
R4D72            RES_0402-68.1K,1%,1/16W,EMPTY,A 1        VR_PVCCIN_CPU0_PH3_OCSET
                                  2        GND                     
R4E2             RES_0402-3.16K,1%,1/16W,CHIP,GA 1        VR_PVCCIO_CPU1_XADDR2   
                                  2        GND                     
R4E3             RES_0402-1.00K,1%,1/16W,CHIP,GA 1        P3V3_STBY               
                                  2        IRQ_PVCCIN_CPU0_VRHOT_LVC3_R_N
R4E4             RES_0402-2.26K,1.0%,1/16W,CHIPA 1        P3V3_STBY               
                                  2        FM_PVCCIN_CPU0_PWR_IN_ALERT_N
R4E5             RES_0402-1.00K,1%,1/16W,CHIP,GA 1        P3V3_STBY               
                                  2        PWRGD_PVSA_CPU0_R       
R4E6             RES_0402-150.0,1%,1/16W,CHIP,GA 1        SVID_CLK0_CPU0_R        
                                  2        SVID_VCLK_PVCCIN_CPU0   
R4E7             RES_0402-10.0,1%,1/16W,CHIP,G2A 1        VSENSE_PVCCIO_CPU1_AVSP 
                                  2        VR_PVCCIO_CPU1_AVSP     
R4E8             RES_0402-10.0,1%,1/16W,CHIP,G2A 1        VSENSE_PVCCIN_CPU0_P    
                                  2        VSENSE_PVCCIN_CPU0_AVSP 
R4E9             RES_0402-49.9,1%,1/16W,CHIP,G2A 1        PVCCIO_CPU0             
                                  2        SVID_CLK0_CPU0_R        
R4E10            RES_0402-100.0,1%,1/16W,CHIP,GA 1        PVCCIO_CPU0             
                                  2        SVID_DIO0_CPU0_R        
R4E13            RES_0603-100.0,1%,1/10W,CHIP,GA 1        PVCCIN_CPU0             
                                  2        GND                     
R4E14            RES_0402-100.0,1%,1/16W,CHIP,GA 1        VSENSE_PVCCIN_CPU0_P    
                                  2        PVCCIN_CPU0             
R4E15            RES_0402-1.00K,1%,1/16W,EMPTY,A 1        VSENSE_PVCCIN_CPU0_P    
                                  2        VSENSE_PVCCIN_CPU0_N    
R4E16            RES_0402-0.0,5%,1/16W,CHIP,G21A 1        VSENSE_PVCCIN_CPU0_P    
                                  2        VSENSE_PVCCIN_CPU0_SKT_VSEN
R4E17            RES_0402-0.0,5%,1/16W,CHIP,G21A 1        VSENSE_PVCCIN_CPU0_N    
                                  2        VSENSE_PVCCIN_CPU0_SKT_VRTN
R4E18            RES_0402-100.0,1%,1/16W,CHIP,GA 1        VSENSE_PVCCIN_CPU0_N    
                                  2        GND                     
R4E19            RES_0402-68.1K,1%,1/16W,EMPTY,A 1        VR_PVCCIN_CPU0_PH2_OCSET
                                  2        GND                     
R4E20            RES_0402-2.26K,1.0%,1/16W,EMPTA 1        P3V3_STBY               
                                  2        PU_VR_PVCCIN_CPU0_FLT1_SMBALT_N
R4E21            RES_0402-68.1K,1%,1/16W,EMPTY,A 1        VR_PVCCIO_CPU1_OCSET    
                                  2        GND                     
R4E22            RES_0402-68.1K,1%,1/16W,EMPTY,A 1        VR_PVCCIN_CPU0_PH1_OCSET
                                  2        GND                     
R4F1             RES_0402-0.0,5%,1/16W,CHIP,G21A 1        VR_PVDDQ_ABC_AIINSEN_R  
                                  2        VR_PVDDQ_ABC_AIINSEN    
R4F2             RES_1206-0.002,1%,1W,CHIP,G521A 1        P12V_NVDIMM_ABC         
                                  2        P12V_STBY               
R4F3             RES_0402-2,1.0%,1/16W,CHIP,G21A 1        M_A_CPU_VREF            
                                  2        M_A_VREF                
R4F4             RES_0402-1.00K,1%,1/16W,CHIP,GA 1        PVDDQ_ABC               
                                  2        M_A_VREF                
R4F5             RES_0402-1.00K,1%,1/16W,CHIP,GA 1        M_A_VREF                
                                  2        GND                     
R4F6             RES_0402-2.2,5%,1/16W,EMPTY,G2A 1        VR_PVPP_GHJ_SNUB        
                                  2        GND                     
R4G1             RES_0402-2,1.0%,1/16W,CHIP,G21A 1        M_B_CPU_VREF            
                                  2        M_B_VREF                
R4G2             RES_0402-1.00K,1%,1/16W,CHIP,GA 1        PVDDQ_ABC               
                                  2        M_B_VREF                
R4G3             RES_0402-1.00K,1%,1/16W,CHIP,GA 1        M_B_VREF                
                                  2        GND                     
R4G4             RES_0402-0.0,5%,1/16W,CHIP,G21A 1        FM_PVPP_CPU1_EN         
                                  2        FM_PVPP_PVDDQ_CPU1_EN_GHJ
R4G5             RES_0402-10.0K,1%,1/16W,CHIP,GA 1        FM_PVPP_CPU1_EN         
                                  2        GND                     
R4G6             RES_0603-120.0,1%,1/10W,CHIP,GA 1        PVPP_GHJ                
                                  2        GND                     
R4G7             RES_0402-20.0K,1%,1/16W,CHIP,GA 1        VSENSE_PVPP_GHJ         
                                  2        VR_FB_PVPP_GHJ          
R4G8             RES_0402-0.0,5%,1/16W,CHIP,G21A 1        PVPP_GHJ                
                                  2        VSENSE_PVPP_GHJ         
R4G9             RES_0402-6.34K,1%,1/16W,CHIP,GA 1        VR_FB_PVPP_GHJ          
                                  2        AGND_PVPP_GHJ           
R4G10            RES_0402-1.0K,0.1%,1/16W,CHIP,A 1        VSENSE_PVPP_GHJ         
                                  2        VR_COMP_PVPP_GHJ        
R4G11            RES_0402-7.87K,1.0%,1/16W,CHIPA 1        VR_PVPP_GHJ_ISET        
                                  2        AGND_PVPP_GHJ           
R4G12            RES_0402-22.1,1.0%,1/16W,CHIP,A 1        PWRGD_PVPP_GHJ_R        
                                  2        PWRGD_PVPP_GHJ          
R4G13            RES_0402-7.87K,1.0%,1/16W,CHIPA 1        VR_COMP_RC_PVPP_GHJ     
                                  2        VR_FB_PVPP_GHJ          
R4G14            RES_0402-1.00K,1%,1/16W,CHIP,GA 1        P3V3_STBY               
                                  2        PWRGD_PVPP_GHJ_R        
R4G15            RES_0402-33.2,1%,1/16W,CHIP,G2A 1        PWRGD_PVTT_GHJ_CPU1_R   
                                  2        PWRGD_PVTT_CPU1         
R4G16            RES_0402-0.0,5%,1/16W,CHIP,G21A 1        PWRGD_PVDDQ_GHJ         
                                  2        FM_PVTT_GHJ_EN_R        
R4G17            RES_0402-10.0K,1%,1/16W,CHIP,GA 1        P3V3                    
                                  2        PWRGD_PVTT_GHJ_CPU1_R   
R4G18            RES_0402-10.0K,1%,1/16W,CHIP,GA 1        P3V3                    
                                  2        PWRGD_PVTT_ABC_CPU0_R   
R4G19            RES_0402-33.2,1%,1/16W,CHIP,G2A 1        PWRGD_PVTT_ABC_CPU0_R   
                                  2        PWRGD_PVTT_CPU0         
R4G20            RES_0402-2,1.0%,1/16W,CHIP,G21A 1        M_C_CPU_VREF            
                                  2        M_C_VREF                
R4G21            RES_0402-1.00K,1%,1/16W,CHIP,GA 1        PVDDQ_ABC               
                                  2        M_C_VREF                
R4G22            RES_0402-1.00K,1%,1/16W,CHIP,GA 1        M_C_VREF                
                                  2        GND                     
R4G23            RES_0402-0.0,5%,1/16W,CHIP,G21A 1        PWRGD_PVDDQ_ABC         
                                  2        FM_PVTT_ABC_EN_R        
R4G24            RES_0402-0.0,5%,1/16W,CHIP,G21A 1        VR_PVPP_GHJ_BOOT        
                                  2        VR_PVPP_GHJ_BOOT_R      
R4G25            RES_0402-0.0,5%,1/16W,CHIP,G21A 1        GND                     
                                  2        AGND_PVPP_GHJ           
R4L2             RES_0402-100.0,1%,1/16W,EMPTY,A 1        VSENSE_PVDDQ_DEF_P      
                                  2        VSENSE_PVDDQ_DEF_N      
R4L4             RES_0603-120.0,1%,1/10W,CHIP,GA 1        PVDDQ_DEF               
                                  2        GND                     
R4P1             RES_0402-240,1.0%,1/16W,EMPTY,A 1        GND                     
                                  2        PD_CPU0_BIST_ENABLE     
R4P2             RES_0402-49.9,1%,1/16W,CHIP,G2A 1        A_CPU0_PE3_RBIAS        
                                  2        GND                     
R4P3             RES_0402-49.9,1%,1/16W,CHIP,G2A 1        A_CPU0_PE012_RBIAS      
                                  2        GND                     
R4P4             RES_0402-49.9,1%,1/16W,CHIP,G2A 1        A_CPU0_UPI2_RBIAS       
                                  2        GND                     
R4P5             RES_0402-10.0K,1%,1/16W,CHIP,GA 1        GND                     
                                  2        PD_CPU0_MCP01_DMON      
R4P6             RES_0402-240,1.0%,1/16W,EMPTY,A 1        GND                     
                                  2        PD_CPU0_DMIMODE_OVERRIDE
R4P7             RES_0402-240,1.0%,1/16W,EMPTY,A 1        GND                     
                                  2        PD_CPU0_KSFC_DIS        
R4P8             RES_0402-90.9,1%,1/16W,CHIP,G2A 1        A_CPU0_ABC_RCOMP0       
                                  2        GND                     
R4P10            RES_0402-90.9,1%,1/16W,CHIP,G2A 1        A_CPU0_ABC_RCOMP1       
                                  2        GND                     
R4P11            RES_0402-100.0,1%,1/16W,CHIP,GA 1        A_CPU0_ABC_RCOMP2       
                                  2        GND                     
R4P12            RES_0402-100.0,1%,1/16W,CHIP,GA 1        PVCCIO_CPU0             
                                  2        XDP_CPU_MBP0_N          
R4P14            RES_0402-240,1.0%,1/16W,CHIP,GA 1        PVCCIO_CPU0             
                                  2        PU_CPU0_LEGACY_SKT      
R4P15            RES_0402-100.0,1%,1/16W,CHIP,GA 1        PVCCIO_CPU0             
                                  2        XDP_CPU_MBP1_N          
R4P17            RES_0402-150.0,1%,1/16W,CHIP,GA 1        H_CPU0_MEMABC_MEMHOT_G_N
                                  2        PVCCIO_CPU0             
R4P18            RES_0402-49.9,1%,1/16W,CHIP,G2A 1        H_PM_SYNC_GTL_R1        
                                  2        H_PM_SYNC_GTL           
R4P19            RES_0402-49.9,1%,1/16W,CHIP,G2A 1        H_PMSYNC_CLK_24M_CPU0   
                                  2        H_PMSYNC_CLK_24M        
R4P20            RES_0402-150.0,1%,1/16W,CHIP,GA 1        H_CPU0_MEMDEF_MEMHOT_G_N
                                  2        PVCCIO_CPU0             
R4P21            RES_0402-240,1.0%,1/16W,CHIP,GA 1        PVCCIO_CPU0             
                                  2        PU_CPU0_TSC_SYNC        
R4P23            RES_0402-150.0,1%,1/16W,CHIP,GA 1        PVCCIO_CPU0             
                                  2        XDP_CPU0_TDO            
R4P24            RES_0402-150.0,1%,1/16W,CHIP,GA 1        PVCCIO_CPU0             
                                  2        XDP_CPU_TDI             
R4R1             RES_0402-1.00K,1%,1/16W,CHIP,GA 1        H_CPU0_FAST_WAKE_N      
                                  2        H_CPU0_FAST_WAKE_B_N    
R4R2             RES_0402-150.0,1%,1/16W,CHIP,GA 1        PVCCIO_CPU0             
                                  2        H_CPU0_CATERR_G_N       
R4R3             RES_0402-150.0,1%,1/16W,CHIP,GA 1        PVCCIO_CPU0             
                                  2        H_CPU0_PROCHOT_G_N      
R4R4             RES_0402-150.0,1%,1/16W,CHIP,GA 1        PVCCIO_CPU0             
                                  2        H_CPU0_FAST_WAKE_N      
R4R5             RES_0402-4.75K,1%,1/16W,CHIP,GA 1        P3V3_STBY               
                                  2        FM_CPU0_SKTOCC_LVT3_N   
R4R6             RES_0402-49.9,1%,1/16W,CHIP,G2A 1        JTAG_MCP_CPU0_TDI_R     
                                  2        JTAG_MCP_CPU0_TDI       
R4T1             RES_0402-0.0,5%,1/16W,CHIP,G21A 1        FM_ADR_COMPLETE_DLY     
                                  2        FM_ADR_COMPLETE_R       
R4T2             RES_0402-0.0,5%,1/16W,EMPTY,G2A 1        FM_ADR_COMPLETE         
                                  2        FM_ADR_COMPLETE_R       
R4T3             RES_0402-10.0,1%,1/16W,CHIP,G2A 1        SMB_DDR_ABC_SCL_G_R     
                                  2        SMB_DDR_ABC_SCL_G       
R4T4             RES_0402-10.0,1%,1/16W,CHIP,G2A 1        SMB_DDR_ABC_SDA_G_R     
                                  2        SMB_DDR_ABC_SDA_G       
R4T5             RES_0402-240,1.0%,1/16W,CHIP,GA 1        PVCCIO_CPU0             
                                  2        SMB_DDR_ABC_SCL_G       
R4T6             RES_0402-240,1.0%,1/16W,CHIP,GA 1        PVCCIO_CPU0             
                                  2        SMB_DDR_ABC_SDA_G       
R4T7             RES_0402-665,1.0%,1/16W,CHIP,GA 1        PVPP_ABC                
                                  2        SMB_DDR_ABC_VPP_SCL_R   
R4T8             RES_0402-665,1.0%,1/16W,CHIP,GA 1        PVPP_ABC                
                                  2        SMB_DDR_ABC_VPP_SDA_R   
R4T9             RES_0402-20.0,1%,1/16W,CHIP,G2A 1        SMB_DDR_ABC_VPP_SCL_R   
                                  2        SMB_DDR_ABC_VPP_SCL     
R4T10            RES_0402-20.0,1%,1/16W,CHIP,G2A 1        SMB_DDR_ABC_VPP_SDA_R   
                                  2        SMB_DDR_ABC_VPP_SDA     
R4U1             RES_0402-4.75K,1%,1/16W,CHIP,GA 1        P3V3_STBY               
                                  2        FM_MEM_THERM_EVENT_LVT3_N
R4U2             RES_0402-2.21K,1%,1/16W,CHIP,GA 1        PVPP_ABC                
                                  2        FM_DIMM_EVENT_COD_N     
R4U3             RES_0402-4.75K,1%,1/16W,CHIP,GA 1        PVPP_ABC                
                                  2        FM_DIMM_EVENT_FET       
R4U4             RES_0402-33.0K,5%,1/16W,CHIP,GA 1        FM_DIMM_EVENT_FET       
                                  2        GND                     
R4U6             RES_0402-100.0,1%,1/16W,EMPTY,A 1        VSENSE_PVDDQ_ABC_P      
                                  2        VSENSE_PVDDQ_ABC_N      
R5D1             RES_0402-90.9,1%,1/16W,CHIP,G2A 1        A_CPU0_DEF_RCOMP0       
                                  2        GND                     
R5D2             RES_0402-90.9,1%,1/16W,CHIP,G2A 1        A_CPU0_DEF_RCOMP1       
                                  2        GND                     
R5D3             RES_0402-240,1.0%,1/16W,CHIP,GA 1        PVCCIO_CPU0             
                                  2        PU_CPU0_FRMAGENT        
R5D4             RES_0402-240,1.0%,1/16W,EMPTY,A 1        PVCCIO_CPU0             
                                  2        PU_CPU0_TXT_AGENT       
R5D5             RES_0402-249,0.1%,1/16W,CHIP,GA 1        VSENSE_PMAX_CPU0        
                                  2        GND                     
R5D6             RES_0402-10.0,1%,1/16W,EMPTY,GA 1        PVCCIO_CPU0             
                                  2        VSENSE_PMAX_CPU0        
R5N1             RES_0402-10.0K,1%,1/16W,CHIP,GA 1        P3V3_STBY               
                                  2        FM_CPU0_PKGID0          
R5N2             RES_0402-1.8K,1%,1/16W,CHIP,G2A 1        P3V3_STBY               
                                  2        FM_CPU0_PROC_ID1        
R5N3             RES_0402-10.0K,1%,1/16W,CHIP,GA 1        P3V3_STBY               
                                  2        FM_CPU0_PKGID2          
R5N4             RES_0402-1.8K,1%,1/16W,CHIP,G2A 1        P3V3_STBY               
                                  2        FM_CPU0_PROC_ID0        
R5N5             RES_0402-10.0K,1%,1/16W,CHIP,GA 1        P3V3_STBY               
                                  2        FM_CPU0_PKGID1          
R5P1             RES_0603-100.0K,1%,1/10W,CHIP,A 1        PVCCIN_CPU0             
                                  2        VSENSE_VCCINR2PMAX_CPU0 
R5P2             RES_0402-49.9,1%,1/16W,CHIP,G2A 1        PD_CPU0_TEST14          
                                  2        GND                     
R5P3             RES_0402-49.9,1%,1/16W,CHIP,G2A 1        PD_CPU0_TEST13          
                                  2        GND                     
R5P4             RES_0402-49.9,1%,1/16W,CHIP,G2A 1        PD_CPU0_RSVD_TEST_2     
                                  2        GND                     
R5R1             RES_0402-49.9,1%,1/16W,CHIP,G2A 1        PD_CPU0_RSVD_TEST_1     
                                  2        GND                     
R6B1             RES_0402-49.9,1%,1/16W,CHIP,G2A 1        PVCCIO_CPU0             
                                  2        SVID_ALERT1_CPU0_R_N    
R6B2             RES_0402-100.0,1%,1/16W,CHIP,GA 1        PVCCIO_CPU0             
                                  2        SVID_DIO1_CPU0_R        
R6B3             RES_0402-221,1.0%,1/16W,CHIP,GA 1        SVID_ALERT1_CPU0_N      
                                  2        SVID_ALERT1_CPU0_R_N    
R6B4             RES_0402-0.0,5%,1/16W,CHIP,G21A 1        SVID_DIO1_CPU0          
                                  2        SVID_DIO1_CPU0_R        
R6B5             RES_0402-0.0,5%,1/16W,CHIP,G21A 1        SVID_CLK1_CPU0          
                                  2        SVID_CLK1_CPU0_R        
R6D1             RES_0402-100.0,1%,1/16W,CHIP,GA 1        A_CPU0_DEF_RCOMP2       
                                  2        GND                     
R6D2             RES_0402-49.9,1%,1/16W,CHIP,G2A 1        A_CPU0_MCP01_RBIAS      
                                  2        GND                     
R6D5             RES_0402-49.9,1%,1/16W,CHIP,G2A 1        PD_CPU0_TEST12          
                                  2        GND                     
R6D6             RES_0402-240,1.0%,1/16W,CHIP,GA 1        GND                     
                                  2        PD_CPU0_TXT_PLTEN       
R6D7             RES_0402-240,1.0%,1/16W,EMPTY,A 1        PVCCIO_CPU0             
                                  2        H_CPU0_BMCINIT          
R6D8             RES_0402-49.9,1%,1/16W,CHIP,G2A 1        PVCCIO_CPU0             
                                  2        PWRGD_CPU0_G            
R6D9             RES_0402-150.0,1%,1/16W,CHIP,GA 1        PVCCIO_CPU0             
                                  2        H_CPU0_MSMI_G_N         
R6D10            RES_0402-240,1.0%,1/16W,EMPTY,A 1        PVCCIO_CPU0             
                                  2        PU_CPU0_SOCKET_ID_1     
R6D11            RES_0402-49.9,1%,1/16W,CHIP,G2A 1        A_CPU0_UPI01_RBIAS      
                                  2        GND                     
R6D12            RES_0402-49.9,1%,1/16W,CHIP,G2A 1        PVCCIO_CPU0             
                                  2        RST_CPU0_G_N            
R6D13            RES_0402-240,1.0%,1/16W,EMPTY,A 1        PVCCIO_CPU0             
                                  2        PU_CPU0_SAFE_MODE_BOOT  
R6D14            RES_0402-240,1.0%,1/16W,EMPTY,A 1        PVCCIO_CPU0             
                                  2        PU_CPU0_EAR_N           
R6D15            RES_0402-240,1.0%,1/16W,EMPTY,A 1        PVCCIO_CPU0             
                                  2        PU_CPU0_SOCKET_ID_0     
R6D16            RES_0402-0.0,5%,1/16W,EMPTY,G2A 1        FM_CPU_BMC_INIT         
                                  2        H_CPU0_BMCINIT          
R6F1             RES_0402-49.9,1%,1/16W,CHIP,G2A 1        IRQ_DIMM_SAVE_N         
                                  2        FM_ADR_COMPLETE_DEF_N   
R6F2             RES_0402-49.9,1%,1/16W,CHIP,G2A 1        IRQ_DIMM_SAVE_N         
                                  2        FM_ADR_COMPLETE_KLM_N   
R6F3             RES_0402-10.0K,1%,1/16W,CHIP,GA 1        PVPP_ABC                
                                  2        IRQ_DIMM_SAVE_N         
R6F4             RES_0402-49.9,1%,1/16W,CHIP,G2A 1        IRQ_DIMM_SAVE_N         
                                  2        FM_ADR_COMPLETE_ABC_N   
R6F5             RES_0402-49.9,1%,1/16W,CHIP,G2A 1        IRQ_DIMM_SAVE_N         
                                  2        FM_ADR_COMPLETE_GHJ_N   
R6F6             RES_0402-0.0,5%,1/16W,EMPTY,G2A 1        CLK_322M_156M_CPU0_OSC_VRM_DN
                                  2        CLK_156M_OSC_CPU0_HFI_DN
R6F7             RES_0402-0.0,5%,1/16W,CHIP,G21A 1        CLK_156M_OSC_BRD_CPU0_DN
                                  2        CLK_156M_OSC_CPU0_HFI_DN
R6F8             RES_0402-0.0,5%,1/16W,EMPTY,G2A 1        CLK_322M_156M_CPU0_OSC_VRM_DP
                                  2        CLK_156M_OSC_CPU0_HFI_DP
R6F9             RES_0402-0.0,5%,1/16W,CHIP,G21A 1        CLK_156M_OSC_BRD_CPU0_DP
                                  2        CLK_156M_OSC_CPU0_HFI_DP
R6F10            RES_0402-0.0,5%,1/16W,EMPTY,G2A 1        CLK_322M_156M_CPU0_OSC_VRM_DN
                                  2        CLK_322M_OSC_CPU0_RC_DN 
R6F11            RES_0402-0.0,5%,1/16W,EMPTY,G2A 1        CLK_322M_156M_CPU0_OSC_VRM_DP
                                  2        CLK_322M_OSC_CPU0_RC_DP 
R6L1             RES_0402-1.00K,1%,1/16W,CHIP,GA 1        M_F_VREF                
                                  2        GND                     
R6L2             RES_0402-1.00K,1%,1/16W,CHIP,GA 1        PVDDQ_DEF               
                                  2        M_F_VREF                
R6L3             RES_0402-2,1.0%,1/16W,CHIP,G21A 1        M_F_CPU_VREF            
                                  2        M_F_VREF                
R6L4             RES_0402-1.0M,1%,1/16W,EMPTY,GA 1        P3V3                    
                                  2        FM_PVTT_DEF_EN_R        
R6L5             RES_0402-1.0M,1%,1/16W,EMPTY,GA 1        P3V3                    
                                  2        FM_PVTT_KLM_EN_R        
R6L6             RES_0402-0.0,5%,1/16W,CHIP,G21A 1        PVDDQ_KLM               
                                  2        VSENSE_PVDDQ_KLM_VTT    
R6L7             RES_0402-51.1,1.0%,1/16W,CHIP,A 1        GND                     
                                  2        PVTT_KLM                
R6L8             RES_0402-0.0,5%,1/16W,CHIP,G21A 1        P3V3                    
                                  2        VR_PVTT_KLM_BIAS        
R6L9             RES_0402-10.0K,1%,1/16W,CHIP,GA 1        P3V3                    
                                  2        PWRGD_PVTT_DEF_CPU0_R   
R6L10            RES_0402-0.0,5%,1/16W,CHIP,G21A 1        PVDDQ_DEF               
                                  2        VSENSE_PVDDQ_DEF_VTT    
R6L11            RES_0402-0.0,5%,1/16W,CHIP,G21A 1        P3V3                    
                                  2        VR_PVTT_DEF_BIAS        
R6L12            RES_0402-1.00K,1%,1/16W,CHIP,GA 1        M_E_VREF                
                                  2        GND                     
R6L13            RES_0402-1.00K,1%,1/16W,CHIP,GA 1        PVDDQ_DEF               
                                  2        M_E_VREF                
R6L14            RES_0402-2,1.0%,1/16W,CHIP,G21A 1        M_E_CPU_VREF            
                                  2        M_E_VREF                
R6L16            RES_0402-1.00K,1%,1/16W,CHIP,GA 1        M_D_VREF                
                                  2        GND                     
R6M1             RES_0402-1.00K,1%,1/16W,CHIP,GA 1        PVDDQ_DEF               
                                  2        M_D_VREF                
R6M2             RES_0402-2,1.0%,1/16W,CHIP,G21A 1        M_D_CPU_VREF            
                                  2        M_D_VREF                
R6M4             RES_0402-4.75K,1%,1/16W,CHIP,GA 1        P3V3                    
                                  2        H_CPU1_MEMKLM_MEMHOT    
R6M8             RES_0402-49.9,1%,1/16W,CHIP,G2A 1        JTAG_MCP_CPU1_TDI_R     
                                  2        JTAG_MCP_CPU1_TDI       
R6M9             RES_0402-4.75K,1%,1/16W,CHIP,GA 1        PVPP_KLM                
                                  2        RST_CD_CPU1_POR_N       
R6N1             RES_0402-49.9,1%,1/16W,CHIP,G2A 1        SVID_ALERT0_CPU0_R_N    
                                  2        PVCCIO_CPU0             
R6N2             RES_0402-100.0,1%,1/16W,CHIP,GA 1        SVID_DIO0_CPU0_R        
                                  2        PVCCIO_CPU0             
R6N3             RES_0402-1.0,1%,1/16W,CHIP,G21A 1        VR_PVSA_CPU0_VCIN       
                                  2        P5V_STBY                
R6N4             RES_0402-51.1,1.0%,1/16W,CHIP,A 1        PVSA_CPU0               
                                  2        GND                     
R6N8             RES_0402-10.0,1%,1/16W,CHIP,G2A 1        SMB_CPU1_PE_HP_GTL_SCL  
                                  2        SMB_CPU1_PE_HP_GTL_R_SCL
R6N9             RES_0402-10.0,1%,1/16W,CHIP,G2A 1        SMB_CPU1_PE_HP_GTL_SDA  
                                  2        SMB_CPU1_PE_HP_GTL_R_SDA
R6N10            RES_0402-221,1.0%,1/16W,CHIP,GA 1        SVID_ALERT0_CPU0_N      
                                  2        SVID_ALERT0_CPU0_R_N    
R6N11            RES_0402-0.0,5%,1/16W,CHIP,G21A 1        SVID_DIO0_CPU0          
                                  2        SVID_DIO0_CPU0_R        
R6N12            RES_0402-0.0,5%,1/16W,CHIP,G21A 1        SVID_CLK0_CPU0          
                                  2        SVID_CLK0_CPU0_R        
R6N13            RES_0402-1.00K,1%,1/16W,CHIP,GA 1        GND                     
                                  2        PD_PIROM_CPU0_ADDR1     
R6N14            RES_0402-1.00K,1%,1/16W,CHIP,GA 1        GND                     
                                  2        PD_PIROM_CPU0_ADDR0     
R6N15            RES_0402-1.00K,1%,1/16W,CHIP,GA 1        GND                     
                                  2        PD_PIROM_CPU0_ADDR2     
R6P1             RES_0402-42.2,1.0%,1/16W,EMPTYA 1        CLK_100M_CPU0_RC_REFCLK0_DP
                                  2        GND                     
R6P2             RES_0402-42.2,1.0%,1/16W,EMPTYA 1        CLK_100M_CPU0_RC_REFCLK0_DN
                                  2        GND                     
R6P3             RES_0402-42.2,1.0%,1/16W,EMPTYA 1        CLK_100M_CPU0_RC_REFCLK1_DP
                                  2        GND                     
R6P4             RES_0402-42.2,1.0%,1/16W,EMPTYA 1        CLK_100M_CPU0_RC_REFCLK1_DN
                                  2        GND                     
R6P5             RES_0402-42.2,1.0%,1/16W,EMPTYA 1        CLK_100M_CPU1_BCLK0_DP  
                                  2        GND                     
R6P6             RES_0402-42.2,1.0%,1/16W,EMPTYA 1        CLK_100M_CPU1_BCLK0_DN  
                                  2        GND                     
R6P7             RES_0402-42.2,1.0%,1/16W,EMPTYA 1        CLK_100M_CPU1_BCLK1_DP  
                                  2        GND                     
R6P8             RES_0402-42.2,1.0%,1/16W,EMPTYA 1        CLK_100M_CPU1_BCLK1_DN  
                                  2        GND                     
R6P9             RES_0402-42.2,1.0%,1/16W,EMPTYA 1        CLK_100M_CPU0_PE_REFCLK_DN
                                  2        GND                     
R6P10            RES_0402-1.0,1%,1/16W,CHIP,G21A 1        VR_PVCCIN_CPU0_PH4_VCIN 
                                  2        P5V_STBY                
R6P11            RES_0402-42.2,1.0%,1/16W,EMPTYA 1        CLK_100M_CPU0_PE_REFCLK_DP
                                  2        GND                     
R6P12            RES_0402-42.2,1.0%,1/16W,EMPTYA 1        CLK_100M_CPU0_BCLK2_DN  
                                  2        GND                     
R6P13            RES_0402-42.2,1.0%,1/16W,EMPTYA 1        CLK_100M_CPU0_BCLK2_DP  
                                  2        GND                     
R6P15            RES_0402-42.2,1.0%,1/16W,EMPTYA 1        CLK_100M_CPU0_BCLK0_DN  
                                  2        GND                     
R6P16            RES_0402-1.00K,1%,1/16W,CHIP,GA 1        PVCCIO_CPU0             
                                  2        VR_PVCCIN_CPU0_VREN     
R6P17            RES_0402-42.2,1.0%,1/16W,EMPTYA 1        CLK_100M_CPU0_BCLK0_DP  
                                  2        GND                     
R6P18            RES_0402-0.0,5%,1/16W,CHIP,G21A 1        FM_PVCCIN_PVCCSA_CPU0_EN_LVC1
                                  2        VR_PVCCIN_CPU0_VREN     
R6P19            RES_0402-1.0,1%,1/16W,CHIP,G21A 1        VR_PVCCIN_CPU0_PH3_VCIN 
                                  2        P5V_STBY                
R6P20            RES_0402-1.00K,1%,1/16W,CHIP,GA 1        FM_DB1200_SMB_SA1       
                                  2        GND                     
R6P21            RES_0402-1.00K,1%,1/16W,CHIP,GA 1        FM_DB1200_SMB_SA0       
                                  2        GND                     
R6P22            RES_0402-4.75K,1%,1/16W,EMPTY,A 1        FM_HBW_BYPASS_LOWBW_N   
                                  2        GND                     
R6P23            RES_0402-4.75K,1%,1/16W,EMPTY,A 1        FM_100M_N               
                                  2        GND                     
R6P25            RES_0603-2.2,1.0%,1/10W,CHIP,GA 1        P3V3_DB1200             
                                  2        P3V3_DB1200_R           
R6P27            RES_0402-4.02K,1%,1/16W,CHIP,GA 1        VR_PVCCIN_CPU0_XADDR2   
                                  2        GND                     
R6P28            RES_0402-4.02K,1%,1/16W,CHIP,GA 1        VR_PVCCIN_CPU0_XADDR1   
                                  2        GND                     
R6P29            RES_0402-0.0,5%,1/16W,CHIP,G21A 1        VR_PVCCIN_CPU0_VD12     
                                  2        VR_PVSA_CPU0_BIREF1     
R6P30            RES_0402-0.0,5%,1/16W,CHIP,G21A 1        VR_PVCCIN_CPU0_VD12     
                                  2        VR_PVCCIN_CPU0_AIREF5   
R6P32            RES_0402-2.0K,1%,1/16W,EMPTY,GA 1        P3V3_STBY               
                                  2        SMB_VR_STBY_LVC3_SDA    
R6P33            RES_0402-110,1%,1/16W,EMPTY,G2A 1        PVCCIO_CPU1             
                                  2        SVID_CLK0_CPU1_R        
R6P34            RES_0402-0.0,5%,1/16W,CHIP,G21A 1        VR_PVCCIN_CPU0_VD12     
                                  2        VR_PVCCIN_CPU0_AIREF4   
R6P35            RES_0402-100.0,1%,1/16W,EMPTY,A 1        PVCCIO_CPU1             
                                  2        SVID_DIO0_CPU1_R        
R6P37            RES_0402-2.0K,1%,1/16W,EMPTY,GA 1        P3V3_STBY               
                                  2        SMB_VR_STBY_LVC3_SCL    
R6P38            RES_0402-0.0,5%,1/16W,CHIP,G21A 1        VR_PVCCIN_CPU0_VD12     
                                  2        VR_PVCCIN_CPU0_AIREF3   
R6P39            RES_0402-4.75K,1%,1/16W,CHIP,GA 1        P3V3_STBY               
                                  2        FM_CPU1_SKTOCC_LVT3_N   
R6P40            RES_0402-100.0K,1%,1/16W,EMPTYA 1        P3V3_STBY               
                                  2        VR_PVCCIO_CPU1_EN       
R6P41            RES_0402-0.0,5%,1/16W,CHIP,G21A 1        FM_PVCCIO_CPU1_EN       
                                  2        VR_PVCCIO_CPU1_EN       
R6P42            RES_0402-0.0,5%,1/16W,CHIP,G21A 1        VR_PVCCIN_CPU0_VD12     
                                  2        VR_PVCCIN_CPU0_AIREF2   
R6P43            RES_0402-0.0,5%,1/16W,CHIP,G21A 1        VR_PVCCIN_CPU0_VD12     
                                  2        VR_PVCCIN_CPU0_AIREF1   
R6P45            RES_0402-33.2,1%,1/16W,CHIP,G2A 1        IRQ_PVCCIN_CPU0_VRHOT_LVC3_R_N
                                  2        IRQ_PVCCIN_CPU0_VRHOT_LVC3_N
R6P46            RES_0402-100.0,1%,1/16W,CHIP,GA 1        PVCCIO_CPU0             
                                  2        XDP_CPU_MBP1_N          
R6P47            RES_0402-1.0,1%,1/16W,CHIP,G21A 1        VR_PVCCIN_CPU0_PH5_VCIN 
                                  2        P5V_STBY                
R6P48            RES_0402-4.75K,1%,1/16W,CHIP,GA 1        P3V3                    
                                  2        FM_DB1200ZL_BCLKS_EN_N  
R6P49            RES_0402-2.26K,1.0%,1/16W,EMPTA 1        P3V3_STBY               
                                  2        PU_VR_PVCCIO_CPU1_FAULT1
R6R2             RES_0402-1.0,1%,1/16W,CHIP,G21A 1        VR_PVCCIN_CPU0_PH1_VCIN 
                                  2        P5V_STBY                
R6R5             RES_0402-1.0,1%,1/16W,CHIP,G21A 1        VR_PVCCIO_CPU1_PH1_VCIN 
                                  2        P5V_STBY                
R6R6             RES_0402-1.0,1%,1/16W,CHIP,G21A 1        VR_PVCCIN_CPU0_PH2_VCIN 
                                  2        P5V_STBY                
R6T1             RES_0402-240,1.0%,1/16W,CHIP,GA 1        PVCCIO_CPU1             
                                  2        SMB_DDR_GHJ_SDA_G       
R6T2             RES_0402-240,1.0%,1/16W,CHIP,GA 1        PVCCIO_CPU1             
                                  2        SMB_DDR_GHJ_SCL_G       
R6T3             RES_0402-10.0,1%,1/16W,CHIP,G2A 1        SMB_DDR_GHJ_SCL_G_R     
                                  2        SMB_DDR_GHJ_SCL_G       
R6T4             RES_0402-10.0,1%,1/16W,CHIP,G2A 1        SMB_DDR_GHJ_SDA_G_R     
                                  2        SMB_DDR_GHJ_SDA_G       
R6T5             RES_0402-1.00K,1%,1/16W,CHIP,GA 1        XDP_CPU_TRST_N          
                                  2        GND                     
R6T6             RES_0402-150.0,1%,1/16W,CHIP,GA 1        PVCCIO_CPU1             
                                  2        XDP_CPU1_TDI            
R6T7             RES_0402-150.0,1%,1/16W,CHIP,GA 1        PVCCIO_CPU1             
                                  2        XDP_CPU1_TDO            
R6T8             RES_0402-100.0,1%,1/16W,CHIP,GA 1        PVCCIO_CPU0             
                                  2        XDP_CPU_OBSFN_B0_MBP6_N 
R6T9             RES_0402-100.0,1%,1/16W,CHIP,GA 1        PVCCIO_CPU0             
                                  2        XDP_CPU_OBSFN_B1_MBP7_N 
R6U3             RES_0402-1.0M,1%,1/16W,EMPTY,GA 1        P3V3                    
                                  2        FM_PVTT_GHJ_EN_R        
R6U4             RES_0402-0.0,5%,1/16W,CHIP,G21A 1        P3V3                    
                                  2        VR_PVTT_ABC_BIAS        
R6U5             RES_0402-0.0,5%,1/16W,CHIP,G21A 1        PVDDQ_ABC               
                                  2        VSENSE_PVDDQ_ABC_VTT    
R6U6             RES_0402-0.0,5%,1/16W,CHIP,G21A 1        PVDDQ_GHJ               
                                  2        VSENSE_PVDDQ_GHJ_VTT    
R6U7             RES_0402-0.0,5%,1/16W,CHIP,G21A 1        P3V3                    
                                  2        VR_PVTT_GHJ_BIAS        
R6U8             RES_0402-51.1,1.0%,1/16W,CHIP,A 1        GND                     
                                  2        PVTT_GHJ                
R6U13            RES_0402-20.0,1%,1/16W,CHIP,G2A 1        SMB_DDR_GHJ_VPP_SCL_R   
                                  2        SMB_DDR_GHJ_VPP_SCL     
R6U14            RES_0402-20.0,1%,1/16W,CHIP,G2A 1        SMB_DDR_GHJ_VPP_SDA_R   
                                  2        SMB_DDR_GHJ_VPP_SDA     
R6U15            RES_0402-1.0M,1%,1/16W,EMPTY,GA 1        P3V3                    
                                  2        FM_PVTT_ABC_EN_R        
R6U16            RES_0402-51.1,1.0%,1/16W,CHIP,A 1        GND                     
                                  2        PVTT_ABC                
R6U17            RES_0402-665,1.0%,1/16W,CHIP,GA 1        PVPP_GHJ                
                                  2        SMB_DDR_GHJ_VPP_SCL_R   
R6U18            RES_0402-665,1.0%,1/16W,CHIP,GA 1        PVPP_GHJ                
                                  2        SMB_DDR_GHJ_VPP_SDA_R   
R7A7             RES_0402-10.0,1%,1/16W,CHIP,G2A 1        VSENSE_PVDDQ_DEF_P      
                                  2        VR_PVDDQ_DEF_AVSP       
R7A8             RES_0402-8.06K,1%,1/16W,CHIP,GA 1        VR_PVDDQ_DEF_XADDR2     
                                  2        GND                     
R7A9             RES_0402-2.26K,1.0%,1/16W,EMPTA 1        P3V3_STBY               
                                  2        PU_VR_PVDDQ_DEF_FAULT1  
R7A10            RES_0402-3.16K,1%,1/16W,CHIP,GA 1        VR_PVDDQ_DEF_XADDR1     
                                  2        GND                     
R7A11            RES_0402-0.0,5%,1/16W,CHIP,G21A 1        SVID_ALERT_PVDDQ_DEF    
                                  2        SVID_ALERT1_CPU0_R_N    
R7A12            RES_0402-0.0,5%,1/16W,CHIP,G21A 1        SVID_VDIO_PVDDQ_DEF     
                                  2        SVID_DIO1_CPU0_R        
R7A13            RES_0402-100.0,1%,1/16W,CHIP,GA 1        VSENSE_PVNN_PCH_STBY_AVSP
                                  2        PVNN_PCH_STBY           
R7A14            RES_0402-10.0,1%,1/16W,CHIP,G2A 1        VSENSE_PVNN_PCH_STBY_FPK
                                  2        VSENSE_PVNN_PCH_STBY_AVSP
R7A15            RES_0402-2.2,5%,1/16W,EMPTY,G2A 1        VR_PVPP_DEF_SNUB        
                                  2        GND                     
R7A16            RES_0402-1.5K,1%,1/16W,CHIP,G2A 1        VR_PVDDQ_DEF_VINSEN     
                                  2        GND                     
R7A17            RES_0402-150.0,1%,1/16W,CHIP,GA 1        SVID_CLK1_CPU0_R        
                                  2        SVID_CLK_PVDDQ_DEF      
R7A18            RES_0402-0.0,5%,1/16W,CHIP,G21A 1        GND                     
                                  2        VSENSE_PVNN_PCH_STBY_AVSN
R7A19            RES_0402-10.0,1%,1/16W,CHIP,G2A 1        VSENSE_PVNN_PCH_STBY_QAT
                                  2        VSENSE_PVNN_PCH_STBY_AVSP
R7A20            RES_0402-68.1K,1%,1/16W,EMPTY,A 1        VR_PVDDQ_DEF_PH1_OCSET  
                                  2        GND                     
R7A21            RES_0402-68.1K,1%,1/16W,EMPTY,A 1        VR_PVDDQ_DEF_PH2_OCSET  
                                  2        GND                     
R7B1             RES_0402-33.2,1%,1/16W,CHIP,G2A 1        IRQ_PVDDQ_DEF_VRHOT_LVT3_R_N
                                  2        IRQ_PVDDQ_DEF_VRHOT_LVT3_N
R7B2             RES_0402-20.0,1%,1/16W,CHIP,G2A 1        SMB_VR_SDA_VDDQ_DEF     
                                  2        SMB_VR_STBY_LVC3_SDA    
R7B3             RES_0402-20.0,1%,1/16W,CHIP,G2A 1        SMB_VR_SCL_VDDQ_DEF     
                                  2        SMB_VR_STBY_LVC3_SCL    
R7B4             RES_0402-1.00K,1%,1/16W,CHIP,GA 1        P3V3_STBY               
                                  2        IRQ_PVDDQ_DEF_VRHOT_LVT3_R_N
R7B5             RES_0402-1.00K,1%,1/16W,CHIP,GA 1        P3V3_STBY               
                                  2        PWRGD_PVDDQ_DEF_R       
R7B6             RES_0402-10.0K,1%,1/16W,CHIP,GA 1        P3V3_STBY               
                                  2        FM_PCH_PRSNT_N          
R7B7             RES_0402-10.0K,1%,1/16W,EMPTY,A 1        A_EXTCLKP               
                                  2        GND                     
R7B8             RES_0402-10.0K,1%,1/16W,EMPTY,A 1        A_EXTCLKN               
                                  2        GND                     
R7B9             RES_0402-0.0,5%,1/16W,CHIP,G21A 1        FM_PVPP_CPU0_EN         
                                  2        FM_PVPP_PVDDQ_CPU0_EN_DEF
R7B10            RES_0603-120.0,1%,1/10W,CHIP,GA 1        PVPP_DEF                
                                  2        GND                     
R7B11            RES_0402-0.0,5%,1/16W,CHIP,G21A 1        PVPP_DEF                
                                  2        VSENSE_PVPP_DEF         
R7B12            RES_0402-22.1,1.0%,1/16W,CHIP,A 1        PWRGD_PVPP_DEF_R        
                                  2        PWRGD_PVPP_DEF          
R7B13            RES_0402-6.34K,1%,1/16W,CHIP,GA 1        VR_FB_PVPP_DEF          
                                  2        AGND_PVPP_DEF           
R7B14            RES_0402-7.87K,1.0%,1/16W,CHIPA 1        VR_PVPP_DEF_ISET        
                                  2        AGND_PVPP_DEF           
R7B15            RES_0402-20.0K,1%,1/16W,CHIP,GA 1        VSENSE_PVPP_DEF         
                                  2        VR_FB_PVPP_DEF          
R7B16            RES_0402-7.87K,1.0%,1/16W,CHIPA 1        VR_COMP_RC_PVPP_DEF     
                                  2        VR_FB_PVPP_DEF          
R7B17            RES_0402-1.00K,1%,1/16W,CHIP,GA 1        P3V3_STBY               
                                  2        PWRGD_PVPP_DEF_R        
R7B18            RES_0402-1.0K,0.1%,1/16W,CHIP,A 1        VSENSE_PVPP_DEF         
                                  2        VR_COMP_PVPP_DEF        
R7B19            RES_0402-0.0,5%,1/16W,CHIP,G21A 1        VR_PVPP_DEF_BOOT        
                                  2        VR_PVPP_DEF_BOOT_R      
R7B20            RES_0402-0.0,5%,1/16W,CHIP,G21A 1        GND                     
                                  2        AGND_PVPP_DEF           
R7C1             RES_0603-200K,0.1%,1/10W,CHIP,A 1        XTAL_PCH_48M_IN         
                                  2        XTAL_PCH_48M_OUT        
R7C2             RES_0402-0.0,5%,1/16W,EMPTY,G2A 1        CLK_100M_BMC_PE_R_DN    
                                  2        CLK_100M_BMC_PE_DN      
R7C3             RES_0402-51.1,1.0%,1/16W,CHIP,A 1        PVCCIO_CPU0             
                                  2        GND                     
R7C4             RES_0402-0.0,5%,1/16W,EMPTY,G2A 1        CLK_100M_BMC_PE_R_DP    
                                  2        CLK_100M_BMC_PE_DP      
R7C5             RES_0402-10.0K,1%,1/16W,CHIP,GA 1        P3V3_STBY               
                                  2        FM_SINT_PRSNT_N         
R7C6             RES_0603-10M,1.0%,1/10W,CHIP,GA 1        XTAL_33K_RTC1           
                                  2        XTAL_33K_RTC2           
R7C8             RES_0402-10.0K,1%,1/16W,CHIP,GA 1        P3V3_STBY               
                                  2        FM_WBG_PRSNT_N          
R7C10            RES_0402-20.0K,1%,1/16W,CHIP,GA 1        P3V3_RTC_STBY           
                                  2        RST_RTCRST_N            
R7C11            RES_0402-1.0M,1%,1/16W,EMPTY,GA 1        GND                     
                                  2        RST_RTCRST_N            
R7C13            RES_0402-10.0K,1%,1/16W,CHIP,GA 1        P3V3_STBY               
                                  2        FM_UART_PRES_N          
R7C14            RES_0402-33.2,1%,1/16W,CHIP,G2A 1        RMII_BMC_PCH_SPRNGVLLE_RXER
                                  2        RMII_BMC_PCH_SPRNGVLLE_RXER_R
R7C15            RES_0402-0.0,5%,1/16W,CHIP,G21A 1        SPI_PCH_MOSI_R          
                                  2        SPI_PCH_MOSI            
R7C16            RES_0402-33.2,1%,1/16W,CHIP,G2A 1        SPI_PCH_CS0_R_N         
                                  2        SPI_PCH_CS0_N           
R7C17            RES_0402-4.75K,1%,1/16W,CHIP,GA 1        PVCCIO_CPU0             
                                  2        PECI_BMC                
R7C18            RES_0402-0.0,5%,1/16W,EMPTY,G2A 1        PECI_BMC                
                                  2        PECI_CPU_G              
R7C19            RES_0402-0.0,5%,1/16W,CHIP,G21A 1        PECI_PCH                
                                  2        PECI_CPU_G              
R7C20            RES_0402-10.0K,1%,1/16W,CHIP,GA 1        CLK_50M_CKMNG_PCH_10GBE 
                                  2        GND                     
R7C21            RES_0402-10.0K,1%,1/16W,CHIP,GA 1        P1V05_PCH_STBY          
                                  2        FM_PCH_LVC1_THERMTRIP_N 
R7C22            RES_0402-4.75K,1%,1/16W,EMPTY,A 1        PVCCIO_CPU0             
                                  2        PECI_PCH                
R7C23            RES_0402-10.0K,1%,1/16W,CHIP,GA 1        P3V3_STBY               
                                  2        XDP_PCH_PWR_DEBUG_N     
R7C24            RES_0402-4.02K,1%,1/16W,CHIP,GA 1        VR_PVCCMCP_CPU0_XADDR2  
                                  2        GND                     
R7C25            RES_0402-68.1K,1%,1/16W,EMPTY,A 1        VR_PVCCIO_CPU0_OCSET    
                                  2        GND                     
R7C26            RES_0402-33.2,1%,1/16W,CHIP,G2A 1        CLK_24M_BMC_LPC         
                                  2        CLK_24M_BMC_LPC_R       
R7D1             RES_0402-1.00K,1%,1/16W,CHIP,GA 1        RMII_PCH_SPRNGVLLE_ARB_OUT
                                  2        GND                     
R7D2             RES_0402-1.00K,1%,1/16W,CHIP,GA 1        P3V3_STBY               
                                  2        PU_FM_RCIN_N            
R7D3             RES_0402-4.75K,1%,1/16W,CHIP,GA 1        P3V3_STBY               
                                  2        IRQ_LPC_SERIRQ_N        
R7D4             RES_0402-10.0K,1%,1/16W,CHIP,GA 1        P3V3_STBY               
                                  2        PU_IRQ_PCH_SCI_WHEA_N   
R7D5             RES_0402-2.26K,1.0%,1/16W,CHIPA 1        P3V3_STBY               
                                  2        FM_MB_SLOT_ID0          
R7D6             RES_0402-4.75K,1%,1/16W,CHIP,GA 1        P3V3_STBY               
                                  2        FM_BMC_READY_N          
R7D7             RES_0402-1.00K,1%,1/16W,CHIP,GA 1        P3V3_STBY               
                                  2        IRQ_PIRQA_SPI_TPM_N     
R7D8             RES_0402-10.0K,1%,1/16W,CHIP,GA 1        P3V3_STBY               
                                  2        PU_LPC_CLKRUN_N         
R7D9             RES_0402-2.26K,1.0%,1/16W,CHIPA 1        P3V3_STBY               
                                  2        FM_MB_SLOT_ID1          
R7D10            RES_0402-10.0K,1%,1/16W,CHIP,GA 1        P3V3_STBY               
                                  2        PU_LPC_PME_N            
R7D12            RES_0402-10.0K,1%,1/16W,CHIP,GA 1        P3V3_STBY               
                                  2        FM_OCP_MEZZA_PRES_N     
R7D13            RES_0402-8.2K,1%,1/16W,EMPTY,GA 1        P3V3_STBY               
                                  2        RMII_BMC_PCH_SPRNGVLLE_RXER
R7D15            RES_0402-348,1%,1/16W,CHIP,G21A 1        PECI_CPU_G              
                                  2        GND                     
R7D18            RES_0402-1.00K,1%,1/16W,CHIP,GA 1        FM_THERMTRIP_DLY        
                                  2        FM_THERMTRIP_DLY_R      
R7D19            RES_0402-1.00K,1%,1/16W,EMPTY,A 1        FM_OC_DETECT_EN_N       
                                  2        GND                     
R7D23            RES_0402-0.0,5%,1/16W,CHIP,G21A 1        RST_BMC_SRST_N          
                                  2        RST_BMC_SRST_R_N        
R7D24            RES_0402-33.2,1%,1/16W,CHIP,G2A 1        FM_CPU1_PROCHOT_LVT3_K_N
                                  2        FM_CPU1_PROCHOT_LVT3_N  
R7D25            RES_0402-33.2,1%,1/16W,CHIP,G2A 1        FM_CPU_MSMI_LVT3_R_N    
                                  2        FM_CPU_MSMI_LVT3_N      
R7D26            RES_0402-1.00K,1%,1/16W,CHIP,GA 1        PD_GTL2104_DIR_0        
                                  2        GND                     
R7D27            RES_0402-0.0,5%,1/16W,CHIP,G21A 1        H_CPU0_MSMI_G_N         
                                  2        H_CPU_MSMI_G_N          
R7D28            RES_0402-0.0,5%,1/16W,CHIP,G21A 1        H_CPU1_MSMI_G_N         
                                  2        H_CPU_MSMI_G_N          
R7D29            RES_0402-33.2,1%,1/16W,CHIP,G2A 1        FM_CPU0_FIVR_FAULT_R_LVT3
                                  2        FM_CPU0_FIVR_FAULT_LVT3 
R7D30            RES_0402-4.75K,1%,1/16W,CHIP,GA 1        P3V3_STBY               
                                  2        FM_CPLD_UART_CH_LOCK_N  
R7D31            RES_0402-33.2,1%,1/16W,CHIP,G2A 1        FM_CPU_ERR2_LVT3_R_N    
                                  2        FM_CPU_ERR2_LVT3_N      
R7D32            RES_0402-100.0,1%,1/16W,CHIP,GA 1        P0V7_GTL2104_VREF_0     
                                  2        GND                     
R7D33            RES_0402-49.9,1%,1/16W,CHIP,G2A 1        PVCCIO_CPU0             
                                  2        P0V7_GTL2104_VREF_0     
R7D34            RES_0402-33.2,1%,1/16W,CHIP,G2A 1        FM_CPU0_THERMTRIP_LVT3_R_N
                                  2        FM_CPU0_THERMTRIP_LVT3_N
R7D36            RES_0402-0.0,5%,1/16W,CHIP,G21A 1        FM_156M_CPU1_BRD_OSC_EN 
                                  2        FM_CPU1_STL_BRD_OSC_EN  
R7D37            RES_0402-0.0,5%,1/16W,EMPTY,G2A 1        FM_CPU1_VRM_OSC_EN      
                                  2        FM_CPU1_VRM_322M_156M_OSC_EN
R7D38            RES_0402-0.0,5%,1/16W,EMPTY,G2A 1        FM_CPU1_VRM_OSC_EN      
                                  2        FM_CPU1_STL_BRD_OSC_EN  
R7D39            RES_0402-0.0,5%,1/16W,EMPTY,G2A 1        FM_CPU0_VRM_OSC_EN      
                                  2        FM_CPU0_VRM_322M_156M_OSC_EN
R7D40            RES_0402-0.0,5%,1/16W,EMPTY,G2A 1        FM_CPU0_VRM_OSC_EN      
                                  2        FM_CPU0_STL_BRD_OSC_EN  
R7D41            RES_0402-0.0,5%,1/16W,CHIP,G21A 1        FM_CPU1_PROCHOT_LVT3_R_N
                                  2        FM_CPU1_PROCHOT_LVT3_K_N
R7D42            RES_0402-4.75K,1%,1/16W,CHIP,GA 1        P3V3_STBY               
                                  2        PU_FAB2_MARKER_CPLD     
R7D43            RES_0402-0.0,5%,1/16W,EMPTY,G2A 1        FM_CPU1_PROCHOT_LVT3_K_N
                                  2        H_CPU1_PROCHOT_G_PCH_N  
R7D44            RES_0402-4.75K,1%,1/16W,CHIP,GA 1        P1V05_PCH_STBY          
                                  2        FM_OCP_MEZZB_PRES_N     
R7E2             RES_0402-75,1.0%,1/16W,CHIP,G2A 1        PVCCIO_CPU0             
                                  2        H_CPU0_THERMTRIP_G_N    
R7E5             RES_0402-10.0K,1%,1/16W,CHIP,GA 1        P3V3_STBY               
                                  2        PU_THERMTRIP_FORCE_N    
R7E6             RES_0402-10.0K,1%,1/16W,CHIP,GA 1        P3V3_STBY               
                                  2        PU_RST_PERST_BIT1       
R7E7             RES_0402-4.75K,1%,1/16W,CHIP,GA 1        P3V3                    
                                  2        FM_SYS_THROTTLE_LVC3    
R7E9             RES_0402-0.0,5%,1/16W,CHIP,G21A 1        FM_THROTTLE_N           
                                  2        FM_THROTTLE_R_N         
R7E10            RES_0402-4.75K,1%,1/16W,CHIP,GA 1        P3V3                    
                                  2        IRQ_CPU0_VRHOT          
R7E11            RES_0402-4.75K,1%,1/16W,CHIP,GA 1        P3V3                    
                                  2        IRQ_CPU1_VRHOT          
R7E12            RES_0402-1.00K,1%,1/16W,CHIP,GA 1        P5V_STBY                
                                  2        PWRGD_P5V_STBY_R        
R7E13            RES_0402-0.0,5%,1/16W,CHIP,G21A 1        GND                     
                                  2        AGND_P5V_STBY           
R7E14            RES_0402-75K,1%,1/16W,CHIP,G21A 1        VR_P5V_STBY_RT          
                                  2        AGND_P5V_STBY           
R7E15            RES_0402-22.1,1.0%,1/16W,CHIP,A 1        PWRGD_P5V_STBY_R        
                                  2        PWRGD_P5V_STBY          
R7E16            RES_0402-1.37K,1%,1/16W,CHIP,GA 1        VR_P5V_STBY_VSENSE      
                                  2        AGND_P5V_STBY           
R7E17            RES_0402-0.0,5%,1/16W,CHIP,G21A 1        VR_FET_SW_P5V_STBY_PVIN 
                                  2        VR_P5V_STBY_VIN         
R7E18            RES_0402-4.75K,1%,1/16W,CHIP,GA 1        P3V3_STBY               
                                  2        RST_RSMRST_N            
R7E19            RES_0402-1.00K,1%,1/16W,EMPTY,A 1        P3V3_STBY               
                                  2        FM_MEM_EVENT_FUNC       
R7E20            RES_0402-1.00K,1%,1/16W,CHIP,GA 1        FM_MEM_EVENT_FUNC       
                                  2        GND                     
R7E21            RES_0402-4.75K,1%,1/16W,CHIP,GA 1        P3V3                    
                                  2        FM_PWRBRK_N             
R7E22            RES_0402-0.0,5%,1/16W,CHIP,G21A 1        FM_PWRBRK_N             
                                  2        FM_PWRBRK_SLOT_N        
R7F1             RES_0402-10.0K,1%,1/16W,CHIP,GA 1        VR_P5V_STBY_VSENSE_R    
                                  2        VR_P5V_STBY_VSENSE      
R7F3             RES_0402-33.2,1%,1/16W,CHIP,G2A 1        SPI_BIOS_SOCKET_IO3     
                                  2        PU_BIOS_SPI_HOLD0_N     
R7F4             RES_0402-33.2,1%,1/16W,CHIP,G2A 1        SPI_SWITCH_MISO         
                                  2        SPI_MISO_R0             
R7F5             RES_0402-4.75K,1%,1/16W,CHIP,GA 1        P3V3_STBY               
                                  2        SPI_CS0_PRIMARY_R_N     
R7F6             RES_0402-4.75K,1%,1/16W,EMPTY,A 1        P3V3_STBY               
                                  2        PU_SPI0_RST             
R7F7             RES_0402-2.2,5%,1/16W,EMPTY,G2A 1        VR_PVPP_ABC_SNUB        
                                  2        GND                     
R7F8             RES_0402-0.0,5%,1/16W,CHIP,G21A 1        VR_PVPP_ABC_BOOT        
                                  2        VR_PVPP_ABC_BOOT_R      
R7F9             RES_0402-0.0,5%,1/16W,CHIP,G21A 1        FM_PVPP_CPU0_EN         
                                  2        FM_PVPP_PVDDQ_CPU0_EN_ABC
R7F10            RES_0603-120.0,1%,1/10W,CHIP,GA 1        PVPP_ABC                
                                  2        GND                     
R7F11            RES_0402-6.34K,1%,1/16W,CHIP,GA 1        VR_FB_PVPP_ABC          
                                  2        AGND_PVPP_ABC           
R7F12            RES_0402-0.0,5%,1/16W,CHIP,G21A 1        PVPP_ABC                
                                  2        VSENSE_PVPP_ABC         
R7F13            RES_0402-20.0K,1%,1/16W,CHIP,GA 1        VSENSE_PVPP_ABC         
                                  2        VR_FB_PVPP_ABC          
R7F14            RES_0402-10.0K,1%,1/16W,CHIP,GA 1        FM_PVPP_CPU0_EN         
                                  2        GND                     
R7F15            RES_0402-7.87K,1.0%,1/16W,CHIPA 1        VR_PVPP_ABC_ISET        
                                  2        AGND_PVPP_ABC           
R7F16            RES_0402-22.1,1.0%,1/16W,CHIP,A 1        PWRGD_PVPP_ABC_R        
                                  2        PWRGD_PVPP_ABC          
R7F17            RES_0402-1.0K,0.1%,1/16W,CHIP,A 1        VSENSE_PVPP_ABC         
                                  2        VR_COMP_PVPP_ABC        
R7F18            RES_0402-7.87K,1.0%,1/16W,CHIPA 1        VR_COMP_RC_PVPP_ABC     
                                  2        VR_FB_PVPP_ABC          
R7F19            RES_0402-1.00K,1%,1/16W,CHIP,GA 1        P3V3_STBY               
                                  2        PWRGD_PVPP_ABC_R        
R7F20            RES_0402-100.0K,1%,1/16W,EMPTYA 1        P3V3_STBY               
                                  2        VR_PVDDQ_ABC_VREN       
R7F21            RES_0402-0.0,5%,1/16W,CHIP,G21A 1        FM_PVDDQ_ABC_EN         
                                  2        VR_PVDDQ_ABC_VREN       
R7F22            RES_0402-1.00K,1%,1/16W,CHIP,GA 1        P3V3_STBY               
                                  2        PWRGD_PVDDQ_ABC_R       
R7F23            RES_0402-33.2,1%,1/16W,CHIP,G2A 1        IRQ_PVDDQ_ABC_VRHOT_LVT3_R_N
                                  2        IRQ_PVDDQ_ABC_VRHOT_LVT3_N
R7F24            RES_0402-22.1,1.0%,1/16W,CHIP,A 1        PWRGD_PVDDQ_ABC_R       
                                  2        PWRGD_PVDDQ_ABC         
R7F25            RES_0402-20.0,1%,1/16W,CHIP,G2A 1        SMB_VR_SCL_VDDQ_ABC     
                                  2        SMB_VR_STBY_LVC3_SCL    
R7F26            RES_0402-20.0,1%,1/16W,CHIP,G2A 1        SMB_VR_SDA_VDDQ_ABC     
                                  2        SMB_VR_STBY_LVC3_SDA    
R7F27            RES_0402-1.00K,1%,1/16W,CHIP,GA 1        P3V3_STBY               
                                  2        IRQ_PVDDQ_ABC_VRHOT_LVT3_R_N
R7F28            RES_0402-10.0K,1%,1/16W,CHIP,GA 1        P3V3_STBY               
                                  2        PU_BIOS_SPI_WP0_N       
R7F29            RES_0402-33.2,1%,1/16W,CHIP,G2A 1        SPI_SWITCH_MOSI         
                                  2        SPI_SWITCH_MOSI_R0      
R7F30            RES_0402-10.0K,1%,1/16W,EMPTY,A 1        PU_BIOS_SPI_WP0_N       
                                  2        GND                     
R7F32            RES_0402-10.0K,1%,1/16W,CHIP,GA 1        P3V3_STBY               
                                  2        PU_BIOS_SPI_HOLD0_N     
R7F33            RES_0402-4.75K,1%,1/16W,CHIP,GA 1        P5V_STBY                
                                  2        FAN_PWM_OUT_SYS1_R      
R7F34            RES_0402-100.0K,1%,1/16W,CHIP,B 1        VR_FET_SW_P12V_STBY_PVDDQ_ABC
                                  2        VR_PVDDQ_ABC_VINSEN     
R7F35            RES_0402-0.0,5%,1/16W,CHIP,G21A 1        GND                     
                                  2        AGND_PVPP_ABC           
R7F36            RES_0402-2.26K,1.0%,1/16W,EMPTA 1        P3V3_STBY               
                                  2        PU_VR_PVDDQ_ABC_FAULT1  
R7F37            RES_0402-33.2,1%,1/16W,CHIP,G2A 1        SPI_BIOS_SOCKET_IO2     
                                  2        PU_BIOS_SPI_WP0_N       
R7G2             RES_0402-0.0,5%,1/16W,CHIP,G21A 1        SVID_VDIO_PVDDQ_ABC     
                                  2        SVID_DIO1_CPU0_R        
R7G3             RES_0402-1.5K,1%,1/16W,CHIP,G2A 1        VR_PVDDQ_ABC_VINSEN     
                                  2        GND                     
R7G4             RES_0402-0.0,5%,1/16W,CHIP,G21A 1        SVID_ALERT_PVDDQ_ABC    
                                  2        SVID_ALERT1_CPU0_R_N    
R7G7             RES_0402-4.75K,1%,1/16W,CHIP,GA 1        P3V3                    
                                  2        H_CPU0_MEMABC_MEMHOT    
R7G8             RES_0402-4.02K,1%,1/16W,CHIP,GA 1        VR_PVDDQ_ABC_XADDR1     
                                  2        GND                     
R7G9             RES_0402-10.0,1%,1/16W,CHIP,G2A 1        VSENSE_PVDDQ_ABC_P      
                                  2        VR_PVDDQ_ABC_AVSP       
R7G10            RES_0402-8.06K,1%,1/16W,CHIP,GA 1        VR_PVDDQ_ABC_XADDR2     
                                  2        GND                     
R7G14            RES_0402-0.0,5%,1/16W,CHIP,G21A 1        JTAG_PLD_TDO            
                                  2        JTAG_TDO                
R7G15            RES_0402-0.0,5%,1/16W,EMPTY,G2A 1        JTAG_PCH_PLD_TDO        
                                  2        JTAG_TDO                
R7G16            RES_0402-0.0,5%,1/16W,EMPTY,G2A 1        JTAG_PCH_GBE_TDO        
                                  2        JTAG_TDO                
R7G17            RES_0402-0.0,5%,1/16W,CHIP,G21A 1        JTAG_BMC_TDO            
                                  2        JTAG_TDO                
R7G18            RES_0402-0.0,5%,1/16W,EMPTY,G2A 1        JTAG_PCH_PLD_TDI        
                                  2        JTAG_TDI                
R7G19            RES_0402-0.0,5%,1/16W,EMPTY,G2A 1        JTAG_PCH_GBE_TDI        
                                  2        JTAG_TDI                
R7G21            RES_0402-0.0,5%,1/16W,CHIP,G21A 1        JTAG_TDO                
                                  2        JTAG_TDO_R              
R7G22            RES_0402-10.0K,1%,1/16W,CHIP,GA 1        P3V3_STBY               
                                  2        JTAG_TDO_R              
R7G23            RES_0402-10.0K,1%,1/16W,CHIP,GA 1        P3V3_STBY               
                                  2        JTAG_TDI_R              
R7G24            RES_0402-150.0,1%,1/16W,CHIP,GA 1        SVID_CLK1_CPU0_R        
                                  2        SVID_CLK_PVDDQ_ABC      
R7G25            RES_0402-68.1K,1%,1/16W,EMPTY,A 1        VR_PVDDQ_ABC_PH1_OCSET  
                                  2        GND                     
R7G26            RES_0402-10.0K,1%,1/16W,CHIP,GA 1        P3V3_STBY               
                                  2        FM_ME_RECOVER_N         
R7G27            RES_0402-1.00K,1%,1/16W,CHIP,GA 1        P3V3_STBY               
                                  2        PU_BIOS_USB_RECOVERY    
R7G28            RES_0402-1.00K,1%,1/16W,CHIP,GA 1        PD_ME_RCVR_N            
                                  2        GND                     
R7G29            RES_0402-1.00K,1%,1/16W,CHIP,GA 1        PD_PASSWORD_CLEAR       
                                  2        GND                     
R7G30            RES_0402-68.1K,1%,1/16W,EMPTY,A 1        VR_PVDDQ_ABC_PH2_OCSET  
                                  2        GND                     
R7G31            RES_0402-1.00K,1%,1/16W,CHIP,GA 1        P3V3_STBY               
                                  2        PU_BIOS_RECOVER_BOOT    
R7L2             RES_0402-100.0,1%,1/16W,EMPTY,A 1        VSENSE_PVDDQ_KLM_P      
                                  2        VSENSE_PVDDQ_KLM_N      
R7M1             RES_0402-665,1.0%,1/16W,CHIP,GA 1        PVPP_KLM                
                                  2        SMB_DDR_KLM_VPP_SCL_R   
R7M2             RES_0402-240,1.0%,1/16W,CHIP,GA 1        PVCCIO_CPU1             
                                  2        SMB_DDR_KLM_SCL_G       
R7M3             RES_0402-10.0,1%,1/16W,CHIP,G2A 1        SMB_DDR_KLM_SCL_G_R     
                                  2        SMB_DDR_KLM_SCL_G       
R7M4             RES_0402-20.0,1%,1/16W,CHIP,G2A 1        SMB_DDR_KLM_VPP_SCL_R   
                                  2        SMB_DDR_KLM_VPP_SCL     
R7M5             RES_0402-20.0,1%,1/16W,CHIP,G2A 1        SMB_DDR_KLM_VPP_SDA_R   
                                  2        SMB_DDR_KLM_VPP_SDA     
R7M6             RES_0402-665,1.0%,1/16W,CHIP,GA 1        PVPP_KLM                
                                  2        SMB_DDR_KLM_VPP_SDA_R   
R7M7             RES_0402-240,1.0%,1/16W,CHIP,GA 1        PVCCIO_CPU1             
                                  2        SMB_DDR_KLM_SDA_G       
R7M8             RES_0402-10.0,1%,1/16W,CHIP,G2A 1        SMB_DDR_KLM_SDA_G_R     
                                  2        SMB_DDR_KLM_SDA_G       
R7M9             RES_0402-64.9,1.0%,1/16W,CHIP,A 1        PVDDQ_KLM               
                                  2        PWRGD_CPU1_DRAMPWROK_KLM_G
R7P1             RES_0402-42.2,1.0%,1/16W,EMPTYA 1        CLK_100M_CPU1_BCLK2_DP  
                                  2        GND                     
R7P2             RES_0402-42.2,1.0%,1/16W,EMPTYA 1        CLK_100M_CPU1_BCLK2_DN  
                                  2        GND                     
R7P3             RES_0402-42.2,1.0%,1/16W,EMPTYA 1        CLK_100M_CPU1_PE_REFCLK_DP
                                  2        GND                     
R7P4             RES_0402-42.2,1.0%,1/16W,EMPTYA 1        CLK_100M_CPU1_PE_REFCLK_DN
                                  2        GND                     
R7P5             RES_0402-150.0,1%,1/16W,CHIP,GA 1        H_CPU1_MEMGHJ_MEMHOT_G_N
                                  2        PVCCIO_CPU1             
R7P6             RES_0402-42.2,1.0%,1/16W,EMPTYA 1        CLK_100M_CPU1_RC_REFCLK0_DP
                                  2        GND                     
R7P7             RES_0402-42.2,1.0%,1/16W,EMPTYA 1        CLK_100M_CPU1_RC_REFCLK0_DN
                                  2        GND                     
R7P8             RES_0402-49.9,1%,1/16W,CHIP,G2A 1        A_CPU1_PE3_RBIAS        
                                  2        GND                     
R7P9             RES_0402-42.2,1.0%,1/16W,EMPTYA 1        CLK_100M_CPU1_RC_REFCLK1_DP
                                  2        GND                     
R7P10            RES_0402-49.9,1%,1/16W,CHIP,G2A 1        A_CPU1_PE012_RBIAS      
                                  2        GND                     
R7P11            RES_0402-49.9,1%,1/16W,CHIP,G2A 1        A_CPU1_UPI2_RBIAS       
                                  2        GND                     
R7P12            RES_0402-42.2,1.0%,1/16W,EMPTYA 1        CLK_100M_CPU1_RC_REFCLK1_DN
                                  2        GND                     
R7P13            RES_0402-10.0K,1%,1/16W,CHIP,GA 1        GND                     
                                  2        PD_CPU1_MCP01_DMON      
R7P14            RES_0402-240,1.0%,1/16W,CHIP,GA 1        GND                     
                                  2        PD_CPU1_DMIMODE_OVERRIDE
R7P15            RES_0402-240,1.0%,1/16W,EMPTY,A 1        GND                     
                                  2        PD_CPU1_KSFC_DIS        
R7P16            RES_0402-90.9,1%,1/16W,CHIP,G2A 1        A_CPU1_GHJ_RCOMP0       
                                  2        GND                     
R7P17            RES_0402-90.9,1%,1/16W,CHIP,G2A 1        A_CPU1_GHJ_RCOMP1       
                                  2        GND                     
R7P18            RES_0402-150.0,1%,1/16W,CHIP,GA 1        PVCCIO_CPU0             
                                  2        H_CPU1_CATERR_G_N       
R7P19            RES_0402-100.0,1%,1/16W,CHIP,GA 1        A_CPU1_GHJ_RCOMP2       
                                  2        GND                     
R7P20            RES_0402-150.0,1%,1/16W,CHIP,GA 1        PVCCIO_CPU0             
                                  2        H_CPU1_FAST_WAKE_N      
R7P21            RES_0402-150.0,1%,1/16W,CHIP,GA 1        H_CPU1_MEMKLM_MEMHOT_G_N
                                  2        PVCCIO_CPU1             
R7P22            RES_0402-240,1.0%,1/16W,EMPTY,A 1        PVCCIO_CPU1             
                                  2        PU_CPU1_LEGACY_SKT      
R7P25            RES_0402-49.9,1%,1/16W,CHIP,G2A 1        H_PM_SYNC_GTL_R2        
                                  2        H_PM_SYNC_GTL           
R7P26            RES_0402-49.9,1%,1/16W,CHIP,G2A 1        H_PMSYNC_CLK_24M_CPU1   
                                  2        H_PMSYNC_CLK_24M        
R7P27            RES_0402-150.0,1%,1/16W,CHIP,GA 1        PVCCIO_CPU0             
                                  2        H_CPU1_MSMI_G_N         
R7P28            RES_0402-150.0,1%,1/16W,CHIP,GA 1        PVCCIO_CPU1             
                                  2        H_CPU1_PROCHOT_G_N      
R7P29            RES_0402-51.1,1.0%,1/16W,CHIP,A 1        XDP_CPU_TCK0            
                                  2        GND                     
R7P30            RES_0402-100.0,1%,1/16W,CHIP,GA 1        PVCCIO_CPU0             
                                  2        XDP_CPU_MBP0_N          
R7R1             RES_0402-51.1,1.0%,1/16W,CHIP,A 1        PVCCIO_CPU1             
                                  2        GND                     
R7U2             RES_0402-100.0,1%,1/16W,EMPTY,A 1        VSENSE_PVDDQ_GHJ_P      
                                  2        VSENSE_PVDDQ_GHJ_N      
R8A1             RES_0402-10.0,1%,1/16W,CHIP,G2A 1        VSENSE_PVNN_PCH_STBY_AVSP
                                  2        VR_PVNN_PCH_AVSP        
R8A2             RES_0402-2.67K,1%,1/16W,CHIP,GA 1        VR_PVNN_PCH_XADDR2      
                                  2        GND                     
R8A4             RES_0402-100.0K,1%,1/16W,CHIP,B 1        VR_FET_SW_P12V_STBY_PVDDQ_DEF
                                  2        VR_PVNN_PCH_VINSEN      
R8A5             RES_0402-1.00K,1%,1/16W,CHIP,GA 1        P3V3_STBY               
                                  2        IRQ_PVNN_PCH_VRHOT_N    
R8A6             RES_0402-1.00K,1%,1/16W,CHIP,GA 1        P3V3_STBY               
                                  2        PWRGD_PVNN_PCH_R        
R8A7             RES_0402-100.0K,1%,1/16W,EMPTYA 1        P3V3_STBY               
                                  2        VR_PVNN_PCH_VREN        
R8A8             RES_0402-20.0,1%,1/16W,CHIP,G2A 1        SMB_VR_STBY_LVC3_SDA    
                                  2        SMB_VR_SDA_PVNN_PCH     
R8A9             RES_0402-20.0,1%,1/16W,CHIP,G2A 1        SMB_VR_STBY_LVC3_SCL    
                                  2        SMB_VR_SCL_PVNN_PCH     
R8A10            RES_0402-5.11K,1%,1/16W,CHIP,GA 1        P3V3_STBY               
                                  2        PWRGD_P1V8_PCH_STBY_R   
R8A11            RES_0402-22.1,1.0%,1/16W,CHIP,A 1        PWRGD_P1V8_PCH_STBY_R   
                                  2        PWRGD_P1V8_PCH_STBY     
R8A12            RES_0603-475.0,1%,1/10W,CHIP,GA 1        P1V8_PCH_STBY           
                                  2        GND                     
R8A13            RES_0402-150.0,1%,1/16W,CHIP,GA 1        P1V05_PCH_STBY          
                                  2        XDP_TDI                 
R8A14            RES_0402-150.0,1%,1/16W,CHIP,GA 1        P1V05_PCH_STBY          
                                  2        XDP_TMS                 
R8B1             RES_0402-51.1,1.0%,1/16W,CHIP,A 1        XDP_PCH_TCK1            
                                  2        GND                     
R8B2             RES_0402-1.00K,1%,1/16W,CHIP,GA 1        XDP_TRST_N              
                                  2        GND                     
R8B3             RES_0402-4.75K,1%,1/16W,CHIP,GA 1        PVPP_ABC                
                                  2        FM_MODPRST_HFI0_CPU0_LVT2_N
R8B4             RES_0402-100.0K,1%,1/16W,CHIP,A 1        FM_CTNR_PS_ON           
                                  2        GND                     
R8B5             RES_0402-4.75K,1%,1/16W,CHIP,GA 1        PVPP_ABC                
                                  2        LED_HFI0_CPU0_N         
R8B6             RES_0402-1.8K,1%,1/16W,CHIP,G2A 1        PVPP_ABC                
                                  2        SMB_HFI0_CPU0_LVC2_SCL  
R8B7             RES_0402-1.8K,1%,1/16W,CHIP,G2A 1        PVPP_ABC                
                                  2        SMB_HFI0_CPU0_LVC2_SDA  
R8B8             RES_0402-4.75K,1%,1/16W,CHIP,GA 1        PVPP_ABC                
                                  2        RST_HFI0_CPU0_LVT2_N    
R8B9             RES_0402-113,1%,1/16W,CHIP,G21A 1        A_USB2_COMP             
                                  2        GND                     
R8B10            RES_0402-4.75K,1%,1/16W,CHIP,GA 1        PVPP_ABC                
                                  2        IRQ_HFI0_CPU0_LVT2_N    
R8B11            RES_0402-1.8K,1%,1/16W,CHIP,G2A 1        PVPP_ABC                
                                  2        SMB_HFI1_CPU0_LVC2_SCL  
R8B12            RES_0402-0.0,5%,1/16W,CHIP,G21A 1        VSENSE_P1V05_PCH_STBY_AVSN
                                  2        GND                     
R8B13            RES_0402-1.8K,1%,1/16W,CHIP,G2A 1        PVPP_ABC                
                                  2        SMB_HFI1_CPU0_LVC2_SDA  
R8B14            RES_0402-0.0,5%,1/16W,CHIP,G21A 1        VSENSE_P1V05_PCH_STBY_AVSP
                                  2        P1V05_PCH_STBY          
R8B15            RES_0402-100.0,1%,1/16W,EMPTY,A 1        VSENSE_P1V05_PCH_STBY_AVSP
                                  2        VSENSE_P1V05_PCH_STBY_AVSN
R8B16            RES_0402-4.75K,1%,1/16W,CHIP,GA 1        PVPP_ABC                
                                  2        RST_HFI1_CPU0_LVT2_N    
R8B17            RES_0402-4.75K,1%,1/16W,CHIP,GA 1        PVPP_ABC                
                                  2        IRQ_HFI1_CPU0_LVT2_N    
R8B18            RES_0402-4.75K,1%,1/16W,CHIP,GA 1        PVPP_ABC                
                                  2        LED_HFI1_CPU0_N         
R8B19            RES_0402-4.75K,1%,1/16W,CHIP,GA 1        PVPP_ABC                
                                  2        FM_MODPRST_HFI1_CPU0_LVT2_N
R8B20            RES_0402-10.0,1%,1/16W,CHIP,G2A 1        H_PMSYNC_CLK_24M_R      
                                  2        H_PMSYNC_CLK_24M        
R8B21            RES_0402-49.9,1%,1/16W,EMPTY,GA 1        H_PMSYNC_CLK_24M        
                                  2        GND                     
R8B23            RES_0402-1.00K,1%,1/16W,CHIP,GA 1        P3V3_STBY               
                                  2        FM_XRC_PRESENT_N        
R8B24            RES_0402-3.3K,5%,1/16W,CHIP,G2A 1        P3V3_STBY               
                                  2        SMB_SLOTX24_PCH_STBY_LVC3_SDA
R8B25            RES_0402-4.75K,1%,1/16W,CHIP,GA 1        P3V3_STBY               
                                  2        FM_BMC_HEARTBEAT_N      
R8B26            RES_0402-3.3K,5%,1/16W,CHIP,G2A 1        P3V3_STBY               
                                  2        SMB_SLOTX24_PCH_STBY_LVC3_SCL
R8B27            RES_0402-20.0,1%,1/16W,CHIP,G2A 1        SMB_SLOTX24_STBY_LVC3_SDA_R1
                                  2        SMB_SLOTX24_PCH_STBY_LVC3_SDA
R8B28            RES_0402-20.0,1%,1/16W,CHIP,G2A 1        SMB_SLOTX24_STBY_LVC3_SCL_R1
                                  2        SMB_SLOTX24_PCH_STBY_LVC3_SCL
R8B29            RES_0402-49.9,1%,1/16W,CHIP,G2A 1        SGPIO_PCH_SSATA_DOUT0   
                                  2        SGPIO_PCH_SSATA_DOUT0_R 
R8B30            RES_0402-1.00K,1%,1/16W,CHIP,GA 1        P3V3_STBY               
                                  2        FM_XRC_READY_N          
R8B31            RES_0402-4.75K,1%,1/16W,CHIP,GA 1        P3V3_STBY               
                                  2        FM_THROTTLE_N           
R8B32            RES_0402-10.0K,1%,1/16W,CHIP,GA 1        A_USB2_VBUS             
                                  2        GND                     
R8C1             RES_0402-4.75K,1%,1/16W,CHIP,GA 1        P3V3_STBY               
                                  2        FM_SLT_CFG1             
R8C2             RES_0402-4.75K,1%,1/16W,CHIP,GA 1        P3V3_STBY               
                                  2        IRQ_BMC_PCH_SCI_LPC_N   
R8C4             RES_0402-1.00K,1%,1/16W,CHIP,GA 1        P3V3_STBY               
                                  2        IRQ_BMC_PCH_SMI_LPC_N   
R8C6             RES_0402-4.75K,1%,1/16W,CHIP,GA 1        P3V3_STBY               
                                  2        FM_BIOS_POST_CMPLT_N    
R8C7             RES_0402-4.75K,1%,1/16W,CHIP,GA 1        P3V3_STBY               
                                  2        FM_SLT_CFG0             
R8C9             RES_0402-4.75K,1%,1/16W,CHIP,GA 1        P3V3_STBY               
                                  2        IRQ_SML0_ALERT_N        
R8C11            RES_0402-20.0,1%,1/16W,CHIP,G2A 1        SMB_SMLINK0_STBY_LVC3_SDA_R1
                                  2        SMB_SMLINK0_STBY_LVC3_SDA
R8C12            RES_0402-20.0,1%,1/16W,CHIP,G2A 1        SMB_SMLINK0_STBY_LVC3_SCL_R1
                                  2        SMB_SMLINK0_STBY_LVC3_SCL
R8C14            RES_0402-20.0,1%,1/16W,CHIP,G2A 1        SMB_HOST_STBY_LVC3_SCL_R1
                                  2        SMB_HOST_STBY_LVC3_SCL  
R8C15            RES_0402-2.0K,1%,1/16W,CHIP,G2A 1        P3V3_STBY               
                                  2        SMB_HOST_STBY_LVC3_SCL  
R8C16            RES_0402-2.0K,1%,1/16W,CHIP,G2A 1        P3V3_STBY               
                                  2        SMB_HOST_STBY_LVC3_SDA  
R8C17            RES_0402-1.00K,1%,1/16W,EMPTY,A 1        PU_PCH_TLS_ENABLE_STRAP 
                                  2        GND                     
R8C18            RES_0402-1.00K,1%,1/16W,CHIP,GA 1        P3V3_STBY               
                                  2        PU_PCH_TLS_ENABLE_STRAP 
R8C20            RES_0402-20.0,1%,1/16W,CHIP,G2A 1        SMB_HOST_STBY_LVC3_SDA_R1
                                  2        SMB_HOST_STBY_LVC3_SDA  
R8C21            RES_0402-100.0,1%,1/16W,CHIP,GA 1        A_RCOMP_3P3             
                                  2        GND                     
R8C23            RES_0402-0.0,5%,1/16W,EMPTY,G2A 1        FM_GBE_LOM_DISABLE_N    
                                  2        FM_10GBE_LOM_DISABLE_N  
R8C24            RES_0402-0.0,5%,1/16W,CHIP,G21A 1        FM_GBE_LOM_DISABLE_N    
                                  2        FM_1GB_LOM_DISABLE_N    
R8C25            RES_0402-4.75K,1%,1/16W,CHIP,GA 1        P3V3_STBY               
                                  2        IRQ_PCH_NIC_ALERT_N     
R8C26            RES_0402-100.0,1%,1/16W,CHIP,GA 1        A_1P8_3P3_RCOMP         
                                  2        GND                     
R8D3             RES_0402-20.0,1%,1/16W,CHIP,G2A 1        SMB_SENSOR_STBY_LVC3_SCL_R1
                                  2        SMB_SENSOR_PCH_STBY_LVC3_SCL
R8D4             RES_0402-20.0,1%,1/16W,CHIP,G2A 1        SMB_VR_STBY_LVC3_SCL_R1 
                                  2        SMB_VR_STBY_LVC3_SCL    
R8D5             RES_0402-1.00K,1%,1/16W,EMPTY,A 1        PU_ADR_TIMER_HOLD_OFF_N 
                                  2        GND                     
R8D6             RES_0402-20.0,1%,1/16W,CHIP,G2A 1        SMB_SENSOR_STBY_LVC3_SDA_R1
                                  2        SMB_SENSOR_PCH_STBY_LVC3_SDA
R8D7             RES_0402-20.0,1%,1/16W,CHIP,G2A 1        SMB_VR_STBY_LVC3_SDA_R1 
                                  2        SMB_VR_STBY_LVC3_SDA    
R8D11            RES_0402-33.2,1%,1/16W,CHIP,G2A 1        RMII_PCH_SPRNGVLLE_ARB_OUT
                                  2        RMII_PCH_SPRNGVLLE_ARB_OUT_R
R8D13            RES_0402-10.0K,1%,1/16W,CHIP,GA 1        P3V3_STBY               
                                  2        PU_ADR_TIMER_HOLD_OFF_N 
R8D14            RES_0402-4.75K,1%,1/16W,CHIP,GA 1        P3V3_STBY               
                                  2        FP_PWR_ID_LED_N         
R8D15            RES_0402-1.37K,1%,1/16W,CHIP,GA 1        P3V3_STBY               
                                  2        SMB_VR_STBY_LVC3_SCL    
R8D16            RES_0402-10.0K,1%,1/16W,EMPTY,A 1        P3V3_STBY               
                                  2        RMII_PCH_SPRNGVLLE_ARB_OUT
R8D17            RES_0402-1.37K,1%,1/16W,CHIP,GA 1        P3V3_STBY               
                                  2        SMB_VR_STBY_LVC3_SDA    
R8D19            RES_0402-49.9,1%,1/16W,CHIP,G2A 1        SGPIO_PCH_SATA_DOUT0    
                                  2        SGPIO_PCH_SATA_DOUT0_R  
R8D20            RES_0402-49.9,1%,1/16W,CHIP,G2A 1        SGPIO_PCH_SATA_LOAD     
                                  2        SGPIO_PCH_SATA_LOAD_R   
R8D21            RES_0402-1.00K,1%,1/16W,CHIP,GA 1        P3V3_STBY               
                                  2        FM_IE_DISABLE_N         
R8D22            RES_0402-33.2,1%,1/16W,CHIP,G2A 1        RST_BMC_SRST_R2_N       
                                  2        RST_BMC_SRST_N          
R8D23            RES_0402-20.0,1%,1/16W,CHIP,G2A 1        SMB_SENSOR_STBY_LVC3_SDA_R2
                                  2        SMB_SENSOR_STBY_LVC3_SDA
R8D24            RES_0402-20.0,1%,1/16W,CHIP,G2A 1        SMB_SENSOR_STBY_LVC3_SCL
                                  2        SMB_SENSOR_STBY_LVC3_SCL_R2
R8D25            RES_0402-4.75K,1%,1/16W,CHIP,GA 1        P3V3_STBY               
                                  2        RST_BMC_SRST_R2_N       
R8D26            RES_0402-4.75K,1%,1/16W,CHIP,GA 1        P3V3_STBY               
                                  2        IRQ_SML1_PMBUS_ALERT_BUF_N
R8D27            RES_0402-1.00K,1%,1/16W,CHIP,GA 1        PD_FRU_WP               
                                  2        GND                     
R8D28            RES_0402-1.00K,1%,1/16W,CHIP,GA 1        P3V3_STBY               
                                  2        PU_AT24C64_A2           
R8D29            RES_0402-4.75K,1%,1/16W,CHIP,GA 1        P3V3_STBY               
                                  2        IRQ_DIMM_SAVE_LVT3      
R8D30            RES_0402-10.0K,1%,1/16W,CHIP,GA 1        IRQ_DIMM_SAVE_N         
                                  2        IRQ_DIMM_SAVE_R_N       
R8D31            RES_0402-4.75K,1%,1/16W,CHIP,GA 1        P3V3_STBY               
                                  2        IRQ_DIMM_SAVE_LVT3_N    
R8D35            RES_0402-0.0,5%,1/16W,CHIP,G21A 1        SPI_PCH_TPM_CS_N        
                                  2        SPI_PCH_TPM_CS_R_N      
R8D36            RES_0402-33.2,1%,1/16W,CHIP,G2A 1        RST_BMC_SRST_R2_N       
                                  2        RST_BMC_DDR3_BUF_IN_N   
R8D37            RES_0402-4.75K,1%,1/16W,CHIP,GA 1        A_PG_P5V                
                                  2        GND                     
R8D38            RES_0402-100.0K,1%,1/16W,CHIP,A 1        P12V                    
                                  2        A_PG_P12V_MAIN          
R8D39            RES_0402-49.9K,1%,1/16W,CHIP,GA 1        P5V                     
                                  2        A_PG_P5V                
R8D40            RES_0402-3.74K,1%,1/16W,CHIP,GA 1        A_PG_P12V_MAIN          
                                  2        GND                     
R8D41            RES_0402-10.0K,1%,1/16W,CHIP,GA 1        P3V3_STBY               
                                  2        PWRGD_P12V_MAIN_R       
R8D42            RES_0402-100.0,1%,1/16W,CHIP,GA 1        PWRGD_P12V_MAIN_R       
                                  2        PWRGD_P12V_MAIN         
R8D43            RES_0402-0.0,5%,1/16W,CHIP,G21A 1        FM_156M_CPU0_BRD_OSC_EN 
                                  2        FM_CPU0_STL_BRD_OSC_EN  
R8D44            RES_0402-10.0K,1%,1/16W,CHIP,GA 1        P3V3_STBY               
                                  2        FM_CPU0_RC_EN           
R8E1             RES_0402-0.0,5%,1/16W,CHIP,G21A 1        IRQ_SPI_TPM_N_R         
                                  2        IRQ_PIRQA_SPI_TPM_N     
R8E2             RES_0402-1.00K,1%,1/16W,CHIP,GA 1        XDP_SPI_PCH_MOSI_BOOT_HALT_N
                                  2        SPI_PCH_MOSI            
R8E3             RES_0402-10.0K,1%,1/16W,CHIP,GA 1        P3V3_STBY               
                                  2        FM_TPM_PRES_N           
R8E4             RES_0402-1.00K,1%,1/16W,EMPTY,A 1        SPI_PCH_MOSI            
                                  2        GND                     
R8E5             RES_0402-33.2,1%,1/16W,CHIP,G2A 1        FM_CTNR_PS_ON_R         
                                  2        FM_CTNR_PS_ON           
R8E6             RES_0402-1.00K,1%,1/16W,EMPTY,A 1        P3V3_STBY               
                                  2        SPI_PCH_MOSI            
R8E7             RES_0402-22.1,1.0%,1/16W,CHIP,A 1        PWRGD_P12V_HSC_DLY_R    
                                  2        PWRGD_P12V_HSC_DLY      
R8E9             RES_0402-33.2,1%,1/16W,CHIP,G2A 1        SPI_PCH_CLK             
                                  2        SPI_PCH_TPM_CLK_R       
R8E10            RES_0402-33.2,1%,1/16W,CHIP,G2A 1        SPI_PCH_MOSI            
                                  2        SPI_PCH_TPM_MOSI_R      
R8E11            RES_0402-0.0,5%,1/16W,EMPTY,G2A 1        FM_MEM_THERM_EVENT_LVT3_N
                                  2        FM_ADR_SMI_GPIO_N       
R8E12            RES_0402-4.75K,1%,1/16W,EMPTY,A 1        P3V3_STBY               
                                  2        FM_CTNR_PS_ON           
R8E13            RES_0402-33.2,1%,1/16W,CHIP,G2A 1        SPI_PCH_MISO            
                                  2        SPI_PCH_TPM_MISO_R      
R8E14            RES_0402-4.75K,1%,1/16W,CHIP,GA 1        P3V3_STBY               
                                  2        RST_PLTRST_TOP_SWAP     
R8E16            RES_0402-20.0K,1%,1/16W,CHIP,GA 1        FM_BIOS_TOP_SWAP        
                                  2        GND                     
R8E17            RES_0402-33.2,1%,1/16W,CHIP,G2A 1        IRQ_LVC3_WAKE_R_N       
                                  2        IRQ_LVC3_WAKE_N         
R8E18            RES_0402-1.0K,0.1%,1/16W,CHIP,A 1        P5V_STBY                
                                  2        GND                     
R8E19            RES_0402-4.75K,1%,1/16W,EMPTY,A 1        P3V3_STBY               
                                  2        FM_BIOS_TOP_SWAP        
R8E20            RES_0402-33.2,1%,1/16W,CHIP,G2A 1        FM_BIOS_TOP_SWAP_SPKR_R 
                                  2        FM_BIOS_TOP_SWAP_SPKR   
R8E21            RES_0402-0.0,5%,1/16W,CHIP,G21A 1        FM_PE_SPRV_WAKE_N       
                                  2        FM_ALL_WAKE_N           
R8E22            RES_0402-4.75K,1%,1/16W,CHIP,GA 1        P3V3_STBY               
                                  2        IRQ_BMC_PCH_NMI_STBY_N  
R8E23            RES_0402-4.75K,1%,1/16W,CHIP,GA 1        PU_TRI_STATE_EN         
                                  2        P3V3_STBY               
R8E24            RES_0402-33.2,1%,1/16W,CHIP,G2A 1        IRQ_BMC_PCH_NMI_STBY_N  
                                  2        IRQ_BMC_PCH_NMI_STBY_R_N
R8E25            RES_0402-0.0,5%,1/16W,CHIP,G21A 1        P3V3_STBY               
                                  2        VSENSE_P3V3_STBY        
R8E26            RES_0402-0.0,5%,1/16W,CHIP,G21A 1        FM_PE_OCP_WAKE_N        
                                  2        FM_ALL_WAKE_N           
R8E27            RES_0402-0.0,5%,1/16W,CHIP,G21A 1        FM_PE_M2_WAKE_N         
                                  2        FM_ALL_WAKE_N           
R8E28            RES_0402-0.0,5%,1/16W,CHIP,G21A 1        FM_PE_SLOTX24_WAKE_N    
                                  2        FM_ALL_WAKE_N           
R8E29            RES_0402-0.0,5%,1/16W,EMPTY,G2A 1        FM_PE_BMC_WAKE_N        
                                  2        FM_ALL_WAKE_N           
R8E30            RES_0402-10.0K,1%,1/16W,CHIP,GA 1        P3V3_STBY               
                                  2        FM_ALL_WAKE_N           
R8E31            RES_0402-23.2K,1%,1/16W,CHIP,GA 1        VSENSE_P3V3_STBY        
                                  2        VSENSE_VOUT_P3V3_STBY   
R8E32            RES_0402-4.75K,1%,1/16W,CHIP,GA 1        P3V3_STBY               
                                  2        FP_NMI_BTN_OUT_R_N      
R8E33            RES_0402-0.0,5%,1/16W,CHIP,G21A 1        PWRGD_P12V_HSC_DLY      
                                  2        VR_P5V_STBY_EN          
R8E34            RES_0402-10.0K,1%,1/16W,CHIP,GA 1        VSENSE_VOUT_P3V3_STBY   
                                  2        AGND_P3V3_STBY          
R8E35            RES_0402-0.0,5%,1/16W,CHIP,G21A 1        VR_P3V3_STBY_BOOT       
                                  2        VR_P3V3_STBY_BOOT_R     
R8E36            RES_0402-10.0K,1%,1/16W,CHIP,GA 1        P3V3_STBY               
                                  2        FM_PE_SLOTX24_WAKE_N    
R8E37            RES_0402-0.0,5%,1/16W,CHIP,G21A 1        VR_P5V_STBY_VSENSE_R    
                                  2        P5V_STBY                
R8E38            RES_0402-0.0,5%,1/16W,CHIP,G21A 1        VSENSE_RGND_P3V3_STBY   
                                  2        AGND_P3V3_STBY          
R8E39            RES_0402-24.9K,1%,1/16W,CHIP,GA 1        VR_P5V_STBY_COMP        
                                  2        VR_P5V_STBY_RC_COMP     
R8E40            RES_0402-100.0K,1%,1/16W,EMPTYA 1        P3V3_STBY               
                                  2        VR_P3V3_STBY_EN         
R8F1             RES_0402-10.0K,1%,1/16W,EMPTY,A 1        PWRGD_P5V_STBY          
                                  2        GND                     
R8F2             RES_0402-0.0,5%,1/16W,CHIP,G21A 1        PWRGD_P5V_STBY          
                                  2        VR_P3V3_STBY_EN         
R8F3             RES_0402-2.2,5%,1/16W,EMPTY,G2A 1        VR_P3V3_STBY_SNUB       
                                  2        GND                     
R8F5             RES_0402-1.00K,1%,1/16W,CHIP,GA 1        P3V3_STBY               
                                  2        PWRGD_P3V3_STBY_R       
R8F6             RES_0402-0.0,5%,1/16W,CHIP,G21A 1        SPI_PCH_MISO            
                                  2        SPI_PCH_MISO_R          
R8F7             RES_0402-33.2,1%,1/16W,CHIP,G2A 1        SPI_SWITCH_CLK          
                                  2        SPI_CLK_R1              
R8F8             RES_0402-33.2,1%,1/16W,CHIP,G2A 1        SPI_SWITCH_CLK          
                                  2        SPI_CLK_R0              
R8F9             RES_0402-64.9K,1%,1/16W,CHIP,GA 1        VR_P3V3_STBY_OCSELECT   
                                  2        AGND_P3V3_STBY          
R8F10            RES_0402-22.1,1.0%,1/16W,CHIP,A 1        PWRGD_P3V3_STBY_R       
                                  2        PWRGD_P3V3_STBY         
R8F11            RES_0402-0.0,5%,1/16W,CHIP,G21A 1        GND                     
                                  2        AGND_P3V3_STBY          
R8F12            RES_0402-33.2,1%,1/16W,CHIP,G2A 1        SPI_BMC_BT_DI           
                                  2        SPI_BMC_BT_DI_R         
R8F13            RES_0402-4.75K,1%,1/16W,CHIP,GA 1        P3V3_STBY               
                                  2        SPI_BMC_BT_CS_N         
R8F14            RES_0402-4.75K,1%,1/16W,CHIP,GA 1        P3V3_STBY               
                                  2        PU_SPI_BMC_BT_HOLD_N    
R8F16            RES_0402-4.75K,1%,1/16W,EMPTY,A 1        P3V3_STBY               
                                  2        PU_SPI_FLASH_RESET_2_N  
R8F18            RES_0402-0.0,5%,1/16W,CHIP,G21A 1        P3E_PCH_RX_0_DP         
                                  2        P3E_PCH_M2_SATA6G_RX_R_DP
R8F21            RES_0402-0.0,5%,1/16W,CHIP,G21A 1        P3E_PCH_RX_0_DN         
                                  2        P3E_PCH_M2_SATA6G_RX_R_DN
R8F23            RES_0402-2.21K,1%,1/16W,CHIP,GA 1        P3V3_STBY               
                                  2        IRQ_MEZZ_LAN_ALERT_N    
R8F24            RES_0402-4.75K,1%,1/16W,CHIP,GA 1        P3V3_STBY               
                                  2        FP_NMI_BTN_N            
R8F25            RES_0402-475.0,1%,1/16W,CHIP,GA 1        A_COMP_CKMNG            
                                  2        GND                     
R8F26            RES_0402-10.0K,1%,1/16W,CHIP,GA 1        P3V3_STBY               
                                  2        FM_PCH_PWRBTN_R_N       
R8F27            RES_0402-22.1,1.0%,1/16W,CHIP,A 1        CLK_32K_SUSCLK_PLD_R    
                                  2        CLK_32K_SUSCLK_PLD      
R8F28            RES_0402-22.1,1.0%,1/16W,CHIP,A 1        RMII_BMC_OCP_TXD1_R     
                                  2        RMII_BMC_OCP_TXD1       
R8F29            RES_0402-33.2,1%,1/16W,CHIP,G2A 1        CLK_25M_BMC_R           
                                  2        CLK_25M_BMC             
R8F30            RES_0402-22.1,1.0%,1/16W,CHIP,A 1        RMII_BMC_OCP_TXEN_R     
                                  2        RMII_BMC_OCP_TXEN       
R8F31            RES_0402-22.1,1.0%,1/16W,CHIP,A 1        RMII_BMC_OCP_TXD0_R     
                                  2        RMII_BMC_OCP_TXD0       
R8F32            RES_0402-10.0K,1%,1/16W,CHIP,GA 1        P3V3_STBY               
                                  2        RMII_BMC_PCH_SPRNGVLLE_TXD1
R8F33            RES_0402-22.1,1.0%,1/16W,CHIP,A 1        RMII_BMC_SPRNGVLLE_TXEN_R
                                  2        RMII_BMC_PCH_SPRNGVLLE_TXEN
R8F34            RES_0402-4.75K,1%,1/16W,CHIP,GA 1        P3V3_STBY               
                                  2        PU_SPI_BMC_BT_WP_N      
R8F35            RES_0402-1.00K,1%,1/16W,EMPTY,A 1        PU_SPI_BMC_BT_WP_N      
                                  2        GND                     
R8F36            RES_0402-10.0K,1%,1/16W,CHIP,GA 1        P3V3                    
                                  2        PU_M2_CLK_REQ_N         
R8F37            RES_0402-0.0,5%,1/16W,EMPTY,G2A 1        FM_CPU_ERR0_LVT3_N      
                                  2        FM_CPU_ERR0_PCH_N       
R8F38            RES_0402-0.0,5%,1/16W,CHIP,G21A 1        FM_CPU_ERR0_LVT3_N      
                                  2        FM_CPU_ERR0_LVT3_BMC_N  
R8G1             RES_0402-33.2,1%,1/16W,CHIP,G2A 1        CLK_50M_CKMNG_BMC_2_R   
                                  2        CLK_50M_CKMNG_BMC_2     
R8G2             RES_0402-4.75K,1%,1/16W,CHIP,GA 1        P3V3_STBY               
                                  2        FM_PCH_PWRBTN_OUT_N     
R8G3             RES_0402-2.26K,1.0%,1/16W,EMPTA 1        P3V3_STBY               
                                  2        SMB_OCP_LAN_STBY_LVC3_SCL_R
R8G4             RES_0402-20.0,1%,1/16W,CHIP,G2A 1        SMB_OCP_LAN_STBY_LVC3_SCL_R
                                  2        SMB_OCP_LAN_STBY_LVC3_SCL
R8G5             RES_0402-20.0,1%,1/16W,CHIP,G2A 1        SMB_OCP_LAN_STBY_LVC3_SDA_R
                                  2        SMB_OCP_LAN_STBY_LVC3_SDA
R8G6             RES_0402-2.26K,1.0%,1/16W,EMPTA 1        P3V3_STBY               
                                  2        SMB_OCP_LAN_STBY_LVC3_SDA_R
R8G7             RES_0402-0.0,5%,1/16W,CHIP,G21A 1        JTAG_PLD_TDI            
                                  2        JTAG_TDI                
R8G8             RES_0402-0.0,5%,1/16W,CHIP,G21A 1        JTAG_BMC_TDI            
                                  2        JTAG_TDI                
R8G9             RES_0402-0.0,5%,1/16W,EMPTY,G2A 1        JTAG_PCH_GBE_TRST_N     
                                  2        JTAG_TRST_N             
R8G10            RES_0402-0.0,5%,1/16W,CHIP,G21A 1        JTAG_BMC_TRST_N         
                                  2        JTAG_TRST_N             
R8G11            RES_0402-0.0,5%,1/16W,EMPTY,G2A 1        JTAG_PCH_PLD_TMS        
                                  2        JTAG_TMS                
R8G12            RES_0402-0.0,5%,1/16W,EMPTY,G2A 1        JTAG_PCH_GBE_TMS        
                                  2        JTAG_TMS                
R8G13            RES_0402-0.0,5%,1/16W,CHIP,G21A 1        JTAG_PLD_TMS            
                                  2        JTAG_TMS                
R8G14            RES_0402-0.0,5%,1/16W,CHIP,G21A 1        JTAG_BMC_TMS            
                                  2        JTAG_TMS                
R8G15            RES_0402-0.0,5%,1/16W,EMPTY,G2A 1        JTAG_PCH_GBE_CLK        
                                  2        JTAG_TCK                
R8G16            RES_0402-0.0,5%,1/16W,EMPTY,G2A 1        JTAG_PCH_PLD_TCK        
                                  2        JTAG_TCK                
R8G17            RES_0402-0.0,5%,1/16W,CHIP,G21A 1        JTAG_BMC_TCK            
                                  2        JTAG_TCK                
R8G18            RES_0402-0.0,5%,1/16W,CHIP,G21A 1        JTAG_PLD_TCK            
                                  2        JTAG_TCK                
R8G19            RES_0402-0.0,5%,1/16W,CHIP,G21A 1        JTAG_TDI                
                                  2        JTAG_TDI_R              
R8G20            RES_0402-10.0K,1%,1/16W,CHIP,GA 1        P3V3_STBY               
                                  2        JTAG_TMS_R              
R8G21            RES_0402-0.0,5%,1/16W,CHIP,G21A 1        JTAG_TMS                
                                  2        JTAG_TMS_R              
R8G22            RES_0402-0.0,5%,1/16W,CHIP,G21A 1        JTAG_TCK                
                                  2        JTAG_TCK_R              
R8G23            RES_0402-4.75K,1%,1/16W,CHIP,GA 1        JTAG_TCK_R              
                                  2        GND                     
R8G24            RES_0402-33.2,1%,1/16W,CHIP,G2A 1        CLK_50M_CKMNG_PCH_10GBE_R
                                  2        CLK_50M_CKMNG_PCH_10GBE 
R8G25            RES_0402-33.2,1%,1/16W,CHIP,G2A 1        CLK_50M_CKMNG_SPRVLLE_R 
                                  2        CLK_50M_CKMNG_SPRVLLE   
R8N1             RES_0402-1.8K,1%,1/16W,CHIP,G2A 1        P3V3_STBY               
                                  2        FM_CPU1_PROC_ID1        
R8N2             RES_0402-10.0K,1%,1/16W,CHIP,GA 1        P3V3_STBY               
                                  2        FM_CPU1_PKGID0          
R8N3             RES_0402-10.0K,1%,1/16W,CHIP,GA 1        P3V3_STBY               
                                  2        FM_CPU1_PKGID2          
R8N4             RES_0402-1.8K,1%,1/16W,CHIP,G2A 1        P3V3_STBY               
                                  2        FM_CPU1_PROC_ID0        
R8N5             RES_0402-10.0K,1%,1/16W,CHIP,GA 1        P3V3_STBY               
                                  2        FM_CPU1_PKGID1          
R8P1             RES_0402-49.9,1%,1/16W,CHIP,G2A 1        PD_CPU1_TEST14          
                                  2        GND                     
R8P2             RES_0402-49.9,1%,1/16W,CHIP,G2A 1        PD_CPU1_TEST13          
                                  2        GND                     
R8P3             RES_0402-49.9,1%,1/16W,CHIP,G2A 1        PD_CPU1_RSVD_TEST_2     
                                  2        GND                     
R8R1             RES_0402-49.9,1%,1/16W,CHIP,G2A 1        PD_CPU1_RSVD_TEST_1     
                                  2        GND                     
R9A1             RES_0402-1.00K,1%,1/16W,EMPTY,A 1        P3V3                    
                                  2        XDP_CPU_TCK_BUF         
R9A2             RES_0402-33.2,1%,1/16W,EMPTY,GA 1        XDP_PCH_CPU_TCK0        
                                  2        XDP_CPU_GTL_TCK_R2      
R9A3             RES_0402-0.0,5%,1/16W,CHIP,G21A 1        XDP_PCH_CPU_TCK0        
                                  2        XDP_CPU_TCK0            
R9A4             RES_0402-475.0,1%,1/16W,CHIP,GA 1        XDP_PRESENT_N           
                                  2        PVCCIO_CPU0             
R9A5             RES_0402-20.0K,1%,1/16W,CHIP,GA 1        P5V_STBY                
                                  2        FM_UART_SWITCH_N        
R9A6             RES_0402-20.0K,1%,1/16W,EMPTY,A 1        P5V_STBY                
                                  2        SPA_5V_SIN_SW           
R9A7             RES_0402-2.21K,1%,1/16W,CHIP,GA 1        P3V3_STBY               
                                  2        SPA_SIN_SW_R            
R9A8             RES_0402-0.0,5%,1/16W,CHIP,G21A 1        SPA_SIN_SW_R            
                                  2        SPA_MID_DBG_RX          
R9A9             RES_0402-100.0,1%,1/16W,CHIP,GA 1        RST_SYSTEM_BTN_BUF_N    
                                  2        RST_SYSTEM_BTN_N        
R9A11            RES_0402-150.0,1%,1/16W,CHIP,GA 1        P1V05_PCH_STBY          
                                  2        XDP_TDO                 
R9A12            RES_0402-2.21K,1%,1/16W,CHIP,GA 1        FM_PCH_SATA_RAID_KEY_R  
                                  2        P3V3_STBY               
R9A13            RES_0402-33.2,1%,1/16W,CHIP,G2A 1        FM_PCH_SATA_RAID_KEY_R  
                                  2        FM_PCH_SATA_RAID_KEY    
R9A14            RES_0402-1.00K,1%,1/16W,CHIP,GA 1        XDP_RST_CO_N            
                                  2        P3V3_STBY               
R9A15            RES_0402-1.00K,1%,1/16W,CHIP,GA 1        RST_RSMRST_N            
                                  2        XDP_RSMRST_N            
R9A16            RES_0402-2.21K,1%,1/16W,CHIP,GA 1        PU_KEY_CONN_PIN2_R      
                                  2        P3V3_STBY               
R9A17            RES_0402-1.00K,1%,1/16W,CHIP,GA 1        XDP_ITP_PMODE           
                                  2        P1V05_PCH_STBY          
R9A18            RES_0402-4.75K,1%,1/16W,CHIP,GA 1        P3V3_STBY               
                                  2        FM_PWR_LED              
R9A20            RES_0402-221,1.0%,1/16W,CHIP,GA 1        FM_PWR_LED_A            
                                  2        P3V3_STBY               
R9A21            RES_0402-4.75K,1%,1/16W,CHIP,GA 1        P3V3_STBY               
                                  2        FM_PWR_LED_N            
R9B4             RES_0402-49.9,1%,1/16W,CHIP,G2A 1        ISENSE_TMP421_1_E       
                                  2        ISENSE_TMP421_1_DXP     
R9B5             RES_0402-49.9,1%,1/16W,CHIP,G2A 1        ISENSE_TMP421_1_BC      
                                  2        ISENSE_TMP421_1_DXN     
R9B6             RES_0402-1.00K,1%,1/16W,CHIP,GA 1        P3V3_STBY               
                                  2        PU_TMP421_1_A1          
R9B7             RES_0402-100.0,1%,1/16W,CHIP,GA 1        GND                     
                                  2        FM_MEZZA_PRSNT1_N       
R9B8             RES_0402-1.00K,1%,1/16W,CHIP,GA 1        PD_TMP421_1_A0          
                                  2        GND                     
R9B9             RES_0402-1.00K,1%,1/16W,CHIP,GA 1        JTAG_MCP_TCK            
                                  2        GND                     
R9B10            RES_0402-49.9,1%,1/16W,CHIP,G2A 1        JTAG_MCP_TCK            
                                  2        JTAG_MCP_TCK_R          
R9B11            RES_0402-0.0,5%,1/16W,CHIP,G21A 1        JTAG_MCP_TCK            
                                  2        JTAG_MCP_TCK_R          
R9B12            RES_0402-1.00K,1%,1/16W,CHIP,GA 1        P1V8_MCP_CPU0           
                                  2        JTAG_MCP_MUX_TDO        
R9B13            RES_0402-0.0,5%,1/16W,CHIP,G21A 1        JTAG_MCP_TMS            
                                  2        JTAG_MCP_TMS_R          
R9B14            RES_0402-1.00K,1%,1/16W,CHIP,GA 1        PWRGD_CPU0_G            
                                  2        PWRGD_CPU0_G_R          
R9E1             RES_0402-10.0K,1%,1/16W,CHIP,GA 1        P3V3_STBY               
                                  2        PU_JTAG_SPRV_TDI        
R9E2             RES_0402-10.0K,1%,1/16W,CHIP,GA 1        P3V3_STBY               
                                  2        PU_JTAG_SPRV_TCK        
R9E3             RES_0402-10.0K,1%,1/16W,CHIP,GA 1        P3V3_STBY               
                                  2        PU_JTAG_SPRV_TMS        
R9E4             RES_0402-10.0K,1%,1/16W,CHIP,GA 1        P3V3_STBY               
                                  2        RST_PLTRST_SPRV_R_N     
R9E5             RES_0402-33.2,1%,1/16W,CHIP,G2A 1        SPI_NIC_CS_R_N          
                                  2        SPI_NIC_CS_N            
R9E6             RES_0402-33.2,1%,1/16W,CHIP,G2A 1        SPI_NIC_MISO_R          
                                  2        SPI_NIC_MISO            
R9E7             RES_0402-3.32K,1%,1/16W,CHIP,GA 1        P3V3_STBY               
                                  2        IRQ_LOM_ALERT_N         
R9E8             RES_0402-33.2,1%,1/16W,CHIP,G2A 1        SPI_NIC_SCLK_R          
                                  2        SPI_NIC_SCLK            
R9E9             RES_0402-33.2,1%,1/16W,CHIP,G2A 1        SPI_NIC_MOSI_R          
                                  2        SPI_NIC_MOSI            
R9E10            RES_0402-200.0,1%,1/16W,CHIP,GA 1        RST_PCIE_CPU_DEV1_R_N   
                                  2        RST_PCIE_CPU_DEV1_N     
R9E11            RES_0402-200.0,1%,1/16W,CHIP,GA 1        RST_PCIE_CPU_DEV2_R_N   
                                  2        RST_PCIE_CPU_DEV2_N     
R9E12            RES_0402-200.0,1%,1/16W,CHIP,GA 1        RST_PCIE_CPU_DEV3_R_N   
                                  2        RST_PCIE_CPU_DEV3_N     
R9E13            RES_0402-10.0K,1%,1/16W,CHIP,GA 1        RMII_BMC_PCH_SPRNGVLLE_TXEN
                                  2        GND                     
R9E14            RES_0402-0.0,5%,1/16W,CHIP,G21A 1        RST_BMC_SRST_N          
                                  2        FM_BMC_ENABLE_N         
R9E15            RES_0402-0.0,5%,1/16W,EMPTY,G2A 1        FM_ROMA<0>              
                                  2        FM_BMC_ENABLE_N         
R9E16            RES_0402-33.2,1%,1/16W,CHIP,G2A 1        RMII_PCH_SPRNGVLLE_ARB_IN_R
                                  2        RMII_PCH_SPRNGVLLE_ARB_IN
R9E17            RES_0402-22.1,1.0%,1/16W,CHIP,A 1        RMII_SPRNGVLLE_BMC_PCH_RXD0_R
                                  2        RMII_SPRNGVLLE_BMC_PCH_RXD0
R9E18            RES_0402-0.0,5%,1/16W,CHIP,G21A 1        XTAL_25MHZ_OUT_R        
                                  2        XTAL_25MHZ_OUT          
R9E19            RES_0402-22.1,1.0%,1/16W,CHIP,A 1        RMII_SPRNGVLLE_BMC_PCH_RXD1_R
                                  2        RMII_SPRNGVLLE_BMC_PCH_RXD1
R9E20            RES_0402-0.0,5%,1/16W,CHIP,G21A 1        XTAL_25MHZ_IN           
                                  2        XTAL_25MHZ_IN_R         
R9E21            RES_0402-4.75K,1%,1/16W,CHIP,GA 1        P3V3_STBY               
                                  2        FM_HEARTBEAT_LED        
R9E22            RES_0402-10.0K,1%,1/16W,CHIP,GA 1        PU_JTAG_SPRV_TDO        
                                  2        P3V3_STBY               
R9E23            RES_0402-4.99K,1%,1/16W,CHIP,GA 1        PD_SPRV_RSET            
                                  2        GND                     
R9E24            RES_0402-221,1.0%,1/16W,CHIP,GA 1        FM_HEARTBEAT_LED_A      
                                  2        P3V3_STBY               
R9F1             RES_0402-22.1,1.0%,1/16W,CHIP,A 1        RMII_BMC_PCH_SPRNGVLLE_CRSDV_R
                                  2        RMII_BMC_PCH_SPRNGVLLE_CRSDV
R9F3             RES_0402-4.75K,1%,1/16W,CHIP,GA 1        P3V3_STBY               
                                  2        FM_FAST_PROCHOT_EN      
R9F4             RES_0402-100.0K,1%,1/16W,CHIP,A 1        RST_PLTRST_BUF_N        
                                  2        GND                     
R9F5             RES_0402-3.32K,1%,1/16W,CHIP,GA 1        P3V3_STBY               
                                  2        PU_SPRV_LAN_PWR_GOOD    
R9F6             RES_0402-5.76K,1%,1/16W,CHIP,GA 1        P1V26_BMC_STBY          
                                  2        VR_P1V26_BMC_STBY_FB    
R9F7             RES_0402-0.0,5%,1/16W,CHIP,G21A 1        RST_PLTRST_BUF_N        
                                  2        RST_BMC_LVC3_N          
R9F8             RES_0402-10.0K,1%,1/16W,CHIP,GA 1        GND                     
                                  2        VR_P1V26_BMC_STBY_FB    
R9F9             RES_0402-4.75K,1%,1/16W,CHIP,GA 1        FM_ROMA<14>             
                                  2        P3V3_STBY               
R9F10            RES_0402-4.75K,1%,1/16W,EMPTY,A 1        FM_ROMA<6>              
                                  2        P3V3_STBY               
R9F11            RES_0402-22.1,1.0%,1/16W,CHIP,A 1        PWRGD_P1V26_BMC_STBY_R  
                                  2        PWRGD_P1V26_BMC_STBY    
R9F12            RES_0402-10.0K,1%,1/16W,CHIP,GA 1        P3V3_STBY               
                                  2        PWRGD_P1V538_BMC_STBY_R 
R9F13            RES_0402-10.0K,1%,1/16W,CHIP,GA 1        P3V3_STBY               
                                  2        PWRGD_P1V26_BMC_STBY_R  
R9F14            RES_0402-4.75K,1%,1/16W,CHIP,GA 1        FM_ROMA<19>             
                                  2        P3V3_STBY               
R9F15            RES_0402-4.75K,1%,1/16W,CHIP,GA 1        FM_ROMA<8>              
                                  2        P3V3_STBY               
R9F16            RES_0402-4.75K,1%,1/16W,CHIP,GA 1        FM_ROMA<10>             
                                  2        P3V3_STBY               
R9F17            RES_0402-4.75K,1%,1/16W,EMPTY,A 1        FM_ROMA<20>             
                                  2        P3V3_STBY               
R9F18            RES_0402-4.75K,1%,1/16W,EMPTY,A 1        FM_ROMA<4>              
                                  2        P3V3_STBY               
R9F19            RES_0402-4.75K,1%,1/16W,EMPTY,A 1        FM_ROMA<3>              
                                  2        P3V3_STBY               
R9F20            RES_0402-348,1%,1/16W,EMPTY,G2A 1        PECI_BMC                
                                  2        GND                     
R9F21            RES_0402-33.2,1%,1/16W,CHIP,G2A 1        SPI_BMC_BT_CLK_R        
                                  2        SPI_BMC_BT_CLK          
R9F22            RES_0402-20.0,1%,1/16W,CHIP,G2A 1        SMB_LAN_STBY_LVC3_SCL_R 
                                  2        SMB_LAN_STBY_LVC3_SCL   
R9F23            RES_0402-20.0,1%,1/16W,CHIP,G2A 1        SMB_LAN_STBY_LVC3_SDA_R 
                                  2        SMB_LAN_STBY_LVC3_SDA   
R9F24            RES_0402-0.0,5%,1/16W,EMPTY,G2A 1        SPA_MID_DBG_RX          
                                  2        SP2_BMC_CM_UART_RX      
R9F25            RES_0402-100.0,1%,1/16W,CHIP,GA 1        SPA_MID_DBG_RX          
                                  2        UART_MUX_IN_R           
R9F26            RES_0402-0.0,5%,1/16W,EMPTY,G2A 1        SP2_BMC_CM_UART_TX      
                                  2        SPA_MID_DBG_TX          
R9F27            RES_0402-0.0,5%,1/16W,CHIP,G21A 1        UART_MUX_OUT_R          
                                  2        SPA_MID_DBG_TX          
R9F28            RES_0402-221,1.0%,1/16W,CHIP,GA 1        P3V3_STBY               
                                  2        FM_RED_LED_ANODE        
R9F29            RES_0402-4.75K,1%,1/16W,CHIP,GA 1        P1V538_BMC_STBY         
                                  2        RST_BMC_DDR3_R_N        
R9F30            RES_0402-4.75K,1%,1/16W,CHIP,GA 1        P3V3_STBY               
                                  2        FM_BMC_FAULT_LED_N      
R9F31            RES_0402-12K,1%,1/16W,CHIP,G21A 1        P1V538_BMC_STBY         
                                  2        VR_P1V538_BMC_STBY_FB   
R9F32            RES_0402-13K,1.0%,1/16W,CHIP,GA 1        GND                     
                                  2        VR_P1V538_BMC_STBY_FB   
R9F33            RES_0402-0.0,5%,1/16W,CHIP,G21A 1        PECI_BMC                
                                  2        PECI_BMC_R              
R9F34            RES_0402-33.2,1%,1/16W,CHIP,G2A 1        RST_BMC_DDR3_R_N        
                                  2        RST_BMC_DDR3_N          
R9F35            RES_0402-4.75K,1%,1/16W,CHIP,GA 1        FM_ROMA<15>             
                                  2        P3V3_STBY               
R9F36            RES_0402-4.75K,1%,1/16W,EMPTY,A 1        FM_ROMA<22>             
                                  2        P3V3_STBY               
R9F37            RES_0402-4.75K,1%,1/16W,EMPTY,A 1        FM_ROMA<11>             
                                  2        P3V3_STBY               
R9F38            RES_0402-4.75K,1%,1/16W,EMPTY,A 1        FM_ROMA<7>              
                                  2        P3V3_STBY               
R9F39            RES_0402-4.75K,1%,1/16W,EMPTY,A 1        FM_ROMA<2>              
                                  2        P3V3_STBY               
R9F40            RES_0402-4.75K,1%,1/16W,CHIP,GA 1        FM_ROMA<1>              
                                  2        P3V3_STBY               
R9F41            RES_0402-33.2,1%,1/16W,CHIP,G2A 1        SPI_BMC_BT_DO_R         
                                  2        SPI_BMC_BT_DO           
R9F42            RES_0402-100.0K,1%,1/16W,CHIP,A 1        P2E_SSB_BMC_TX_C_DP     
                                  2        GND                     
R9F43            RES_0402-100.0K,1%,1/16W,CHIP,A 1        P2E_SSB_BMC_TX_C_DN     
                                  2        GND                     
R9F44            RES_0402-100.0K,1%,1/16W,CHIP,A 1        CLK_100M_BMC_PE_R_DN    
                                  2        GND                     
R9F45            RES_0402-100.0K,1%,1/16W,CHIP,A 1        CLK_100M_BMC_PE_R_DP    
                                  2        GND                     
R9F46            RES_0402-100.0K,1%,1/16W,CHIP,A 1        FM_PE_BMC_WAKE_N        
                                  2        GND                     
R9F47            RES_0402-4.75K,1%,1/16W,CHIP,GA 1        P3V3_STBY               
                                  2        PU_PI7C9X1172_I2C_SPI_N 
R9F48            RES_0402-4.75K,1%,1/16W,EMPTY,A 1        P3V3_STBY               
                                  2        FM_PI7C9X1172_A1        
R9F49            RES_0402-4.75K,1%,1/16W,EMPTY,A 1        P3V3_STBY               
                                  2        FM_PI7C9X1172_A0        
R9F50            RES_0402-1.00K,1%,1/16W,CHIP,GA 1        FM_PI7C9X1172_A1        
                                  2        GND                     
R9F51            RES_0402-1.00K,1%,1/16W,CHIP,GA 1        FM_PI7C9X1172_A0        
                                  2        GND                     
R9F52            RES_0402-4.75K,1%,1/16W,CHIP,GA 1        P3V3_STBY               
                                  2        FM_BMC_FAULT_LED        
R9F53            RES_0402-0.0,5%,1/16W,CHIP,G21A 1        UART_BMC_RXD5           
                                  2        UART_BRIDGE_RXD5        
R9F54            RES_0402-0.0,5%,1/16W,CHIP,G21A 1        SP1_BMC_HOST_UART_RX    
                                  2        SP1_HOST_BRIDGE_UART_RX 
R9F55            RES_0402-4.75K,1%,1/16W,CHIP,GA 1        P3V3_STBY               
                                  2        FM_UART_ALERT_N         
R9F56            RES_0402-0.0,5%,1/16W,CHIP,G21A 1        SP1_HOST_BRIDGE_UART_TX 
                                  2        SP1_BMC_HOST_UART_TX    
R9F57            RES_0402-0.0,5%,1/16W,CHIP,G21A 1        UART_BRIDGE_TXD5        
                                  2        UART_BMC_TXD5           
R9F58            RES_0402-0.0,5%,1/16W,CHIP,G21A 1        XTAL_24MHZ_PI7C9X1172_IN
                                  2        XTAL_24MHZ_IN_R         
R9F59            RES_0402-0.0,5%,1/16W,CHIP,G21A 1        XTAL_24MHZ_PI7C9X1172_OUT
                                  2        XTAL_24MHZ_OUT_R        
R9F60            RES_0402-0.0,5%,1/16W,EMPTY,G2A 1        CLK_25M_BMC             
                                  2        CLK_24M_25M_BMC_CLKIN   
R9F61            RES_0402-10.0K,1%,1/16W,CHIP,GA 1        P3V3_STBY               
                                  2        PU_24M_OSC_OE           
R9F62            RES_0402-0.0,5%,1/16W,CHIP,G21A 1        CLK_24M_BMC_CLKIN_R     
                                  2        CLK_24M_25M_BMC_CLKIN   
R9F63            RES_0402-0.0,5%,1/16W,CHIP,G21A 1        SPA_MID_DBG_RX          
                                  2        SPA_MID_DBG_RX_R        
R9F64            RES_0402-0.0,5%,1/16W,EMPTY,G2A 1        SP2_BMC_CM_UART_TX_R1   
                                  2        SPA_MID_DBG_RX_R        
R9F65            RES_0402-0.0,5%,1/16W,EMPTY,G2A 1        SP2_BMC_CM_UART_TX_R1   
                                  2        SP2_BMC_CM_UART_TX_R    
R9F66            RES_0402-0.0,5%,1/16W,CHIP,G21A 1        SP2_BMC_CM_UART_TX      
                                  2        SP2_BMC_CM_UART_TX_R    
R9F67            RES_0402-0.0,5%,1/16W,EMPTY,G2A 1        SP2_BMC_CM_UART_RX_R1   
                                  2        SPA_MID_DBG_TX_R        
R9F68            RES_0402-0.0,5%,1/16W,CHIP,G21A 1        SP2_BMC_CM_UART_RX_R    
                                  2        SP2_BMC_CM_UART_RX      
R9F69            RES_0402-0.0,5%,1/16W,EMPTY,G2A 1        SP2_BMC_CM_UART_RX_R    
                                  2        SP2_BMC_CM_UART_RX_R1   
R9F70            RES_0402-0.0,5%,1/16W,CHIP,G21A 1        SPA_MID_DBG_TX          
                                  2        SPA_MID_DBG_TX_R        
R9G1             RES_0402-150.0,1%,1/16W,CHIP,GA 1        LED_LAN_1_N             
                                  2        LED_LAN_1_R_N           
R9G2             RES_0402-150.0,1%,1/16W,CHIP,GA 1        LED_LAN_2_R_N           
                                  2        LED_LAN_2_N             
R9G3             RES_0402-150.0,1%,1/16W,CHIP,GA 1        LED_LAN_0_R_N           
                                  2        LED_LAN_0_N             
R9G4             RES_0402-0.0,5%,1/16W,CHIP,G21A 1        NIC_LED_ACT_ANODE_R     
                                  2        P3V3_STBY               
R9G5             RES_0402-0.0,5%,1/16W,EMPTY,G2A 1        PD_USB_BMC_P1_DN        
                                  2        GND                     
R9G6             RES_0402-0.0,5%,1/16W,EMPTY,G2A 1        PD_USB_BMC_P1_DP        
                                  2        GND                     
R9G7             RES_0402-49.9K,1%,1/16W,CHIP,GA 1        PD_ADCREXT              
                                  2        GND                     
R9G8             RES_0402-2.7K,1%,1/16W,CHIP,G2A 1        A_DACRSET               
                                  2        GND                     
R9G9             RES_0402-0.0,5%,1/16W,CHIP,G21A 1        NIC_SER_P_MDI_3_DP      
                                  2        NIC_MDI_SPRV_RJ45_3_R_DP
R9G10            RES_0402-33.2,1%,1/16W,CHIP,G2A 1        FM_CPU1_FIVR_FAULT_LVT3_N
                                  2        FM_CPU1_FIVR_FAULT_LVT3_R_N
R9G11            RES_0402-0.0,5%,1/16W,CHIP,G21A 1        NIC_SER_N_MDI_3_DN      
                                  2        NIC_MDI_SPRV_RJ45_3_R_DN
R9G12            RES_0402-20.0,1%,1/16W,CHIP,G2A 1        SMB_OCP_LAN_STBY_LVC3_SDA
                                  2        SMB_SPRINGVILLE_STBY_LVC3_SDA
R9G13            RES_0402-20.0,1%,1/16W,CHIP,G2A 1        SMB_OCP_LAN_STBY_LVC3_SCL
                                  2        SMB_SPRINGVILLE_STBY_LVC3_SCL
R9G14            RES_0402-20.0,1%,1/16W,CHIP,G2A 1        SMB_SENSOR_BMC_STBY_LVC3_SCL
                                  2        SMB_SENSOR_STBY_LVC3_SCL
R9G15            RES_0402-20.0,1%,1/16W,CHIP,G2A 1        SMB_SENSOR_BMC_STBY_LVC3_SDA
                                  2        SMB_SENSOR_STBY_LVC3_SDA
R9G16            RES_0402-33.2,1%,1/16W,CHIP,G2A 1        FM_CPU0_FIVR_FAULT_LVT3_N
                                  2        FM_CPU0_FIVR_FAULT_LVT3_R_N
R9G17            RES_0402-0.0,5%,1/16W,CHIP,G21A 1        NIC_SET_N_MDI_2_DN      
                                  2        NIC_MDI_SPRV_RJ45_2_R_DN
R9G18            RES_0402-0.0,5%,1/16W,CHIP,G21A 1        NIC_SET_P_MDI_2_DP      
                                  2        NIC_MDI_SPRV_RJ45_2_R_DP
R9G19            RES_0402-0.0,5%,1/16W,CHIP,G21A 1        NIC_MDI_SPRV_RJ45_1_DP  
                                  2        NIC_MDI_SPRV_RJ45_1_R_DP
R9G20            RES_0402-0.0,5%,1/16W,CHIP,G21A 1        NIC_MDI_SPRV_RJ45_1_DN  
                                  2        NIC_MDI_SPRV_RJ45_1_R_DN
R9G21            RES_0402-4.75K,1%,1/16W,CHIP,GA 1        P3V3_STBY               
                                  2        IRQ_VM_INT_R_N          
R9G22            RES_0402-0.0,5%,1/16W,CHIP,G21A 1        NIC_MDI_SPRV_RJ45_0_DN  
                                  2        NIC_MDI_SPRV_RJ45_0_R_DN
R9G23            RES_0402-4.75K,1%,1/16W,EMPTY,A 1        P3V3_STBY               
                                  2        FM_ADC128_A0            
R9G24            RES_0402-0.0,5%,1/16W,CHIP,G21A 1        NIC_MDI_SPRV_RJ45_0_DP  
                                  2        NIC_MDI_SPRV_RJ45_0_R_DP
R9G25            RES_0402-4.75K,1%,1/16W,EMPTY,A 1        P3V3_STBY               
                                  2        FM_ADC128_A1            
R9G26            RES_0402-100.0K,1%,1/16W,CHIP,A 1        A_P3V_BAT_SCALED        
                                  2        GND                     
R9G27            RES_0402-0.0,5%,1/16W,EMPTY,G2A 1        H_CPU0_MEMDEF_MEMHOT_G_PCH_N
                                  2        H_CPU0_MEMDEF_MEMHOT_LVT3_K_N
R9G28            RES_0402-0.0,5%,1/16W,CHIP,G21A 1        H_CPU1_KLM_MEMHOT_LVT3_R_N
                                  2        H_CPU1_MEMKLM_MEMHOT_LVT3_K_N
R9G29            RES_0402-0.0,5%,1/16W,CHIP,G21A 1        H_CPU0_MEMDEF_MEMHOT_LVT3_N
                                  2        H_CPU0_MEMDEF_MEMHOT_LVT3_BMC_N
R9G30            RES_0402-0.0,5%,1/16W,EMPTY,G2A 1        H_CPU0_MEMDEF_MEMHOT_LVT3_N
                                  2        H_CPU0_MEMDEF_MEMHOT_PCH_N
R9G31            RES_0402-33.2,1%,1/16W,CHIP,G2A 1        H_CPU0_MEMDEF_MEMHOT_LVT3_K_N
                                  2        H_CPU0_MEMDEF_MEMHOT_LVT3_N
R9G32            RES_0402-0.0,5%,1/16W,CHIP,G21A 1        H_CPU1_GHJ_MEMHOT_LVT3_R_N
                                  2        H_CPU1_MEMGHJ_MEMHOT_LVT3_K_N
R9G33            RES_0402-0.0,5%,1/16W,CHIP,G21A 1        H_CPU0_DEF_MEMHOT_LVT3_R_N
                                  2        H_CPU0_MEMDEF_MEMHOT_LVT3_K_N
R9G34            RES_0402-0.0,5%,1/16W,CHIP,G21A 1        H_CPU0_MEMABC_MEMHOT_G_N
                                  2        H_CPU0_MEMABC_MEMHOT_G_R_N
R9G35            RES_0402-2.7K,1%,1/16W,CHIP,G2A 1        P3V3_STBY               
                                  2        FM_BATTERY_SENSE_EN_N   
R9L1             RES_0402-1.00K,1%,1/16W,CHIP,GA 1        M_M_VREF                
                                  2        GND                     
R9L2             RES_0402-1.00K,1%,1/16W,CHIP,GA 1        PVDDQ_KLM               
                                  2        M_M_VREF                
R9L3             RES_0402-2,1.0%,1/16W,CHIP,G21A 1        M_M_CPU_VREF            
                                  2        M_M_VREF                
R9L4             RES_0402-1.0,1%,1/16W,CHIP,G21A 1        VR_PVDDQ_KLM_PH2_VCIN   
                                  2        P5V_STBY                
R9L6             RES_0402-1.00K,1%,1/16W,CHIP,GA 1        M_L_VREF                
                                  2        GND                     
R9L7             RES_0402-1.00K,1%,1/16W,CHIP,GA 1        PVDDQ_KLM               
                                  2        M_L_VREF                
R9L8             RES_0402-2,1.0%,1/16W,CHIP,G21A 1        M_L_CPU_VREF            
                                  2        M_L_VREF                
R9L9             RES_0402-1.0,1%,1/16W,CHIP,G21A 1        VR_PVDDQ_KLM_PH1_VCIN   
                                  2        P5V_STBY                
R9L11            RES_0402-1.00K,1%,1/16W,CHIP,GA 1        M_K_VREF                
                                  2        GND                     
R9M1             RES_0402-1.00K,1%,1/16W,CHIP,GA 1        PVDDQ_KLM               
                                  2        M_K_VREF                
R9M2             RES_0402-2,1.0%,1/16W,CHIP,G21A 1        M_K_CPU_VREF            
                                  2        M_K_VREF                
R9M3             RES_0402-0.0,5%,1/16W,CHIP,G21A 1        P3V3_STBY               
                                  2        VR_PVDDQ_KLM_VDD        
R9M4             RES_1206-0.002,1%,1W,CHIP,G521A 1        P12V_NVDIMM_KLM         
                                  2        P12V_STBY               
R9M5             RES_0402-100.0K,1%,1/16W,EMPTYA 1        P3V3_STBY               
                                  2        VR_PVDDQ_KLM_VREN       
R9M6             RES_0402-49.9,1%,1/16W,CHIP,G2A 1        PVCCIO_CPU1             
                                  2        SVID_CLK1_CPU1_R        
R9M7             RES_0402-100.0,1%,1/16W,EMPTY,A 1        PVCCIO_CPU1             
                                  2        SVID_DIO1_CPU1_R        
R9M8             RES_0402-100.0K,1%,1/16W,CHIP,B 1        VR_FET_SW_P12V_STBY_PVDDQ_KLM
                                  2        VR_PVDDQ_KLM_VINSEN     
R9M9             RES_0402-0.0,5%,1/16W,CHIP,G21A 1        FM_PVDDQ_KLM_EN         
                                  2        VR_PVDDQ_KLM_VREN       
R9M10            RES_0402-0.0,5%,1/16W,CHIP,G21A 1        VR_PVDDQ_KLM_VD12       
                                  2        VR_PVDDQ_KLM_AIREF2     
R9M11            RES_0402-0.0,5%,1/16W,CHIP,G21A 1        VR_PVDDQ_KLM_VD12       
                                  2        VR_PVDDQ_KLM_AIREF1     
R9M12            RES_0402-20.0,1%,1/16W,CHIP,G2A 1        SMB_PEHPCPU1_STBY_LVC3_R_SDA
                                  2        SMB_SLOTX24_BMC_STBY_LVC3_SDA
R9M13            RES_0402-20.0,1%,1/16W,CHIP,G2A 1        SMB_PEHPCPU1_STBY_LVC3_R_SDA
                                  2        SMB_PEHPCPU1_STBY_LVC3_SDA
R9M14            RES_0402-20.0,1%,1/16W,CHIP,G2A 1        SMB_PEHPCPU1_STBY_LVC3_R_SCL
                                  2        SMB_PEHPCPU1_STBY_LVC3_SCL
R9M15            RES_0402-20.0,1%,1/16W,CHIP,G2A 1        SMB_PEHPCPU1_STBY_LVC3_R_SCL
                                  2        SMB_SLOTX24_BMC_STBY_LVC3_SCL
R9M16            RES_0402-2.0K,1%,1/16W,CHIP,G2A 1        P3V3_STBY               
                                  2        SMB_PEHPCPU1_STBY_LVC3_R_SDA
R9M17            RES_0402-2.0K,1%,1/16W,CHIP,G2A 1        P3V3_STBY               
                                  2        SMB_PEHPCPU1_STBY_LVC3_R_SCL
R9M18            RES_0402-240,1.0%,1/16W,CHIP,GA 1        PVCCIO_CPU1             
                                  2        SMB_CPU1_PE_HP_GTL_R_SDA
R9M19            RES_0402-240,1.0%,1/16W,CHIP,GA 1        PVCCIO_CPU1             
                                  2        SMB_CPU1_PE_HP_GTL_R_SCL
R9M20            RES_0402-0.0,5%,1/16W,CHIP,G21A 1        SMB_LAN_STBY_LVC3_SCL   
                                  2        SMB_PIROM_CPU1_SCL      
R9M21            RES_0402-0.0,5%,1/16W,CHIP,G21A 1        SMB_LAN_STBY_LVC3_SDA   
                                  2        SMB_PIROM_CPU1_SDA      
R9N1             RES_0402-49.9,1%,1/16W,CHIP,G2A 1        PVCCIO_CPU1             
                                  2        SVID_ALERT1_CPU1_R_N    
R9N2             RES_0402-100.0,1%,1/16W,CHIP,GA 1        PVCCIO_CPU1             
                                  2        SVID_DIO1_CPU1_R        
R9N3             RES_0402-1.0,1%,1/16W,CHIP,G21A 1        VR_PVSA_CPU1_VCIN       
                                  2        P5V_STBY                
R9N4             RES_0402-51.1,1.0%,1/16W,CHIP,A 1        PVSA_CPU1               
                                  2        GND                     
R9N5             RES_0402-0.0,5%,1/16W,CHIP,G21A 1        VR_PVCCIN_CPU1_VD12     
                                  2        VR_PVSA_CPU1_BIREF1     
R9N7             RES_0402-3.16K,1%,1/16W,CHIP,GA 1        VR_PVCCIN_CPU1_XADDR2   
                                  2        GND                     
R9N8             RES_0402-4.02K,1%,1/16W,CHIP,GA 1        VR_PVCCIN_CPU1_XADDR1   
                                  2        GND                     
R9N9             RES_0402-0.0,5%,1/16W,CHIP,G21A 1        VR_PVCCIN_CPU1_VD12     
                                  2        VR_PVCCIN_CPU1_AIREF5   
R9N10            RES_0402-0.0,5%,1/16W,CHIP,G21A 1        VR_PVCCIN_CPU1_VD12     
                                  2        VR_PVCCIN_CPU1_AIREF4   
R9N12            RES_0402-0.0,5%,1/16W,CHIP,G21A 1        VR_PVCCIN_CPU1_VD12     
                                  2        VR_PVCCIN_CPU1_AIREF3   
R9N14            RES_0402-1.00K,1%,1/16W,CHIP,GA 1        PVCCIO_CPU1             
                                  2        VR_PVCCIN_CPU1_VREN     
R9N15            RES_0402-0.0,5%,1/16W,CHIP,G21A 1        VR_PVCCIN_CPU1_VD12     
                                  2        VR_PVCCIN_CPU1_AIREF1   
R9N16            RES_0402-0.0,5%,1/16W,CHIP,G21A 1        FM_PVCCIN_PVCCSA_CPU1_EN_LVC1
                                  2        VR_PVCCIN_CPU1_VREN     
R9N17            RES_0402-0.0,5%,1/16W,CHIP,G21A 1        VR_PVCCIN_CPU1_VD12     
                                  2        VR_PVCCIN_CPU1_AIREF2   
R9P1             RES_0402-100.0,1%,1/16W,CHIP,GA 1        PVCCIO_CPU1             
                                  2        SVID_DIO0_CPU1_R        
R9P2             RES_0402-49.9,1%,1/16W,CHIP,G2A 1        PVCCIO_CPU1             
                                  2        SVID_CLK0_CPU1_R        
R9P3             RES_0402-33.2,1%,1/16W,CHIP,G2A 1        IRQ_PVCCIN_CPU1_VRHOT_LVC3_R_N
                                  2        IRQ_PVCCIN_CPU1_VRHOT_LVC3_N
R9P4             RES_0402-2.7K,1%,1/16W,CHIP,G2A 1        P3V3_STBY               
                                  2        IRQ_UV_DETECT_N         
R9P5             RES_0402-10.0K,1%,1/16W,CHIP,GA 1        P3V3_STBY               
                                  2        FM_DISABLE_FAN_N        
R9P6             RES_0402-10.0K,1%,1/16W,CHIP,GA 1        P3V3_STBY               
                                  2        FM_UV_ADR_TRIGGER_N     
R9P7             RES_0402-249K,1.0%,1/16W,CHIP,A 1        P12V_STBY               
                                  2        A_P12V_STBY_ADR_TRIGGER 
R9P8             RES_0402-1.0,1%,1/16W,CHIP,G21A 1        VR_PVCCIN_CPU1_PH4_VCIN 
                                  2        P5V_STBY                
R9P9             RES_0402-10.0K,1%,1/16W,CHIP,GA 1        A_P12V_STBY_ADR_TRIGGER 
                                  2        AGND_HSC                
R9P10            RES_0402-10.0K,1%,1/16W,CHIP,GA 1        P3V3_STBY               
                                  2        A_P12V_STBY_FPH_GATE    
R9P11            RES_0402-10.0K,1%,1/16W,CHIP,GA 1        A_P12V_STBY_FP_TRIGGER  
                                  2        AGND_HSC                
R9P12            RES_0402-4.99K,1%,1/16W,CHIP,GA 1        A_HSC_INAP              
                                  2        AGND_HSC                
R9P13            RES_0402-274K,1.0%,1/16W,CHIP,A 1        P12V_STBY               
                                  2        A_P12V_STBY_FP_TRIGGER  
R9P15            RES_0402-0.0,5%,1/16W,EMPTY,G2A 1        A_HSC_LOW_DRAIN         
                                  2        IRQ_OC_DETECT_N         
R9P16            RES_0402-0.0,5%,1/16W,CHIP,G21A 1        FM_P12V_HSC_ADR2        
                                  2        AGND_HSC                
R9P17            RES_0402-150.0K,1%,1/16W,CHIP,A 1        FM_P12V_HSC_ADR1        
                                  2        AGND_HSC                
R9P18            RES_0402-15.0K,1%,1/16W,CHIP,GA 1        P12V_STBY               
                                  2        PWRGD_P12V_R            
R9P19            RES_0402-10.0K,1%,1/16W,EMPTY,A 1        A_HSC_TIMER_R           
                                  2        AGND_HSC                
R9P20            RES_0402-2.7K,1%,1/16W,CHIP,G2A 1        P3V3_STBY               
                                  2        FM_HSC_TIMER_EXP_N      
R9P21            RES_0402-0.0,5%,1/16W,CHIP,G21A 1        A_HSC_TIMER             
                                  2        A_HSC_TIMER_R           
R9P22            RES_0402-1.0,1%,1/16W,CHIP,G21A 1        VR_PVCCIN_CPU1_PH3_VCIN 
                                  2        P5V_STBY                
R9P23            RES_0402-100.0K,1%,1/16W,CHIP,A 1        P12V_STBY               
                                  2        A_HSC_PWGIN             
R9P24            RES_0402-12.1K,1%,1/16W,CHIP,GA 1        A_HSC_PWGIN             
                                  2        AGND_HSC                
R9P26            RES_0402-10.0,1%,1/16W,CHIP,G2A 1        P12V_HSC_SENN1          
                                  2        A_HSC_HSN               
R9P27            RES_0402-10.0,1%,1/16W,CHIP,G2A 1        P12V_HSC_SENP1          
                                  2        A_HSC_HSP               
R9P28            RES_0402-100.0K,1%,1/16W,CHIP,A 1        P12V_PSU                
                                  2        A_HSC_OV                
R9P29            RES_0402-100.0K,1%,1/16W,CHIP,A 1        P12V_PSU                
                                  2        A_HSC_UV                
R9P30            RES_0603-10.0,1%,1/10W,CHIP,G2A 1        P12V_PSU                
                                  2        P12V_HSC_VCC            
R9P32            RES_0402-1.0,1%,1/16W,CHIP,G21A 1        VR_PVCCIN_CPU1_PH5_VCIN 
                                  2        P5V_STBY                
R9P33            RES_0402-100.0K,1%,1/16W,CHIP,A 1        P12V_STBY               
                                  2        A_HSC_INAP              
R9R1             RES_PWR_6PAD-0.001,1%,3W,CHIP,A 1        P12V_PSU                
                                  2        P12V_MB0_SW             
                                  3        P12V_HSC_SENP1          
                                  4        P12V_HSC_SENN1          
                                  5        P12V_PSU                
                                  6        P12V_MB0_SW             
R9R2             RES_0402-1.0,1%,1/16W,CHIP,G21A 1        VR_PVCCIN_CPU1_PH1_VCIN 
                                  2        P5V_STBY                
R9R4             RES_0402-10.0,1%,1/16W,CHIP,G2A 1        A_HSC_GATE              
                                  2        A_HSC_GATE2_R           
R9R5             RES_0402-49.9,1%,1/16W,CHIP,G2A 1        ISENSE_TMP421_2_E       
                                  2        ISENSE_TMP421_2_DXP     
R9R6             RES_0402-49.9,1%,1/16W,CHIP,G2A 1        ISENSE_TMP421_2_BC      
                                  2        ISENSE_TMP421_2_DXN     
R9R7             RES_0402-20.0,1%,1/16W,CHIP,G2A 1        SMB_SENSOR_TMP421_2_SCL 
                                  2        SMB_SENSOR_STBY_LVC3_SCL
R9R8             RES_0402-20.0,1%,1/16W,CHIP,G2A 1        SMB_SENSOR_TMP421_2_SDA 
                                  2        SMB_SENSOR_STBY_LVC3_SDA
R9R9             RES_0402-0.0,5%,1/16W,CHIP,G21A 1        FAN_TACH3               
                                  2        FAN_TACH3_R             
R9R10            RES_0402-0.0,5%,1/16W,CHIP,G21A 1        FAN_TACH1               
                                  2        FAN_TACH1_R             
R9R11            RES_0402-1.0,1%,1/16W,CHIP,G21A 1        VR_PVCCIN_CPU1_PH2_VCIN 
                                  2        P5V_STBY                
R9R12            RES_0402-0.0,5%,1/16W,CHIP,G21A 1        FAN_TACH2               
                                  2        FAN_TACH2_R             
R9T1             RES_0402-0.0,5%,1/16W,CHIP,G21A 1        FAN_PWM_OUT_SYS0_R      
                                  2        FAN_PWM_OUT_SYS0_R1     
R9T3             RES_0402-6.19K,1%,1/16W,CHIP,GA 1        FM_P12V_HOTSWAP0_EN     
                                  2        GND                     
R9T4             RES_0402-0.0,5%,1/16W,CHIP,G21A 1        VR_PVDDQ_GHJ_AIINSEN_R  
                                  2        VR_PVDDQ_GHJ_AIINSEN    
R9T5             RES_0402-4.75K,1%,1/16W,CHIP,GA 1        P3V3_STBY               
                                  2        FAN_TACH1               
R9T6             RES_0402-15.0K,1%,1/16W,CHIP,GA 1        P12V_PSU                
                                  2        FM_P12V_HOTSWAP0_EN     
R9T7             RES_0402-100.0,1%,1/16W,CHIP,GA 1        FAN_TACH1               
                                  2        FAN_TACH1_CPU1_D2       
R9T8             RES_0402-0.0,5%,1/16W,EMPTY,G2A 1        FM_MATED_IN_N           
                                  2        GND                     
R9T9             RES_0402-4.75K,1%,1/16W,CHIP,GA 1        P12V_PSU                
                                  2        FM_MATED_IN_N           
R9U1             RES_0402-1.0,1%,1/16W,CHIP,G21A 1        VR_PVDDQ_GHJ_PH1_VCIN   
                                  2        P5V_STBY                
R9U3             RES_0402-100.0,1%,1/16W,CHIP,GA 1        PVCCIO_CPU1             
                                  2        SVID_DIO1_CPU1_R        
R9U4             RES_0402-49.9,1%,1/16W,EMPTY,GA 1        PVCCIO_CPU1             
                                  2        SVID_CLK1_CPU1_R        
R9U7             RES_0402-0.0,5%,1/16W,CHIP,G21A 1        FM_PVDDQ_GHJ_EN         
                                  2        VR_PVDDQ_GHJ_VREN       
R9U8             RES_0402-100.0K,1%,1/16W,EMPTYA 1        P3V3_STBY               
                                  2        VR_PVDDQ_GHJ_VREN       
R9U10            RES_0402-0.0,5%,1/16W,CHIP,G21A 1        P3V3_STBY               
                                  2        VR_PVDDQ_GHJ_VDD        
R9U11            RES_0402-100.0K,1%,1/16W,CHIP,B 1        VR_FET_SW_P12V_STBY_PVDDQ_GHJ
                                  2        VR_PVDDQ_GHJ_VINSEN     
R9U12            RES_0402-1.0,1%,1/16W,CHIP,G21A 1        VR_PVDDQ_GHJ_PH2_VCIN   
                                  2        P5V_STBY                
RM1E1            CONN3_G98259001_PIP-CONN,G9825A 1        GND                     
                                  2        GND                     
                                  3        GND                     
RM8D1            STANDOFF_TH1-SO,H72821-001 1        GND                     
RT8P1            RES_0603-100.0K,1%,1/10W,CHIP,A 1        PVCCIN_CPU1             
                                  2        VSENSE_VCCINR2PMAX_CPU1 
RTI1             2D2R2F-GP_SMD-RG1-2D2R2F-GP,64A 1        VR_PVCCIN_CPU0_PH1_BOOT 
                                  2        VR_PVCCIN_CPU0_PH1_BOOT_R
RTI2             3D01R5F-GP_SMD-RG5-3D01R5F-GP,A 1        GND                     
                                  2        UNNAMED_202_3D01R5F-GP_I75_2
RTI3             2D2R2F-GP_SMD-RG1-2D2R2F-GP,64A 1        VR_PVCCIN_CPU0_PH2_BOOT 
                                  2        VR_PVCCIN_CPU0_PH2_BOOT_R
RTI4             3D01R5F-GP_SMD-RG5-3D01R5F-GP,A 1        GND                     
                                  2        UNNAMED_202_3D01R5F-GP_I83_2
RTI5             2D2R2F-GP_SMD-RG1-2D2R2F-GP,64A 1        VR_PVDDQ_KLM_PH1_BOOT   
                                  2        VR_PVDDQ_KLM_PH1_BOOT_R 
RTI6             3D01R5F-GP_SMD-RG5-3D01R5F-GP,A 1        UNNAMED_227_3D01R5F-GP_I125_1
                                  2        GND                     
RTI7             3D01R5F-GP_SMD-RG5-3D01R5F-GP,A 1        UNNAMED_227_3D01R5F-GP_I124_1
                                  2        GND                     
RTI8             2D2R2F-GP_SMD-RG1-2D2R2F-GP,64A 1        VR_PVDDQ_KLM_PH2_BOOT   
                                  2        VR_PVDDQ_KLM_PH2_BOOT_R 
RTI9             2D2R2F-GP_SMD-RG1-2D2R2F-GP,64A 1        VR_PVCCIN_CPU1_PH5_BOOT 
                                  2        VR_PVCCIN_CPU1_PH5_BOOT_R
RTI10            3D01R5F-GP_SMD-RG5-3D01R5F-GP,A 1        GND                     
                                  2        UNNAMED_209_3D01R5F-GP_I66_2
RTI11            2D2R2F-GP_SMD-RG1-2D2R2F-GP,64A 1        VR_PVCCIN_CPU1_PH3_BOOT 
                                  2        VR_PVCCIN_CPU1_PH3_BOOT_R
RTI12            3D01R5F-GP_SMD-RG5-3D01R5F-GP,A 1        GND                     
                                  2        UNNAMED_208_3D01R5F-GP_I86_2
RTI13            3D01R5F-GP_SMD-RG5-3D01R5F-GP,A 1        GND                     
                                  2        UNNAMED_208_3D01R5F-GP_I94_2
RTI14            2D2R2F-GP_SMD-RG1-2D2R2F-GP,64A 1        VR_PVCCIN_CPU1_PH4_BOOT 
                                  2        VR_PVCCIN_CPU1_PH4_BOOT_R
RTI15            2D2R2F-GP_SMD-RG1-2D2R2F-GP,64A 1        VR_PVCCIN_CPU1_PH1_BOOT 
                                  2        VR_PVCCIN_CPU1_PH1_BOOT_R
RTI16            3D01R5F-GP_SMD-RG5-3D01R5F-GP,A 1        GND                     
                                  2        UNNAMED_207_3D01R5F-GP_I76_2
RTI17            2D2R2F-GP_SMD-RG1-2D2R2F-GP,64A 1        VR_PVCCIN_CPU1_PH2_BOOT 
                                  2        VR_PVCCIN_CPU1_PH2_BOOT_R
RTI18            3D01R5F-GP_SMD-RG5-3D01R5F-GP,A 1        GND                     
                                  2        UNNAMED_207_3D01R5F-GP_I85_2
RTI19            2D2R2F-GP_SMD-RG1-2D2R2F-GP,64A 1        VR_PVDDQ_GHJ_PH1_BOOT   
                                  2        VR_PVDDQ_GHJ_PH1_BOOT_R 
RTI20            3D01R5F-GP_SMD-RG5-3D01R5F-GP,A 1        GND                     
                                  2        UNNAMED_224_3D01R5F-GP_I119_2
RTI21            2D2R2F-GP_SMD-RG1-2D2R2F-GP,64A 1        VR_PVDDQ_GHJ_PH2_BOOT   
                                  2        VR_PVDDQ_GHJ_PH2_BOOT_R 
RTI22            3D01R5F-GP_SMD-RG5-3D01R5F-GP,A 1        GND                     
                                  2        UNNAMED_224_3D01R5F-GP_I129_2
RTI23            2D2R2F-GP_SMD-RG1-2D2R2F-GP,64A 1        VR_PVCCIN_CPU0_PH5_BOOT 
                                  2        VR_PVCCIN_CPU0_PH5_BOOT_R
RTI24            3D01R5F-GP_SMD-RG5-3D01R5F-GP,A 1        GND                     
                                  2        UNNAMED_204_3D01R5F-GP_I91_2
RTI25            2D2R2F-GP_SMD-RG1-2D2R2F-GP,64A 1        VR_PVCCIN_CPU0_PH3_BOOT 
                                  2        VR_PVCCIN_CPU0_PH3_BOOT_R
RTI26            3D01R5F-GP_SMD-RG5-3D01R5F-GP,A 1        GND                     
                                  2        UNNAMED_203_3D01R5F-GP_I102_2
RTI27            3D01R5F-GP_SMD-RG5-3D01R5F-GP,A 1        GND                     
                                  2        UNNAMED_203_3D01R5F-GP_I105_2
RTI28            2D2R2F-GP_SMD-RG1-2D2R2F-GP,64A 1        VR_PVCCIN_CPU0_PH4_BOOT 
                                  2        VR_PVCCIN_CPU0_PH4_BOOT_R
RTI29            3D01R5F-GP_SMD-RG5-3D01R5F-GP,A 1        GND                     
                                  2        UNNAMED_219_3D01R5F-GP_I126_2
RTI30            2D2R2F-GP_SMD-RG1-2D2R2F-GP,64A 1        VR_PVDDQ_DEF_PH1_BOOT   
                                  2        VR_PVDDQ_DEF_PH1_BOOT_R 
RTI31            2D2R2F-GP_SMD-RG1-2D2R2F-GP,64A 1        VR_PVDDQ_DEF_PH2_BOOT   
                                  2        VR_PVDDQ_DEF_PH2_BOOT_R 
RTI32            3D01R5F-GP_SMD-RG5-3D01R5F-GP,A 1        GND                     
                                  2        UNNAMED_219_3D01R5F-GP_I123_2
RTI33            2D2R2F-GP_SMD-RG1-2D2R2F-GP,64A 1        VR_PVDDQ_ABC_PH1_BOOT   
                                  2        VR_PVDDQ_ABC_PH1_BOOT_R 
RTI34            3D01R5F-GP_SMD-RG5-3D01R5F-GP,A 1        GND                     
                                  2        UNNAMED_216_3D01R5F-GP_I114_2
RTI35            3D01R5F-GP_SMD-RG5-3D01R5F-GP,A 1        GND                     
                                  2        UNNAMED_216_3D01R5F-GP_I123_2
RTI36            2D2R2F-GP_SMD-RG1-2D2R2F-GP,64A 1        VR_PVDDQ_ABC_PH2_BOOT   
                                  2        VR_PVDDQ_ABC_PH2_BOOT_R 
RTI37            2D2R2F-GP_SMD-RG1-2D2R2F-GP,64A 1        VR_PVSA_CPU1_BOOT       
                                  2        VR_PVSA_CPU1_BOOT_R     
RTI38            3D01R5F-GP_SMD-RG5-3D01R5F-GP,A 1        GND                     
                                  2        UNNAMED_210_3D01R5F-GP_I59_2
RTI39            3D01R5F-GP_SMD-RG5-3D01R5F-GP,A 1        GND                     
                                  2        UNNAMED_205_3D01R5F-GP_I68_2
RTI40            2D2R2F-GP_SMD-RG1-2D2R2F-GP,64A 1        VR_PVSA_CPU0_BOOT       
                                  2        VR_PVSA_CPU0_BOOT_R     
RTI41            2D2R2F-GP_SMD-RG1-2D2R2F-GP,64A 1        VR_PVCCIO_CPU1_PH1_BOOT 
                                  2        VR_PVCCIO_CPU1_PH1_BOOT_R
RTI42            3D01R5F-GP_SMD-RG5-3D01R5F-GP,A 1        GND                     
                                  2        UNNAMED_214_3D01R5F-GP_I132_2
RTI43            3D01R5F-GP_SMD-RG5-3D01R5F-GP,A 1        GND                     
                                  2        UNNAMED_236_3D01R5F-GP_I132_2
RTI44            2D2R2F-GP_SMD-RG1-2D2R2F-GP,64A 1        VR_PVNN_PCH_PH1_BOOT    
                                  2        VR_PVNN_PCH_PH1_BOOT_R  
RTI45            3D01R5F-GP_SMD-RG5-3D01R5F-GP,A 1        GND                     
                                  2        UNNAMED_236_3D01R5F-GP_I137_2
RTI46            2D2R2F-GP_SMD-RG1-2D2R2F-GP,64A 1        VR_P1V05_PCH_STBY_PH1_BOOT
                                  2        VR_P1V05_PCH_STBY_PH1_BOOT_R
RTI47            2D2R2F-GP_SMD-RG1-2D2R2F-GP,64A 1        VR_PVCCIO_CPU0_PH1_BOOT 
                                  2        VR_PVCCIO_CPU0_PH1_BOOT_R
RTI48            3D01R5F-GP_SMD-RG5-3D01R5F-GP,A 1        GND                     
                                  2        UNNAMED_212_3D01R5F-GP_I112_2
S8E1             SWITCH_D90553001_SMLF-IC,D9055A 1        GND                     
                                  2        FP_NMI_BTN_OUT_R_N      
S9A1             SWITCH_D37771002_SM-IC,D37771-A 1        FM_DEBUG_RST_BTN_N      
                                  2        FM_DEBUG_RST_BTN_N      
                                  3        GND                     
                                  4        GND                     
S9A2             SW_H67881001_SM-IC,H67881-001 1        FP_PWR_BTN_R_N          
                                  2        FP_PWR_BTN_R_N          
                                  3        GND                     
                                  4        GND                     
SH3D1            SHUNT_SH0201-EMPTY,N_A 1        VSENSE_PVCCIO_CPU1_SKT_VRTN
                                  2        VSENSE_PVCCIO_CPU1_AVSN 
SH3D2            SHUNT_SH0201-EMPTY,N_A 1        VSENSE_PVCCIO_CPU1_SKT_VSEN
                                  2        VSENSE_PVCCIO_CPU1_AVSP 
SH3P1            SHUNT_SH0201-EMPTY,N_A 1        VSENSE_PVCCIO_CPU0_SKT_VSEN
                                  2        VSENSE_PVCCIO_CPU0_AVSP 
SH3P2            SHUNT_SH0201-EMPTY,N_A 1        VSENSE_PVCCIO_CPU0_SKT_VRTN
                                  2        VSENSE_PVCCIO_CPU0_AVSN 
SH4L1            SHUNT_SH0201-EMPTY,N_A 1        VSENSE_PVDDQ_DEF_N      
                                  2        GND                     
SH4L2            SHUNT_SH0201-EMPTY,N_A 1        VSENSE_PVDDQ_DEF_P      
                                  2        PVDDQ_DEF               
SH4U1            SHUNT_SH0201-EMPTY,N_A 1        VSENSE_PVDDQ_ABC_N      
                                  2        GND                     
SH4U2            SHUNT_SH0201-EMPTY,N_A 1        VSENSE_PVDDQ_ABC_P      
                                  2        PVDDQ_ABC               
SH5L1            SHUNT_SH0201-EMPTY,N_A 1        VR_PVTT_DEF_SNS         
                                  2        PVTT_DEF                
SH5U1            SHUNT_SH0201-EMPTY,N_A 1        VR_PVTT_ABC_SNS         
                                  2        PVTT_ABC                
SH7L1            SHUNT_SH0201-EMPTY,N_A 1        VSENSE_PVDDQ_KLM_N      
                                  2        GND                     
SH7L2            SHUNT_SH0201-EMPTY,N_A 1        VSENSE_PVDDQ_KLM_P      
                                  2        PVDDQ_KLM               
SH7U1            SHUNT_SH0201-EMPTY,N_A 1        VSENSE_PVDDQ_GHJ_P      
                                  2        PVDDQ_GHJ               
SH7U2            SHUNT_SH0201-EMPTY,N_A 1        VSENSE_PVDDQ_GHJ_N      
                                  2        GND                     
SH8L1            SHUNT_SH0201-EMPTY,N_A 1        VR_PVTT_KLM_SNS         
                                  2        PVTT_KLM                
SH8U1            SHUNT_SH0201-EMPTY,N_A 1        VR_PVTT_GHJ_SNS         
                                  2        PVTT_GHJ                
TC1A1            RCC_DFX1940_ID4-EMPTY,N_A 1        GND                     
                                  2        RCC_DFX_1940_1          
                                  3        RCC_DFX_1940_1          
TC1G1            RCC_DFX1940_ID4-EMPTY,N_A 1        GND                     
                                  2        RCC_DFX_1940_4          
                                  3        RCC_DFX_1940_4          
TC9A1            RCC_DFX1940_ID4-EMPTY,N_A 1        GND                     
                                  2        RCC_DFX_1940_2          
                                  3        RCC_DFX_1940_2          
TC9F1            RCC_DFX1940_ID4-EMPTY,N_A 1        GND                     
                                  2        RCC_DFX_1940_3          
                                  3        RCC_DFX_1940_3          
TH1A1            MTG_KEYHOLE_TH-EMPTY,NA 1        GND                     
TH4A1            MTG_KEYHOLE_TH-EMPTY,NA 1        GND                     
TH4G1            MTG_KEYHOLE_TH-EMPTY,NA 1        GND                     
TH7A1            MTG_KEYHOLE_TH-EMPTY,NA 1        GND                     
TH7G1            MTG_KEYHOLE_TH-EMPTY,NA 1        GND                     
TH9A1            MTG_KEYHOLE_TH-EMPTY,NA 1        GND                     
TH9G1            MTG_KEYHOLE_TH-EMPTY,NA 1        GND                     
U1B1             MAX9634_SOT-IC,H35789-001 1        GND                     
                                  2        GND                     
                                  3        VR_PVDDQ_KLM_AIINSEN_R  
                                  4        P12V_NVDIMM_KLM         
                                  5        P12V_STBY               
U1B2             PCA9517_SM-IC,G77073-001-GND=GA 1        PVCCIO_CPU1             
                                  2        SMB_CPU1_PE_HP_GTL_R_SCL
                                  3        SMB_CPU1_PE_HP_GTL_R_SDA
                                  5        TP_SMB_PEHPCPU1_EN      
                                  6        SMB_PEHPCPU1_STBY_LVC3_R_SDA
                                  7        SMB_PEHPCPU1_STBY_LVC3_R_SCL
                                  8        P3V3_STBY               
U1B3             ADM4073_SM-EMPTY,G12194-001 1        GND                     
                                  2        GND                     
                                  3        VR_FET_SW_P12V_PVCCIN_CPU1_R
                                  4        VR_FET_SW_P12V_PVCCIN_CPU1_R
                                  5        VR_FET_SW_P12V_STBY_PVCCIN_CPU1
                                  6        PVCCIN_PVSA_CPU1_IINSEN 
U1D1             TTL1G126_A_SOT-74HC1G126,IC,A7B 1        FM_OC_DETECT_EN         
                                  2        IRQ_OC_DETECT_N         
                                  4        FM_OC_DETECT_N          
U1D2             TPS3700_SM-IC,H69492-001 1        IRQ_OC_DETECT_N         
                                  2        P12V_STBY               
                                  3        A_HSC_HIGH              
                                  4        A_HSC_LOW               
                                  5        GND                     
                                  6        A_HSC_LOW_GATE          
U1E1             TMP421_TSSOP-IC,G62962-001 1        ISENSE_TMP421_2_DXP     
                                  2        ISENSE_TMP421_2_DXN     
                                  3        PD_TMP421_2_A1          
                                  4        PU_TMP421_2_A0          
                                  5        GND                     
                                  6        SMB_SENSOR_TMP421_2_SDA 
                                  7        SMB_SENSOR_TMP421_2_SCL 
                                  8        P3V3_STBY               
U1E2             TTL1G08_SOTLF-NC7SZ08,IC,D1032B 1        FM_CTNR_PS_ON           
                                  2        FM_DISABLE_FAN_N        
                                  4        FM_ENABLE_FAN_POWER     
U1F1             MAX9634_SOT-IC,H35789-001 1        GND                     
                                  2        GND                     
                                  3        VR_PVDDQ_GHJ_AIINSEN_R  
                                  4        P12V_NVDIMM_GHJ         
                                  5        P12V_STBY               
U1L1             TTL3126_QFNLF-74CBTLV3126,IC,DB 1        PWRGD_PVCCIN_CPU0       
                                  2        XDP_TRST_N              
                                  3        XDP_CPU_TRST_N          
                                  4        PWRGD_PVCCIN_CPU0       
                                  5        XDP_TMS                 
                                  6        XDP_CPU_TMS             
                                  8        XDP_CPU_TDO             
                                  9        XDP_TDO                 
                                  10       PWRGD_PVCCIN_CPU0       
                                  11       XDP_CPU_TDI             
                                  12       XDP_TDI                 
                                  13       PWRGD_PVCCIN_CPU0       
U1L2             TTL1G86_SOTLF-74AHCT1G86,IC,D3B 1        PWRGD_P3V3_R            
                                  2        FP_PWR_ID_LED_N         
                                  4        FP_ID_LED_P5V_STBY_N    
U1L3             ADM809_SMLF-IC,D23047-001-GND=A 2        PWRGD_P3V3_R1           
                                  3        P3V3                    
U1L4             TTL1G07_A_SOP-74LVC1G07,IC,C88B 2        XDP_RST_CO_N            
                                  4        FM_DEBUG_RST_BTN_R1_N   
U1L5             TTL3126_QFNLF-74CBTLV3126,IC,DB 1        PWRGD_PVCCIN_CPU0       
                                  2        XDP_OBSFN_B1_MBP7_N     
                                  3        XDP_CPU_OBSFN_B1_MBP7_N 
                                  4        PWRGD_PVCCIN_CPU0       
                                  5        XDP_OBSFN_B0_MBP6_N     
                                  6        XDP_CPU_OBSFN_B0_MBP6_N 
                                  8        XDP_CPU_PRDY_N          
                                  9        XDP_PRDY_N              
                                  10       PWRGD_PVCCIN_CPU0       
                                  11       XDP_CPU_PREQ_N          
                                  12       XDP_PREQ_N              
                                  13       PWRGD_PVCCIN_CPU0       
U1M1             TTL1G08_SOTLF-NC7SZ08,IC,D1032C 1        LED_SATA_ACT_R_N        
                                  2        LED_SAS_ACT_R_N         
                                  4        FP_LED_HDD_ACTIVITY_AND_N
U1M2             NC7SB3157_SMLF-IC,C99406-001 1        JTAG_MCP_CPU0_TDO       
                                  2        GND                     
                                  3        JTAG_MCP_CPU1_TDO       
                                  4        JTAG_MCP_MUX_TDO        
                                  5        P3V3_STBY               
                                  6        FM_CPU1_CD_PRES         
U1M3             TPS2061_SM-IC,H66405-001 1        P5V_USB                 
                                  2        GND                     
                                  3        FM_OC0_USB_N            
                                  4        FM_USB_P0_EN_BOOT_BIOS_STRAP_N
                                  5        P5V                     
U1M4             74CBTLV1G125_SMLF-IC,C88177-00A 1        FM_CPU1_SKTOCC_LVT3_N   
                                  2        XDP_CPU0_TDO            
                                  4        XDP_CPU1_TDI            
U1M5             74CBTLV1G125_SMLF-IC,C88177-00A 1        FM_CPU0_OR_CPU1_MCP_PRES
                                  2        P1V8_MCP_CPU0           
                                  4        JTAG_MCP_TMS_R1         
U1M6             74CBTLV1G125_SMLF-IC,C88177-00A 1        FM_CPU0_AND_CPU1_MCP_PRES
                                  2        JTAG_MCP_CPU0_TDO       
                                  4        JTAG_MCP_CPU1_TDI       
U1M7             NC7SB3157_SMLF-IC,C99406-001 1        XDP_CPU0_TDO            
                                  2        GND                     
                                  3        XDP_CPU1_TDO            
                                  4        XDP_CPU_TDO             
                                  5        P3V3_STBY               
                                  6        FM_CPU1_SKTOCC_LVT3_N   
U1R1             TTL1G07_A_SOP-74LVC1G07,IC,C88B 2        FM_FAST_PROCHOT_THROTTLE_DLY_BU
                                  4        FM_THROTTLE_R1_N        
U1R2             TTL1G126_A_SOT-74HC1G126,IC,A7B 1        FM_FAST_PROCHOT_EN      
                                  2        FM_FAST_PROCHOT_THROTTLE_DLY_N
                                  4        FM_FAST_PROCHOT_THROTTLE_DLY_BU
U2D1             SKX_EXT_B_BGA1-IC,TBD A4       TP_CPU1_RSVD_304        
                                  A6       TP_CPU1_RSVD_303        
                                  A8       PVPP_GHJ                
                                  A10      PVPP_GHJ                
                                  A12      PVPP_GHJ                
                                  A14      P1V8_MCP_CPU1           
                                  A16      P1V8_MCP_CPU1           
                                  A24      TP_CPU1_RSVD_300        
                                  A26      GND                     
                                  A28      M_H_DQS_DN<15>          
                                  A30      GND                     
                                  A32      GND                     
                                  A34      M_H_DQS_DN<14>          
                                  A36      GND                     
                                  A38      GND                     
                                  A40      M_G_DQS_DN<13>          
                                  A42      GND                     
                                  AA2      UPI_CPU1_CPU0_P0P0_DP<4>
                                  AA4      GND                     
                                  AA6      UPI_CPU0_CPU1_P0P0_DP<2>
                                  AA8      UPI_CPU0_CPU1_P0P0_DN<1>
                                  AA10     PVCCIO_CPU1             
                                  AA12     TP_XDP_CPU1_OBSDATA_B2_MBP4_N
                                  AA14     XDP_CPU_TCK0            
                                  AA16     GND                     
                                  AA18     GND                     
                                  AA20     UPI_CPU0_CPU1_P1P1_DN<19>
                                  AA22     GND                     
                                  AA24     GND                     
                                  AA26     M_H_DQ<63>              
                                  AA28     M_H_DQ<57>              
                                  AA30     GND                     
                                  AA32     M_J_DQ<47>              
                                  AA34     M_J_DQ<41>              
                                  AA36     GND                     
                                  AA38     M_J_DQ<39>              
                                  AA40     M_J_DQ<33>              
                                  AA42     GND                     
                                  AA46     M_J_CS_N<3>             
                                  AA48     M_J_ODT<1>              
                                  AA50     M_J_ODT<0>              
                                  AA52     M_J_MA<16>              
                                  AA54     M_J_CLK_DN<0>           
                                  AA56     M_J_CLK_DN<2>           
                                  AA58     M_J_MA<4>               
                                  AA60     M_J_BG<0>               
                                  AA62     M_J_CKE<0>              
                                  AA64     GND                     
                                  AA66     GND                     
                                  AA68     GND                     
                                  AA70     M_J_DQ<17>              
                                  AA72     M_J_DQ<20>              
                                  AA74     M_J_DQS_DN<1>           
                                  AA76     GND                     
                                  AA78     GND                     
                                  AA80     GND                     
                                  AA82     GND                     
                                  AA84     M_G_DQ<13>              
                                  AA86     M_G_DQ<12>              
                                  AB1      GND                     
                                  AB3      UPI_CPU1_CPU0_P0P0_DN<4>
                                  AB5      GND                     
                                  AB7      UPI_CPU0_CPU1_P0P0_DN<2>
                                  AB9      UPI_CPU0_CPU1_P0P0_DN<0>
                                  AB11     GND                     
                                  AB13     FM_CPU1_SKTOCC_LVT3_N   
                                  AB15     H_CPU1_THERMTRIP_G_N    
                                  AB17     TP_CPU1_PROC_DIS_G_N    
                                  AB19     UPI_CPU0_CPU1_P1P1_DP<19>
                                  AB21     GND                     
                                  AB23     GND                     
                                  AB25     GND                     
                                  AB27     M_H_DQS_DN<7>           
                                  AB29     GND                     
                                  AB31     GND                     
                                  AB33     M_J_DQS_DN<5>           
                                  AB35     GND                     
                                  AB37     GND                     
                                  AB39     M_J_DQS_DN<4>           
                                  AB41     GND                     
                                  AB43     A_CPU1_GHJ_RCOMP1       
                                  AB45     M_J_C<2>                
                                  AB47     M_J_ODT<3>              
                                  AB49     M_J_CS_N<1>             
                                  AB51     M_J_CS_N<4>             
                                  AB53     M_J_MA<0>               
                                  AB55     M_J_CLK_DP<0>           
                                  AB57     M_J_CLK_DP<2>           
                                  AB59     M_J_MA<6>               
                                  AB61     M_J_ACT_N               
                                  AB63     M_J_CKE<3>              
                                  AB65     GND                     
                                  AB67     M_G_DQS_DN<17>          
                                  AB69     GND                     
                                  AB71     M_J_DQ<21>              
                                  AB73     GND                     
                                  AB75     M_J_DQS_DP<1>           
                                  AB77     M_J_DQ<14>              
                                  AB79     GND                     
                                  AB81     M_H_DQ<11>              
                                  AB83     GND                     
                                  AB85     GND                     
                                  AC2      UPI_CPU1_CPU0_P0P0_DP<5>
                                  AC4      PVCCIO_CPU1             
                                  AC6      UPI_CPU0_CPU1_P0P0_DN<3>
                                  AC8      UPI_CPU0_CPU1_P0P0_DP<1>
                                  AC10     UPI_CPU0_CPU1_P0P0_DP<0>
                                  AC12     XDP_CPU_OBSFN_B1_MBP7_N 
                                  AC14     XDP_CPU1_TDI            
                                  AC16     H_CPU1_PROCHOT_G_N      
                                  AC18     GND                     
                                  AC20     PVCCIO_CPU1             
                                  AC22     GND                     
                                  AC24     M_J_DQS_DN<16>          
                                  AC26     GND                     
                                  AC28     GND                     
                                  AC30     M_J_DQS_DN<15>          
                                  AC32     GND                     
                                  AC34     GND                     
                                  AC36     PVCCIO_CPU1             
                                  AC38     GND                     
                                  AC40     GND                     
                                  AC42     A_CPU1_GHJ_RCOMP2       
                                  AC46     M_J_MA<17>              
                                  AC48     GND                     
                                  AC50     GND                     
                                  AC52     GND                     
                                  AC54     GND                     
                                  AC56     GND                     
                                  AC58     GND                     
                                  AC60     GND                     
                                  AC62     GND                     
                                  AC64     GND                     
                                  AC66     M_G_ECC<6>              
                                  AC68     M_G_ECC<0>              
                                  AC70     GND                     
                                  AC72     GND                     
                                  AC74     M_J_DQ<9>               
                                  AC76     M_J_DQS_DP<10>          
                                  AC78     GND                     
                                  AC80     M_H_DQ<15>              
                                  AC82     M_H_DQ<10>              
                                  AC84     GND                     
                                  AC86     GND                     
                                  AD1      UPI_CPU1_CPU0_P0P0_DN<5>
                                  AD3      GND                     
                                  AD5      UPI_CPU0_CPU1_P0P0_DP<3>
                                  AD7      GND                     
                                  AD9      GND                     
                                  AD11     GND                     
                                  AD13     GND                     
                                  AD15     GND                     
                                  AD17     SMB_DDR_KLM_SDA_G_R     
                                  AD19     GND                     
                                  AD21     GND                     
                                  AD23     M_J_DQ<62>              
                                  AD25     M_J_DQ<56>              
                                  AD27     GND                     
                                  AD29     M_J_DQ<54>              
                                  AD31     M_J_DQ<48>              
                                  AD33     GND                     
                                  AD35     PVCCIO_CPU1             
                                  AD37     PVCCIO_CPU1             
                                  AD39     GND                     
                                  AD41     VSENSE_PMAX_CPU1        
                                  AD43     GND                     
                                  AD45     PVDDQ_GHJ               
                                  AD47     TP_CPU1_RSVD_254        
                                  AD49     TP_CPU1_RSVD_253        
                                  AD51     TP_CPU1_RSVD_252        
                                  AD53     M_J_MA<13>              
                                  AD55     M_J_MA<10>              
                                  AD57     M_J_MA<2>               
                                  AD59     M_J_MA<8>               
                                  AD61     M_J_ALERT_N             
                                  AD63     M_J_CKE<1>              
                                  AD65     M_G_ECC<2>              
                                  AD67     M_G_DQS_DP<17>          
                                  AD69     M_G_ECC<4>              
                                  AD71     GND                     
                                  AD73     GND                     
                                  AD75     GND                     
                                  AD77     M_J_DQS_DN<10>          
                                  AD79     M_H_DQS_DN<1>           
                                  AD81     GND                     
                                  AD83     GND                     
                                  AD85     GND                     
                                  AE2      UPI_CPU1_CPU0_P0P0_DN<7>
                                  AE4      GND                     
                                  AE6      UPI_CPU0_CPU1_P0P0_DP<4>
                                  AE8      GND                     
                                  AE10     PVCCIO_CPU1             
                                  AE12     XDP_CPU_OBSFN_B0_MBP6_N 
                                  AE14     XDP_CPU1_TDO            
                                  AE16     GND                     
                                  AE18     SMB_DDR_KLM_SCL_G_R     
                                  AE20     PU_CPU1_LEGACY_SKT      
                                  AE22     M_J_DQ<58>              
                                  AE24     M_J_DQS_DP<16>          
                                  AE26     M_J_DQ<60>              
                                  AE28     M_J_DQ<50>              
                                  AE30     M_J_DQS_DP<15>          
                                  AE32     M_J_DQ<52>              
                                  AE34     PVCCIO_CPU1             
                                  AE36     PVCCIO_CPU1             
                                  AE38     GND                     
                                  AE40     GND                     
                                  AE42     GND                     
                                  AE46     TP_CPU1_RSVD_251        
                                  AE48     TP_CPU1_RSVD_250        
                                  AE50     TP_CPU1_RSVD_249        
                                  AE52     TP_CPU1_RSVD_248        
                                  AE54     M_J_MA<15>              
                                  AE56     M_J_BA<1>               
                                  AE58     M_J_MA<1>               
                                  AE60     M_J_MA<7>               
                                  AE62     M_J_BG<1>               
                                  AE64     GND                     
                                  AE66     GND                     
                                  AE68     GND                     
                                  AE70     GND                     
                                  AE72     TP_CPU1_RSVD_247        
                                  AE74     M_J_DQ<13>              
                                  AE76     M_J_DQ<8>               
                                  AE78     GND                     
                                  AE80     M_H_DQS_DP<1>           
                                  AE82     M_H_DQ<14>              
                                  AE84     M_G_DQ<3>               
                                  AE86     M_G_DQ<2>               
                                  AF1      GND                     
                                  AF3      UPI_CPU1_CPU0_P0P0_DP<6>
                                  AF5      PVCCIO_CPU1             
                                  AF7      UPI_CPU0_CPU1_P0P0_DN<5>
                                  AF9      GND                     
                                  AF11     TP_XDP_CPU1_OBSDATA_B1_MBP3_N
                                  AF13     H_CPU1_MEMKLM_MEMHOT_G_N
                                  AF15     H_CPU1_FAST_WAKE_N      
                                  AF17     SMB_DDR_GHJ_SDA_G_R     
                                  AF19     TP_CPU1_RSVD_246        
                                  AF21     GND                     
                                  AF23     GND                     
                                  AF25     GND                     
                                  AF27     GND                     
                                  AF29     GND                     
                                  AF31     GND                     
                                  AF33     GND                     
                                  AF35     PVCCIO_CPU1             
                                  AF37     GND                     
                                  AF39     GND                     
                                  AF41     GND                     
                                  AF43     PVCCIN_CPU1             
                                  AF45     PD_CPU1_RSVD_TEST_1     
                                  AF47     TP_CPU1_RSVD_245        
                                  AF49     TP_CPU1_RSVD_244        
                                  AF51     TP_CPU1_RSVD_243        
                                  AF53     TP_CPU1_RSVD_242        
                                  AF55     PVDDQ_GHJ               
                                  AF57     PVDDQ_GHJ               
                                  AF59     PVDDQ_GHJ               
                                  AF61     PVDDQ_GHJ               
                                  AF63     PVDDQ_GHJ               
                                  AF65     M_G_ECC<3>              
                                  AF67     M_G_DQS_DP<8>           
                                  AF69     M_G_ECC<5>              
                                  AF71     TP_CPU1_RSVD_241        
                                  AF73     GND                     
                                  AF75     M_J_DQ<12>              
                                  AF77     GND                     
                                  AF79     M_H_DQ<9>               
                                  AF81     M_H_DQS_DP<10>          
                                  AF83     GND                     
                                  AF85     GND                     
                                  AG2      UPI_CPU1_CPU0_P0P0_DP<7>
                                  AG4      UPI_CPU1_CPU0_P0P0_DN<6>
                                  AG6      UPI_CPU0_CPU1_P0P0_DN<4>
                                  AG8      UPI_CPU0_CPU1_P0P0_DP<5>
                                  AG10     TP_XDP_CPU1_OBSDATA_B0_MBP2_N
                                  AG12     GND                     
                                  AG14     GND                     
                                  AG16     XDP_CPU_PRDY_N          
                                  AG18     GND                     
                                  AG20     TP_CPU1_RSVD_240        
                                  AG22     M_J_DQ<59>              
                                  AG24     M_J_DQS_DP<7>           
                                  AG26     M_J_DQ<61>              
                                  AG28     M_J_DQ<51>              
                                  AG30     M_J_DQS_DP<6>           
                                  AG32     M_J_DQ<53>              
                                  AG34     PVCCIO_CPU1             
                                  AG36     GND                     
                                  AG38     PVCCIN_CPU1             
                                  AG40     PVCCIN_CPU1             
                                  AG42     PVCCIN_CPU1             
                                  AG46     PD_CPU1_RSVD_TEST_2     
                                  AG48     TP_CPU1_RSVD_239        
                                  AG50     TP_CPU1_RSVD_238        
                                  AG52     TP_CPU1_RSVD_237        
                                  AG54     TP_CPU1_RSVD_236        
                                  AG56     TP_CPU1_RSVD_235        
                                  AG58     M_J_MA<9>               
                                  AG60     M_J_MA<11>              
                                  AG62     M_J_MA<12>              
                                  AG64     GND                     
                                  AG66     M_G_ECC<7>              
                                  AG68     M_G_ECC<1>              
                                  AG70     GND                     
                                  AG72     TP_CPU1_RSVD_234        
                                  AG74     GND                     
                                  AG76     GND                     
                                  AG78     GND                     
                                  AG80     GND                     
                                  AG82     M_H_DQS_DN<10>          
                                  AG84     M_G_DQ<7>               
                                  AG86     M_G_DQ<6>               
                                  AH1      GND                     
                                  AH3      UPI_CPU1_CPU0_P0P0_DP<8>
                                  AH5      GND                     
                                  AH7      UPI_CPU0_CPU1_P0P0_DN<6>
                                  AH9      PVCCIO_CPU1             
                                  AH11     XDP_CPU_MBP1_N          
                                  AH13     H_CPU1_MEMGHJ_MEMHOT_G_N
                                  AH15     TP_CPU1_RSVD_233        
                                  AH19     TP_CPU1_RSVD_232        
                                  AH21     GND                     
                                  AH23     M_J_DQ<63>              
                                  AH25     M_J_DQ<57>              
                                  AH27     GND                     
                                  AH29     M_J_DQ<55>              
                                  AH31     M_J_DQ<49>              
                                  AH33     GND                     
                                  AH35     GND                     
                                  AH37     PVCCIN_CPU1             
                                  AH39     PVCCIN_CPU1             
                                  AH41     PVCCIN_CPU1             
                                  AH45     GND                     
                                  AH47     GND                     
                                  AH49     GND                     
                                  AH51     GND                     
                                  AH53     GND                     
                                  AH55     TP_CPU1_RSVD_231        
                                  AH57     TP_CPU1_RSVD_230        
                                  AH59     GND                     
                                  AH61     GND                     
                                  AH63     M_J_CPU_VREF            
                                  AH65     GND                     
                                  AH67     M_G_DQS_DN<8>           
                                  AH69     GND                     
                                  AH71     TP_CPU1_RSVD_229        
                                  AH73     TP_CPU1_RSVD_228        
                                  AH75     GND                     
                                  AH77     GND                     
                                  AH79     M_H_DQ<13>              
                                  AH81     M_H_DQ<8>               
                                  AH83     GND                     
                                  AH85     M_G_DQS_DP<0>           
                                  AJ2      UPI_CPU1_CPU0_P0P0_DN<8>
                                  AJ4      GND                     
                                  AJ6      UPI_CPU0_CPU1_P0P0_DP<6>
                                  AJ8      GND                     
                                  AJ10     XDP_CPU_MBP0_N          
                                  AJ12     H_CPU1_ERR0_G_N         
                                  AJ14     PU_CPU1_EAR_N           
                                  AJ18     SMB_DDR_GHJ_SCL_G_R     
                                  AJ20     TP_CPU1_RSVD_227        
                                  AJ22     GND                     
                                  AJ24     M_J_DQS_DN<7>           
                                  AJ26     GND                     
                                  AJ28     GND                     
                                  AJ30     M_J_DQS_DN<6>           
                                  AJ32     GND                     
                                  AJ34     GND                     
                                  AJ36     PVCCIN_CPU1             
                                  AJ46     GND                     
                                  AJ48     GND                     
                                  AJ50     GND                     
                                  AJ52     GND                     
                                  AJ54     GND                     
                                  AJ56     TP_CPU1_RSVD_226        
                                  AJ58     TP_CPU1_RSVD_225        
                                  AJ60     TP_CPU1_RSVD_224        
                                  AJ62     TP_CPU1_RSVD_223        
                                  AJ64     M_G_CPU_VREF            
                                  AJ66     GND                     
                                  AJ68     GND                     
                                  AJ70     TP_CPU1_RSVD_222        
                                  AJ74     GND                     
                                  AJ76     M_J_DQ<3>               
                                  AJ78     GND                     
                                  AJ80     M_H_DQ<12>              
                                  AJ82     GND                     
                                  AJ84     M_G_DQS_DN<0>           
                                  AJ86     GND                     
                                  AK1      UPI_CPU1_CPU0_P0P0_DP<9>
                                  AK3      UPI_CPU1_CPU0_P0P0_DN<10>
                                  AK5      UPI_CPU0_CPU1_P0P0_DN<7>
                                  AK7      UPI_CPU0_CPU1_P0P0_DP<8>
                                  AK9      GND                     
                                  AK11     H_CPU1_ERR1_G_N         
                                  AK13     GND                     
                                  AK19     GND                     
                                  AK21     VSENSE_P1V8MCP_CPU1_SKT_VSEN
                                  AK23     GND                     
                                  AK25     GND                     
                                  AK27     CLK_322M_OSC_CPU1_RC_DP 
                                  AK29     GND                     
                                  AK31     GND                     
                                  AK33     GND                     
                                  AK35     PVCCIN_CPU1             
                                  AK45     PVCCIN_CPU1             
                                  AK47     PVCCIN_CPU1             
                                  AK49     PVCCIN_CPU1             
                                  AK51     PVCCIN_CPU1             
                                  AK53     PVCCIN_CPU1             
                                  AK55     GND                     
                                  AK57     TP_CPU1_RSVD_219        
                                  AK59     TP_CPU1_RSVD_218        
                                  AK61     TP_CPU1_RSVD_217        
                                  AK63     M_H_CPU_VREF            
                                  AK65     GND                     
                                  AK67     GND                     
                                  AK69     TP_CPU1_RSVD_216        
                                  AK73     GND                     
                                  AK75     M_J_DQ<7>               
                                  AK77     M_J_DQ<2>               
                                  AK79     GND                     
                                  AK81     GND                     
                                  AK83     GND                     
                                  AK85     GND                     
                                  AL2      UPI_CPU1_CPU0_P0P0_DN<9>
                                  AL4      GND                     
                                  AL6      UPI_CPU0_CPU1_P0P0_DP<7>
                                  AL8      UPI_CPU0_CPU1_P0P0_DN<9>
                                  AL10     GND                     
                                  AL12     H_CPU1_ERR2_G_N         
                                  AL14     H_CPU1_CATERR_G_N       
                                  AL18     SMB_CPU1_PE_HP_GTL_SDA  
                                  AL20     VSENSE_P1V8MCP_CPU1_SKT_VRTN
                                  AL22     TP_CPU1_RSVD_214        
                                  AL24     GND                     
                                  AL26     CLK_322M_OSC_CPU1_RC_DN 
                                  AL28     PVCCIO_CPU1             
                                  AL30     GND                     
                                  AL32     GND                     
                                  AL34     PVCCIN_CPU1             
                                  AL46     PVCCIN_CPU1             
                                  AL48     PVCCIN_CPU1             
                                  AL50     PVCCIN_CPU1             
                                  AL52     PVCCIN_CPU1             
                                  AL54     PVCCIN_CPU1             
                                  AL56     GND                     
                                  AL58     TP_CPU1_RSVD_212        
                                  AL60     TP_CPU1_RSVD_211        
                                  AL62     TP_CPU1_RSVD_210        
                                  AL64     GND                     
                                  AL66     M_J_DQS_DN<12>          
                                  AL68     GND                     
                                  AL74     M_J_DQS_DN<0>           
                                  AL76     GND                     
                                  AL78     GND                     
                                  AL80     GND                     
                                  AL82     GND                     
                                  AL84     M_G_DQS_DN<9>           
                                  AL86     GND                     
                                  AM1      GND                     
                                  AM3      UPI_CPU1_CPU0_P0P0_DP<10>
                                  AM5      PVCCIO_CPU1             
                                  AM7      UPI_CPU0_CPU1_P0P0_DN<8>
                                  AM9      UPI_CPU0_CPU1_P0P0_DP<9>
                                  AM11     PU_CPU1_TSC_SYNC        
                                  AM13     TP_CPU1_RSVD_TEST_3     
                                  AM19     SMB_CPU1_PE_HP_GTL_SCL  
                                  AM21     PVCCMCP_CPU1            
                                  AM23     TP_CPU1_RSVD_208        
                                  AM25     PVCCMCP_CPU1            
                                  AM27     CLK_100M_CPU1_RC_REFCLK0_DP
                                  AM29     PVCCIO_CPU1             
                                  AM31     GND                     
                                  AM33     PVCCIN_CPU1             
                                  AM53     PVCCIN_CPU1             
                                  AM55     PVCCIN_CPU1             
                                  AM57     GND                     
                                  AM59     TP_CPU1_RSVD_205        
                                  AM61     TP_CPU1_RSVD_204        
                                  AM63     GND                     
                                  AM65     M_J_DQ<30>              
                                  AM67     M_J_DQ<24>              
                                  AM69     GND                     
                                  AM73     GND                     
                                  AM75     M_J_DQS_DP<0>           
                                  AM77     M_J_DQ<6>               
                                  AM79     GND                     
                                  AM81     M_H_DQ<3>               
                                  AM83     GND                     
                                  AM85     M_G_DQS_DP<9>           
                                  AN2      GND                     
                                  AN4      UPI_CPU1_CPU0_P0P0_DP<11>
                                  AN6      GND                     
                                  AN8      UPI_CPU0_CPU1_P0P0_DP<10>
                                  AN10     PVCCIO_CPU1             
                                  AN12     TP_CPU1_RSVD_TEST_4     
                                  AN14     TP_CPU1_RSVD_TEST_5     
                                  AN18     PVCCMCP_CPU1            
                                  AN20     H_CPU1_MSMI_G_N         
                                  AN22     PVCCMCP_CPU1            
                                  AN24     PVCCMCP_CPU1            
                                  AN26     PVCCMCP_CPU1            
                                  AN28     GND                     
                                  AN30     PWRGD_CPU1_DRAMPWROK_GHJ_G
                                  AN32     PVCCIN_CPU1             
                                  AN54     PVCCIN_CPU1             
                                  AN56     PVCCIN_CPU1             
                                  AN58     GND                     
                                  AN60     TP_CPU1_RSVD_199        
                                  AN62     TP_CPU1_RSVD_198        
                                  AN64     M_J_DQ<26>              
                                  AN66     M_J_DQS_DP<12>          
                                  AN68     M_J_DQ<28>              
                                  AN74     M_J_DQ<1>               
                                  AN76     M_J_DQS_DP<9>           
                                  AN78     GND                     
                                  AN80     M_H_DQ<7>               
                                  AN82     M_H_DQ<2>               
                                  AN84     M_G_DQ<1>               
                                  AN86     M_G_DQ<0>               
                                  AP1      UPI_CPU1_CPU0_P0P0_DN<12>
                                  AP3      UPI_CPU1_CPU0_P0P0_DN<11>
                                  AP5      GND                     
                                  AP7      UPI_CPU0_CPU1_P0P0_DN<10>
                                  AP9      GND                     
                                  AP11     TP_CPU1_NMI             
                                  AP13     GND                     
                                  AP17     XDP_CPU_PWR_DEBUG_N     
                                  AP19     GND                     
                                  AP21     RST_CPU1_G_N            
                                  AP23     PVCCMCP_CPU1            
                                  AP25     PVCCMCP_CPU1            
                                  AP27     CLK_100M_CPU1_RC_REFCLK0_DN
                                  AP29     A_CPU1_UPI01_RBIAS      
                                  AP31     GND                     
                                  AP55     PVCCIN_CPU1             
                                  AP57     PVCCIN_CPU1             
                                  AP59     GND                     
                                  AP61     TP_CPU1_RSVD_194        
                                  AP63     GND                     
                                  AP65     GND                     
                                  AP67     GND                     
                                  AP69     GND                     
                                  AP73     GND                     
                                  AP75     GND                     
                                  AP77     M_J_DQS_DN<9>           
                                  AP79     M_H_DQS_DN<0>           
                                  AP81     GND                     
                                  AP83     GND                     
                                  AP85     GND                     
                                  AR2      UPI_CPU1_CPU0_P0P0_DN<13>
                                  AR4      UPI_CPU1_CPU0_P0P0_DN<14>
                                  AR6      GND                     
                                  AR8      UPI_CPU0_CPU1_P0P0_DP<11>
                                  AR10     GND                     
                                  AR12     XDP_CPU_PREQ_N          
                                  AR14     H_PM_SYNC_GTL_R2        
                                  AR16     TP_CPU1_TEST_6          
                                  AR18     PU_CPU1_SAFE_MODE_BOOT  
                                  AR20     PVCCMCP_CPU1            
                                  AR22     PVCCMCP_CPU1            
                                  AR24     GND                     
                                  AR26     PVCCMCP_CPU1            
                                  AR28     PVCCIO_CPU1             
                                  AR30     GND                     
                                  AR56     PVCCIN_CPU1             
                                  AR58     PVCCIN_CPU1             
                                  AR60     GND                     
                                  AR62     TP_CPU1_RSVD_190        
                                  AR64     M_J_DQ<27>              
                                  AR66     M_J_DQS_DP<3>           
                                  AR68     M_J_DQ<29>              
                                  AR72     GND                     
                                  AR74     M_J_DQ<5>               
                                  AR76     M_J_DQ<0>               
                                  AR78     GND                     
                                  AR80     M_H_DQS_DP<0>           
                                  AR82     M_H_DQ<6>               
                                  AR84     M_G_DQ<5>               
                                  AR86     M_G_DQ<4>               
                                  AT1      UPI_CPU1_CPU0_P0P0_DP<12>
                                  AT3      UPI_CPU1_CPU0_P0P0_DP<13>
                                  AT5      PVCCIO_CPU1             
                                  AT7      PVCCIO_CPU1             
                                  AT9      UPI_CPU0_CPU1_P0P0_DP<12>
                                  AT11     PVCCIO_CPU1             
                                  AT13     TP_CPU1_RSVD_189        
                                  AT15     GND                     
                                  AT17     GND                     
                                  AT19     H_PMSYNC_CLK_24M_CPU1   
                                  AT21     GND                     
                                  AT23     PVCCMCP_CPU1            
                                  AT25     PVCCMCP_CPU1            
                                  AT27     GND                     
                                  AT29     A_CPU1_UPI01_RBIAS      
                                  AT57     PVCCIN_CPU1             
                                  AT59     PVCCIN_CPU1             
                                  AT61     GND                     
                                  AT63     GND                     
                                  AT65     M_J_DQ<31>              
                                  AT67     M_J_DQ<25>              
                                  AT69     GND                     
                                  AT71     M_J_DQS_DN<17>          
                                  AT73     GND                     
                                  AT75     M_J_DQ<4>               
                                  AT77     GND                     
                                  AT79     M_H_DQ<1>               
                                  AT81     M_H_DQS_DP<9>           
                                  AT83     GND                     
                                  AT85     GND                     
                                  AU2      GND                     
                                  AU4      UPI_CPU1_CPU0_P0P0_DP<14>
                                  AU6      GND                     
                                  AU8      UPI_CPU0_CPU1_P0P0_DN<11>
                                  AU10     UPI_CPU0_CPU1_P0P0_DN<12>
                                  AU12     PECI_CPU_G              
                                  AU14     H_CPU1_FIVR_FAULT_G     
                                  AU16     PU_CPU1_SOCKET_ID_1     
                                  AU18     TP_CPU1_TEST_7          
                                  AU20     TP_CPU1_SOCKET_ID_2     
                                  AU22     PU_CPU1_SOCKET_ID_0     
                                  AU24     CLK_100M_CPU1_BCLK0_DN  
                                  AU26     GND                     
                                  AU28     GND                     
                                  AU58     PVCCIN_CPU1             
                                  AU60     PVCCIN_CPU1             
                                  AU62     GND                     
                                  AU64     GND                     
                                  AU66     M_J_DQS_DN<3>           
                                  AU68     GND                     
                                  AU70     M_J_ECC<6>              
                                  AU72     M_J_ECC<0>              
                                  AU74     GND                     
                                  AU76     GND                     
                                  AU78     GND                     
                                  AU80     GND                     
                                  AU82     M_H_DQS_DN<9>           
                                  AU84     GND                     
                                  AU86     GND                     
                                  AV1      GND                     
                                  AV3      GND                     
                                  AV5      UPI_CPU1_CPU0_P0P0_DP<15>
                                  AV7      GND                     
                                  AV9      UPI_CPU0_CPU1_P0P0_DP<16>
                                  AV11     GND                     
                                  AV13     GND                     
                                  AV15     PD_CPU1_TXT_PLTEN       
                                  AV17     PU_CPU1_FRMAGENT        
                                  AV19     GND                     
                                  AV21     XDP_PRESENT_N           
                                  AV23     GND                     
                                  AV25     GND                     
                                  AV27     PVCCIO_CPU1             
                                  AV59     PVCCIN_CPU1             
                                  AV61     PVCCIN_CPU1             
                                  AV63     GND                     
                                  AV65     GND                     
                                  AV67     GND                     
                                  AV69     M_J_ECC<2>              
                                  AV71     M_J_DQS_DP<17>          
                                  AV73     M_J_ECC<4>              
                                  AV75     GND                     
                                  AV77     TP_CPU1_RSVD_186        
                                  AV79     M_H_DQ<5>               
                                  AV81     M_H_DQ<0>               
                                  AV83     GND                     
                                  AV85     VSENSE_VCCINR2PMAX_CPU1 
                                  AW2      GND                     
                                  AW4      UPI_CPU1_CPU0_P0P0_DN<15>
                                  AW6      PVCCIO_CPU1             
                                  AW8      UPI_CPU0_CPU1_P0P0_DN<16>
                                  AW10     GND                     
                                  AW12     PD_CPU1_DMIMODE_OVERRIDE
                                  AW14     PD_CPU1_KSFC_DIS        
                                  AW16     TP_CPU1_TEST_8          
                                  AW18     PU_CPU1_TXT_AGENT       
                                  AW20     TP_CPU1_TEST_9          
                                  AW22     TP_CPU1_TEST_10         
                                  AW24     CLK_100M_CPU1_BCLK0_DP  
                                  AW26     PVCCIO_CPU1             
                                  AW60     PVCCIN_CPU1             
                                  AW62     GND                     
                                  AW64     TP_CPU1_RSVD_184        
                                  AW66     GND                     
                                  AW68     GND                     
                                  AW70     GND                     
                                  AW72     GND                     
                                  AW74     GND                     
                                  AW76     TP_CPU1_RSVD_183        
                                  AW78     GND                     
                                  AW80     M_H_DQ<4>               
                                  AW82     GND                     
                                  AW84     GND                     
                                  AW86     VSENSE_VCCINR2PMAX_CPU1 
                                  AY3      UPI_CPU1_CPU0_P0P0_DN<16>
                                  AY5      GND                     
                                  AY7      UPI_CPU0_CPU1_P0P0_DP<13>
                                  AY9      UPI_CPU0_CPU1_P0P0_DN<17>
                                  AY11     PVCCIO_CPU1             
                                  AY13     TP_CPU1_RSVD_TEST_11    
                                  AY15     GND                     
                                  AY17     GND                     
                                  AY19     PD_CPU1_TEST12          
                                  AY21     GND                     
                                  AY23     GND                     
                                  AY25     GND                     
                                  AY27     PVCCIO_CPU1             
                                  AY61     PVCCIN_CPU1             
                                  AY63     GND                     
                                  AY65     TP_CPU1_RSVD_182        
                                  AY67     TP_CPU1_RSVD_181        
                                  AY69     M_J_ECC<3>              
                                  AY71     M_J_DQS_DP<8>           
                                  AY73     M_J_ECC<5>              
                                  AY75     TP_CPU1_RSVD_180        
                                  AY77     TP_CPU1_RSVD_179        
                                  AY79     GND                     
                                  AY81     GND                     
                                  AY83     TP_CPU1_RSVD_255        
                                  AY85     VSENSE_PVCCIN_CPU1_SKT_VRTN
                                  B3       TP_CPU1_RSVD_299        
                                  B5       GND                     
                                  B7       TP_CPU1_RSVD_298        
                                  B9       GND                     
                                  B11      PVPP_GHJ                
                                  B13      P1V8_MCP_CPU1           
                                  B15      P1V8_MCP_CPU1           
                                  B17      P1V8_MCP_CPU1           
                                  B25      GND                     
                                  B27      M_H_DQ<54>              
                                  B29      M_H_DQ<49>              
                                  B31      GND                     
                                  B33      M_H_DQ<46>              
                                  B35      M_H_DQ<41>              
                                  B37      GND                     
                                  B39      M_G_DQ<38>              
                                  B41      M_G_DQ<33>              
                                  B43      GND                     
                                  B47      PVDDQ_GHJ               
                                  B49      PVDDQ_GHJ               
                                  B51      M_G_CS_N<4>             
                                  B53      PVDDQ_GHJ               
                                  B55      M_G_CLK_DP<1>           
                                  B57      M_G_CLK_DP<3>           
                                  B59      PVDDQ_GHJ               
                                  B61      M_G_ALERT_N             
                                  B63      M_G_CKE<2>              
                                  B71      GND                     
                                  B73      M_H_DQS_DN<12>          
                                  B75      GND                     
                                  B77      TP_CPU1_RSVD_293        
                                  B79      GND                     
                                  B81      TP_CPU1_RSVD_292        
                                  BA2      GND                     
                                  BA4      UPI_CPU1_CPU0_P0P0_DP<16>
                                  BA6      GND                     
                                  BA8      UPI_CPU0_CPU1_P0P0_DN<13>
                                  BA10     UPI_CPU0_CPU1_P0P0_DN<19>
                                  BA12     GND                     
                                  BA14     TP_CPU1_RSVD_178        
                                  BA16     TP_CPU1_RSVD_177        
                                  BA18     TP_CPU1_RSVD_176        
                                  BA20     PD_CPU1_BIST_ENABLE     
                                  BA22     TP_CPU1_RSVD_175        
                                  BA24     PVCCIO_CPU1             
                                  BA26     PVCCIO_CPU1             
                                  BA60     PVCCIN_CPU1             
                                  BA62     GND                     
                                  BA64     TP_CPU1_RSVD_174        
                                  BA66     TP_CPU1_RSVD_173        
                                  BA68     GND                     
                                  BA70     M_J_ECC<7>              
                                  BA72     M_J_ECC<1>              
                                  BA74     GND                     
                                  BA76     TP_CPU1_RSVD_172        
                                  BA78     TP_CPU1_RSVD_171        
                                  BA80     GND                     
                                  BA82     TP_CPU1_RSVD_170        
                                  BA84     GND                     
                                  BA86     VSENSE_PVCCIN_CPU1_SKT_VSEN
                                  BB3      UPI_CPU1_CPU0_P0P0_DN<17>
                                  BB5      PVCCIO_CPU1             
                                  BB7      UPI_CPU0_CPU1_P0P0_DN<14>
                                  BB9      UPI_CPU0_CPU1_P0P0_DP<17>
                                  BB11     UPI_CPU0_CPU1_P0P0_DP<19>
                                  BB13     TP_CPU1_RSVD_169        
                                  BB15     TP_CPU1_RSVD_168        
                                  BB17     TP_CPU1_RSVD_167        
                                  BB19     GND                     
                                  BB21     TP_CPU1_RSVD_166        
                                  BB23     GND                     
                                  BB25     CLK_100M_CPU1_RC_REFCLK1_DN
                                  BB27     PVCCIO_CPU1             
                                  BB61     PVCCIN_CPU1             
                                  BB63     GND                     
                                  BB65     TP_CPU1_RSVD_164        
                                  BB67     TP_CPU1_RSVD_163        
                                  BB69     GND                     
                                  BB71     M_J_DQS_DN<8>           
                                  BB73     GND                     
                                  BB75     GND                     
                                  BB77     GND                     
                                  BB79     GND                     
                                  BB81     GND                     
                                  BB83     GND                     
                                  BB85     PVCCIN_CPU1             
                                  BC2      UPI_CPU1_CPU0_P0P0_DP<17>
                                  BC4      GND                     
                                  BC6      UPI_CPU0_CPU1_P0P0_DP<14>
                                  BC8      GND                     
                                  BC10     UPI_CPU0_CPU1_P0P0_DN<18>
                                  BC12     GND                     
                                  BC14     TP_CPU1_RSVD_162        
                                  BC16     GND                     
                                  BC18     TP_CPU1_RSVD_161        
                                  BC20     TP_CPU1_RSVD_160        
                                  BC22     TP_CPU1_RSVD_159        
                                  BC24     PWRGD_CPU1_G            
                                  BC26     PVCCIO_CPU1             
                                  BC60     PVCCIN_CPU1             
                                  BC62     PVCCIN_CPU1             
                                  BC64     TP_CPU1_RSVD_158        
                                  BC66     TP_CPU1_RSVD_157        
                                  BC68     TP_CPU1_RSVD_156        
                                  BC70     GND                     
                                  BC72     GND                     
                                  BC74     GND                     
                                  BC76     GND                     
                                  BC78     GND                     
                                  BC80     GND                     
                                  BC82     GND                     
                                  BC84     PVCCIN_CPU1             
                                  BD3      UPI_CPU1_CPU0_P0P0_DP<18>
                                  BD5      GND                     
                                  BD7      UPI_CPU0_CPU1_P0P0_DN<15>
                                  BD9      UPI_CPU0_CPU1_P0P0_DP<18>
                                  BD11     GND                     
                                  BD13     PVCCMCP_CPU1            
                                  BD15     GND                     
                                  BD17     TP_CPU1_RSVD_155        
                                  BD19     TP_CPU1_RSVD_154        
                                  BD21     GND                     
                                  BD23     H_CPU1_BMCINIT          
                                  BD25     CLK_100M_CPU1_RC_REFCLK1_DP
                                  BD27     GND                     
                                  BD61     PVCCIN_CPU1             
                                  BD63     GND                     
                                  BD65     TP_CPU1_RSVD_152        
                                  BD67     TP_CPU1_RSVD_151        
                                  BD69     TP_CPU1_RSVD_150        
                                  BD71     GND                     
                                  BD73     PVCCIN_CPU1             
                                  BD75     PVCCIN_CPU1             
                                  BD77     PVCCIN_CPU1             
                                  BD79     PVCCIN_CPU1             
                                  BD81     PVCCIN_CPU1             
                                  BD83     PVCCIN_CPU1             
                                  BD85     PVCCIN_CPU1             
                                  BE4      GND                     
                                  BE6      GND                     
                                  BE8      GND                     
                                  BE10     GND                     
                                  BE12     PVCCMCP_CPU1            
                                  BE14     PVCCMCP_CPU1            
                                  BE16     CLK_156M_OSC_CPU1_HFI_DN
                                  BE18     TP_CPU1_RSVD_149        
                                  BE20     TP_CPU1_RSVD_148        
                                  BE22     TP_CPU1_RSVD_147        
                                  BE24     PVCCIO_CPU1             
                                  BE26     GND                     
                                  BE60     PVCCIN_CPU1             
                                  BE62     PVCCIN_CPU1             
                                  BE64     GND                     
                                  BE66     GND                     
                                  BE68     GND                     
                                  BE70     GND                     
                                  BE72     PVCCIN_CPU1             
                                  BE74     PVCCIN_CPU1             
                                  BE76     PVCCIN_CPU1             
                                  BE78     PVCCIN_CPU1             
                                  BE80     PVCCIN_CPU1             
                                  BE82     PVCCIN_CPU1             
                                  BE84     PVCCIN_CPU1             
                                  BF3      UPI_CPU1_CPU0_P0P0_DN<18>
                                  BF5      VSENSE_PVCCIO_CPU1_SKT_VRTN
                                  BF7      UPI_CPU0_CPU1_P0P0_DP<15>
                                  BF9      GND                     
                                  BF11     PVCCMCP_CPU1            
                                  BF13     PVCCMCP_CPU1            
                                  BF15     GND                     
                                  BF17     GND                     
                                  BF19     GND                     
                                  BF21     TP_CPU1_RSVD_146        
                                  BF23     PVCCIO_CPU1             
                                  BF25     GND                     
                                  BF27     PVCCIO_CPU1             
                                  BF61     PVCCIN_CPU1             
                                  BF63     GND                     
                                  BF65     GND                     
                                  BF67     GND                     
                                  BF69     GND                     
                                  BF71     GND                     
                                  BF73     PVCCIN_CPU1             
                                  BF75     PVCCIN_CPU1             
                                  BF77     PVCCIN_CPU1             
                                  BF79     PVCCIN_CPU1             
                                  BF81     PVCCIN_CPU1             
                                  BF83     PVCCIN_CPU1             
                                  BF85     PVCCIN_CPU1             
                                  BG4      UPI_CPU1_CPU0_P0P0_DP<19>
                                  BG6      GND                     
                                  BG8      GND                     
                                  BG10     GND                     
                                  BG12     PVCCMCP_CPU1            
                                  BG14     PVCCMCP_CPU1            
                                  BG16     CLK_156M_OSC_CPU1_HFI_DP
                                  BG18     TP_CPU1_RSVD_145        
                                  BG20     TP_CPU1_RSVD_144        
                                  BG22     GND                     
                                  BG24     GND                     
                                  BG26     PVCCIO_CPU1             
                                  BG60     PVCCIN_CPU1             
                                  BG62     PVCCIN_CPU1             
                                  BG64     PVCCIN_CPU1             
                                  BG66     PVCCIN_CPU1             
                                  BG68     PVCCIN_CPU1             
                                  BG70     PVCCIN_CPU1             
                                  BG72     GND                     
                                  BG74     GND                     
                                  BG76     GND                     
                                  BG78     GND                     
                                  BG80     GND                     
                                  BG82     GND                     
                                  BG84     PVCCIN_CPU1             
                                  BH3      UPI_CPU1_CPU0_P0P0_DN<19>
                                  BH5      VSENSE_PVCCIO_CPU1_SKT_VSEN
                                  BH7      GND                     
                                  BH9      GND                     
                                  BH11     GND                     
                                  BH13     PVCCMCP_CPU1            
                                  BH15     GND                     
                                  BH17     GND                     
                                  BH19     PVCCMCP_CPU1            
                                  BH21     GND                     
                                  BH23     TP_CD_HFI1_CPU1_I2CDAT  
                                  BH25     PVCCIO_CPU1             
                                  BH27     PVCCIO_CPU1             
                                  BH61     PVCCIN_CPU1             
                                  BH63     PVCCIN_CPU1             
                                  BH65     PVCCIN_CPU1             
                                  BH67     PVCCIN_CPU1             
                                  BH69     PVCCIN_CPU1             
                                  BH71     PVCCIN_CPU1             
                                  BH73     PVCCIN_CPU1             
                                  BH75     PVCCIN_CPU1             
                                  BH77     PVCCIN_CPU1             
                                  BH79     PVCCIN_CPU1             
                                  BH81     PVCCIN_CPU1             
                                  BH83     PVCCIN_CPU1             
                                  BJ4      GND                     
                                  BJ6      GND                     
                                  BJ8      TP_P3E_CPU1_PE2_RSR_RXP<14>
                                  BJ10     TP_P3E_CPU1_PE2_RSR_RXP<15>
                                  BJ12     PVCCMCP_CPU1            
                                  BJ14     PVCCMCP_CPU1            
                                  BJ16     PVCCMCP_CPU1            
                                  BJ18     PVCCMCP_CPU1            
                                  BJ20     PVCCMCP_CPU1            
                                  BJ22     TP_CD_HFI1_CPU1_I2CLK   
                                  BJ24     PVCCIO_CPU1             
                                  BJ26     PVCCIO_CPU1             
                                  BJ60     PVCCIN_CPU1             
                                  BJ62     PVCCIN_CPU1             
                                  BJ64     PVCCIN_CPU1             
                                  BJ66     PVCCIN_CPU1             
                                  BJ68     PVCCIN_CPU1             
                                  BJ70     PVCCIN_CPU1             
                                  BJ72     PVCCIN_CPU1             
                                  BJ74     PVCCIN_CPU1             
                                  BJ76     PVCCIN_CPU1             
                                  BJ78     PVCCIN_CPU1             
                                  BJ80     PVCCIN_CPU1             
                                  BJ82     PVCCIN_CPU1             
                                  BJ84     PVCCIN_CPU1             
                                  BK3      GND                     
                                  BK5      TP_P3E_CPU1_PE2_RSR_TXP<15>
                                  BK7      GND                     
                                  BK9      TP_P3E_CPU1_PE2_RSR_RXN<15>
                                  BK11     GND                     
                                  BK13     PVCCMCP_CPU1            
                                  BK15     PVCCMCP_CPU1            
                                  BK17     PVCCMCP_CPU1            
                                  BK19     GND                     
                                  BK21     TP_LED_CPU1_CD_HFI0_N   
                                  BK23     TP_CD_HFI1_CPU1_RESET_N 
                                  BK25     PVCCIO_CPU1             
                                  BK27     PVCCIO_CPU1             
                                  BK61     PVCCIN_CPU1             
                                  BK63     PVCCIN_CPU1             
                                  BK65     PVCCIN_CPU1             
                                  BK67     PVCCIN_CPU1             
                                  BK69     PVCCIN_CPU1             
                                  BK71     PVCCIN_CPU1             
                                  BK73     PVCCIN_CPU1             
                                  BK75     PVCCIN_CPU1             
                                  BK77     PVCCIN_CPU1             
                                  BK79     PVCCIN_CPU1             
                                  BK81     PVCCIN_CPU1             
                                  BK83     PVCCIN_CPU1             
                                  BL4      TP_P3E_CPU1_PE2_RSR_TXN<14>
                                  BL6      GND                     
                                  BL8      TP_P3E_CPU1_PE2_RSR_RXN<14>
                                  BL10     GND                     
                                  BL12     GND                     
                                  BL14     PVCCMCP_CPU1            
                                  BL16     VSENSE_PVCCMCP_CPU1_SKT_VRTN
                                  BL18     PVCCMCP_CPU1            
                                  BL20     PVCCMCP_CPU1            
                                  BL22     GND                     
                                  BL24     GND                     
                                  BL26     PVCCIO_CPU1             
                                  BL60     PVCCIN_CPU1             
                                  BL62     PVCCIN_CPU1             
                                  BL64     GND                     
                                  BL66     GND                     
                                  BL68     GND                     
                                  BL70     GND                     
                                  BL72     GND                     
                                  BL74     GND                     
                                  BL76     GND                     
                                  BL78     GND                     
                                  BL80     GND                     
                                  BL82     GND                     
                                  BL84     PVCCIN_CPU1             
                                  BM3      TP_P3E_CPU1_PE2_RSR_TXP<14>
                                  BM5      TP_P3E_CPU1_PE2_RSR_TXN<15>
                                  BM7      TP_P3E_CPU1_PE2_RSR_RXP<13>
                                  BM9      GND                     
                                  BM11     PVCCIOMCP_CPU1          
                                  BM13     GND                     
                                  BM15     GND                     
                                  BM17     PVCCMCP_CPU1            
                                  BM19     PVCCMCP_CPU1            
                                  BM21     TP_CD_HFI1_CPU1_INT_N   
                                  BM23     TP_CD_HFI1_CPU1_LED_N   
                                  BM25     GND                     
                                  BM27     PVCCIO_CPU1             
                                  BM61     PVCCIN_CPU1             
                                  BM63     PVCCIN_CPU1             
                                  BM65     PVCCIN_CPU1             
                                  BM67     PVCCIN_CPU1             
                                  BM69     PVCCIN_CPU1             
                                  BM71     PVCCIN_CPU1             
                                  BM73     PVCCIN_CPU1             
                                  BM75     PVCCIN_CPU1             
                                  BM77     PVCCIN_CPU1             
                                  BM79     PVCCIN_CPU1             
                                  BM81     PVCCIN_CPU1             
                                  BM83     PVCCIN_CPU1             
                                  BN4      TP_P3E_CPU1_PE2_RSR_TXP<13>
                                  BN6      GND                     
                                  BN8      TP_P3E_CPU1_PE2_RSR_RXN<13>
                                  BN10     GND                     
                                  BN12     PVCCIOMCP_CPU1          
                                  BN14     PVCCIOMCP_CPU1          
                                  BN16     VSENSE_PVCCMCP_CPU1_SKT_VSEN
                                  BN18     PVCCMCP_CPU1            
                                  BN20     GND                     
                                  BN22     TP_SMB_CPU1_CD_HFI0_I2CCLK
                                  BN24     TP_RST_CPU1_CD_HFI0_N   
                                  BN26     GND                     
                                  BN60     PVCCIN_CPU1             
                                  BN62     PVCCIN_CPU1             
                                  BN64     PVCCIN_CPU1             
                                  BN66     PVCCIN_CPU1             
                                  BN68     PVCCIN_CPU1             
                                  BN70     PVCCIN_CPU1             
                                  BN72     PVCCIN_CPU1             
                                  BN74     PVCCIN_CPU1             
                                  BN76     PVCCIN_CPU1             
                                  BN78     PVCCIN_CPU1             
                                  BN80     PVCCIN_CPU1             
                                  BN82     PVCCIN_CPU1             
                                  BN84     PVCCIN_CPU1             
                                  BP3      GND                     
                                  BP5      TP_P3E_CPU1_PE2_RSR_TXN<13>
                                  BP7      TP_P3E_CPU1_PE2_RSR_RXP<11>
                                  BP9      TP_P3E_CPU1_PE2_RSR_RXP<12>
                                  BP11     PVCCIOMCP_CPU1          
                                  BP13     PVCCIOMCP_CPU1          
                                  BP15     PVCCIOMCP_CPU1          
                                  BP17     PVCCMCP_CPU1            
                                  BP19     TP_IRQ_CPU1_CD_HFI0_N   
                                  BP21     PVCCMCP_CPU1            
                                  BP23     TP_SMB_CPU1_CD_HFI0_I2CDAT
                                  BP25     PVCCIO_CPU1             
                                  BP27     GND                     
                                  BP61     PVCCIN_CPU1             
                                  BP63     PVCCIN_CPU1             
                                  BP65     PVCCIN_CPU1             
                                  BP67     PVCCIN_CPU1             
                                  BP69     PVCCIN_CPU1             
                                  BP71     PVCCIN_CPU1             
                                  BP73     PVCCIN_CPU1             
                                  BP75     PVCCIN_CPU1             
                                  BP77     PVCCIN_CPU1             
                                  BP79     PVCCIN_CPU1             
                                  BP81     PVCCIN_CPU1             
                                  BP83     PVCCIN_CPU1             
                                  BR4      TP_P3E_CPU1_PE2_RSR_TXP<12>
                                  BR6      GND                     
                                  BR8      TP_P3E_CPU1_PE2_RSR_RXN<12>
                                  BR10     GND                     
                                  BR12     PVCCIOMCP_CPU1          
                                  BR14     PVCCIOMCP_CPU1          
                                  BR16     GND                     
                                  BR18     GND                     
                                  BR20     TP_FM_CPU1_CD_HFI0_MODPRST_N
                                  BR22     PVCCMCP_CPU1            
                                  BR24     PVCCMCP_CPU1            
                                  BR26     GND                     
                                  BR60     PVCCIN_CPU1             
                                  BR62     PVCCIN_CPU1             
                                  BR64     GND                     
                                  BR66     GND                     
                                  BR68     GND                     
                                  BR70     GND                     
                                  BR72     GND                     
                                  BR74     GND                     
                                  BR76     GND                     
                                  BR78     GND                     
                                  BR80     GND                     
                                  BR82     GND                     
                                  BR84     PVCCIN_CPU1             
                                  BT3      GND                     
                                  BT5      GND                     
                                  BT7      TP_P3E_CPU1_PE2_RSR_RXN<11>
                                  BT9      GND                     
                                  BT11     PVCCIOMCP_CPU1          
                                  BT13     PVCCIOMCP_CPU1          
                                  BT15     PVCCIOMCP_CPU1          
                                  BT17     VSENSE_PVCCIOMCP_CPU1_SKT_VSEN
                                  BT19     TP_CD_HFI1_CPU1_MODPRST_N
                                  BT21     GND                     
                                  BT23     GND                     
                                  BT25     GND                     
                                  BT27     P1V8_MCP_CPU1           
                                  BT61     PVCCIN_CPU1             
                                  BT63     PVCCIN_CPU1             
                                  BT65     PVCCIN_CPU1             
                                  BT67     PVCCIN_CPU1             
                                  BT69     PVCCIN_CPU1             
                                  BT71     PVCCIN_CPU1             
                                  BT73     PVCCIN_CPU1             
                                  BT75     PVCCIN_CPU1             
                                  BT77     PVCCIN_CPU1             
                                  BT79     PVCCIN_CPU1             
                                  BT81     PVCCIN_CPU1             
                                  BT83     PVCCIN_CPU1             
                                  BU4      TP_P3E_CPU1_PE2_RSR_TXN<12>
                                  BU6      TP_P3E_CPU1_PE2_RSR_RXP<10>
                                  BU8      GND                     
                                  BU10     GND                     
                                  BU12     PVCCIOMCP_CPU1          
                                  BU14     PVCCIOMCP_CPU1          
                                  BU16     VSENSE_PVCCIOMCP_CPU1_SKT_VRTN
                                  BU18     PVCCMCP_CPU1            
                                  BU20     PVCCMCP_CPU1            
                                  BU22     PVCCMCP_CPU1            
                                  BU24     CLK_100M_CPU1_PE_REFCLK_DN
                                  BU26     P1V8_MCP_CPU1           
                                  BU60     PVCCIN_CPU1             
                                  BU62     PVCCIN_CPU1             
                                  BU64     PVCCIN_CPU1             
                                  BU66     PVCCIN_CPU1             
                                  BU68     PVCCIN_CPU1             
                                  BU70     PVCCIN_CPU1             
                                  BU72     PVCCIN_CPU1             
                                  BU74     PVCCIN_CPU1             
                                  BU76     PVCCIN_CPU1             
                                  BU78     PVCCIN_CPU1             
                                  BU80     PVCCIN_CPU1             
                                  BU82     PVCCIN_CPU1             
                                  BU84     PVCCIN_CPU1             
                                  BV3      TP_P3E_CPU1_PE2_RSR_TXP<11>
                                  BV5      GND                     
                                  BV7      TP_P3E_CPU1_PE2_RSR_RXN<10>
                                  BV9      TP_P3E_CPU1_PE2_RSR_RXP<8>
                                  BV11     PVCCIOMCP_CPU1          
                                  BV13     PVCCIOMCP_CPU1          
                                  BV15     PVCCIOMCP_CPU1          
                                  BV17     GND                     
                                  BV19     PVCCMCP_CPU1            
                                  BV21     PVCCMCP_CPU1            
                                  BV23     TP_CPU1_RSVD_124        
                                  BV25     GND                     
                                  BV27     P1V8_MCP_CPU1           
                                  BV61     PVCCIN_CPU1             
                                  BV63     PVCCIN_CPU1             
                                  BV65     PVCCIN_CPU1             
                                  BV67     PVCCIN_CPU1             
                                  BV69     PVCCIN_CPU1             
                                  BV71     PVCCIN_CPU1             
                                  BV73     PVCCIN_CPU1             
                                  BV75     PVCCIN_CPU1             
                                  BV77     PVCCIN_CPU1             
                                  BV79     PVCCIN_CPU1             
                                  BV81     PVCCIN_CPU1             
                                  BV83     PVCCIN_CPU1             
                                  BW4      TP_P3E_CPU1_PE2_RSR_TXN<11>
                                  BW6      GND                     
                                  BW8      TP_P3E_CPU1_PE2_RSR_RXP<9>
                                  BW10     TP_CPU1_RSVD_123        
                                  BW12     GND                     
                                  BW14     GND                     
                                  BW16     GND                     
                                  BW18     GND                     
                                  BW20     PVCCMCP_CPU1            
                                  BW22     TP_CPU1_RSVD_121        
                                  BW24     CLK_100M_CPU1_PE_REFCLK_DP
                                  BW26     GND                     
                                  BW60     PVCCIN_CPU1             
                                  BW62     PVCCIN_CPU1             
                                  BW64     PVCCIN_CPU1             
                                  BW66     PVCCIN_CPU1             
                                  BW68     PVCCIN_CPU1             
                                  BW70     PVCCIN_CPU1             
                                  BW72     GND                     
                                  BW74     GND                     
                                  BW76     GND                     
                                  BW78     GND                     
                                  BW80     GND                     
                                  BW82     GND                     
                                  BW84     PVCCIN_CPU1             
                                  BY3      TP_P3E_CPU1_PE2_RSR_TXP<9>
                                  BY5      TP_P3E_CPU1_PE2_RSR_TXP<10>
                                  BY7      TP_P3E_CPU1_PE2_RSR_RXN<9>
                                  BY9      TP_P3E_CPU1_PE2_RSR_RXN<8>
                                  BY11     GND                     
                                  BY13     GND                     
                                  BY15     GND                     
                                  BY17     GND                     
                                  BY19     PVCCMCP_CPU1            
                                  BY21     JTAG_MCP_CPU1_TDI       
                                  BY23     GND                     
                                  BY25     TP_CPU1_RSVD_119        
                                  BY27     P1V8_MCP_CPU1           
                                  BY61     PVCCIN_CPU1             
                                  BY63     GND                     
                                  BY65     GND                     
                                  BY67     GND                     
                                  BY69     GND                     
                                  BY71     GND                     
                                  BY73     PVCCIN_CPU1             
                                  BY75     PVCCIN_CPU1             
                                  BY77     PVCCIN_CPU1             
                                  BY79     PVCCIN_CPU1             
                                  BY81     PVCCIN_CPU1             
                                  BY83     PVCCIN_CPU1             
                                  C4       GND                     
                                  C6       TP_CPU1_RSVD_291        
                                  C8       GND                     
                                  C10      GND                     
                                  C12      GND                     
                                  C14      GND                     
                                  C16      GND                     
                                  C18      TP_CPU1_RSVD_290        
                                  C24      TP_CPU1_RSVD_289        
                                  C26      M_H_DQ<50>              
                                  C28      M_H_DQS_DP<15>          
                                  C30      M_H_DQ<48>              
                                  C32      M_H_DQ<42>              
                                  C34      M_H_DQS_DP<14>          
                                  C36      M_H_DQ<40>              
                                  C38      M_G_DQ<34>              
                                  C40      M_G_DQS_DP<13>          
                                  C42      M_G_DQ<32>              
                                  C46      PVDDQ_GHJ               
                                  C48      M_G_ODT<1>              
                                  C50      M_G_ODT<0>              
                                  C52      M_G_BA<0>               
                                  C54      M_G_CLK_DN<1>           
                                  C56      M_G_CLK_DN<3>           
                                  C58      M_G_MA<3>               
                                  C60      M_G_MA<8>               
                                  C62      M_G_CKE<0>              
                                  C64      M_G_CKE<1>              
                                  C72      M_H_DQ<30>              
                                  C74      M_H_DQ<25>              
                                  C76      GND                     
                                  C78      GND                     
                                  C80      GND                     
                                  C82      TP_CPU1_RSVD_288        
                                  CA2      GND                     
                                  CA4      TP_P3E_CPU1_PE2_RSR_TXN<10>
                                  CA6      GND                     
                                  CA8      GND                     
                                  CA10     GND                     
                                  CA12     TP_CPU1_UPI2_RSVD_DP21  
                                  CA14     GND                     
                                  CA16     GND                     
                                  CA18     GND                     
                                  CA20     GND                     
                                  CA22     PVCCMCP_CPU1            
                                  CA24     TP_CPU1_RSVD_117        
                                  CA26     GND                     
                                  CA60     PVCCIN_CPU1             
                                  CA62     PVCCIN_CPU1             
                                  CA64     GND                     
                                  CA66     GND                     
                                  CA68     GND                     
                                  CA70     GND                     
                                  CA72     PVCCIN_CPU1             
                                  CA74     PVCCIN_CPU1             
                                  CA76     PVCCIN_CPU1             
                                  CA78     PVCCIN_CPU1             
                                  CA80     PVCCIN_CPU1             
                                  CA82     PVCCIN_CPU1             
                                  CA84     PVCCIN_CPU1             
                                  CB3      TP_P3E_CPU1_PE2_RSR_TXN<9>
                                  CB5      TP_CPU1_RSVD_113        
                                  CB7      GND                     
                                  CB9      GND                     
                                  CB11     TP_CPU1_UPI2_RSVD_DN20  
                                  CB13     PVCCIO_CPU1             
                                  CB15     GND                     
                                  CB17     PVCCIO_CPU1             
                                  CB19     PVCCMCP_CPU1            
                                  CB21     PVCCMCP_CPU1            
                                  CB23     JTAG_MCP_TCK            
                                  CB25     TP_CPU1_RSVD_114        
                                  CB27     GND                     
                                  CB61     PVCCIN_CPU1             
                                  CB63     GND                     
                                  CB65     PVSA_CPU1               
                                  CB67     PVSA_CPU1               
                                  CB69     PVSA_CPU1               
                                  CB71     GND                     
                                  CB73     PVCCIN_CPU1             
                                  CB75     PVCCIN_CPU1             
                                  CB77     PVCCIN_CPU1             
                                  CB79     PVCCIN_CPU1             
                                  CB81     PVCCIN_CPU1             
                                  CB83     PVCCIN_CPU1             
                                  CC2      TP_P3E_CPU1_PE2_RSR_TXN<8>
                                  CC4      GND                     
                                  CC6      TP_CPU1_RSVD_111        
                                  CC8      TP_P3E_CPU1_PE2_RSR_RXP<7>
                                  CC10     TP_CPU1_UPI2_RSVD_DM21  
                                  CC12     TP_CPU1_UPI2_RSVD_DT21  
                                  CC14     GND                     
                                  CC16     GND                     
                                  CC18     GND                     
                                  CC20     PVCCMCP_CPU1            
                                  CC22     JTAG_MCP_CPU1_TDO       
                                  CC24     GND                     
                                  CC26     PVCCIO_CPU1             
                                  CC60     PVCCIN_CPU1             
                                  CC62     PVCCIN_CPU1             
                                  CC64     GND                     
                                  CC66     PVSA_CPU1               
                                  CC68     PVSA_CPU1               
                                  CC70     PVSA_CPU1               
                                  CC72     GND                     
                                  CC74     GND                     
                                  CC76     GND                     
                                  CC78     GND                     
                                  CC80     GND                     
                                  CC82     GND                     
                                  CC84     PVCCIN_CPU1             
                                  CD3      TP_P3E_CPU1_PE2_RSR_TXP<8>
                                  CD5      GND                     
                                  CD7      TP_P3E_CPU1_PE2_RSR_RXP<6>
                                  CD9      PVCCIO_CPU1             
                                  CD11     TP_CPU1_UPI2_RSVD_DK19  
                                  CD13     GND                     
                                  CD15     GND                     
                                  CD17     GND                     
                                  CD19     PVCCMCP_CPU1            
                                  CD21     PVCCMCP_CPU1            
                                  CD23     JTAG_MCP_TRST_N         
                                  CD25     TP_CPU1_RSVD_108        
                                  CD27     PVCCIO_CPU1             
                                  CD61     PVCCIN_CPU1             
                                  CD63     GND                     
                                  CD65     PVSA_CPU1               
                                  CD67     PVSA_CPU1               
                                  CD69     PVSA_CPU1               
                                  CD71     PVSA_CPU1               
                                  CD73     GND                     
                                  CD75     GND                     
                                  CD77     GND                     
                                  CD79     GND                     
                                  CD81     GND                     
                                  CD83     PVCCIN_CPU1             
                                  CD85     PVCCIN_CPU1             
                                  CE2      TP_P3E_CPU1_PE2_RSR_TXP<6>
                                  CE4      TP_P3E_CPU1_PE2_RSR_TXP<7>
                                  CE6      TP_P3E_CPU1_PE2_RSR_RXN<6>
                                  CE8      TP_P3E_CPU1_PE2_RSR_RXN<7>
                                  CE10     GND                     
                                  CE12     TP_CPU1_UPI2_RSVD_DL20  
                                  CE14     GND                     
                                  CE16     GND                     
                                  CE18     PVCCIO_CPU1             
                                  CE20     GND                     
                                  CE22     PVCCMCP_CPU1            
                                  CE24     JTAG_MCP_TMS            
                                  CE26     GND                     
                                  CE60     PVCCIN_CPU1             
                                  CE62     GND                     
                                  CE64     PVSA_CPU1               
                                  CE66     PVSA_CPU1               
                                  CE68     PVSA_CPU1               
                                  CE70     GND                     
                                  CE72     PVSA_CPU1               
                                  CE74     PVSA_CPU1               
                                  CE76     VSENSE_PVSA_CPU1_SKT_VSEN
                                  CE78     TP_CPU1_RSVD_106        
                                  CE80     TP_CPU1_RSVD_105        
                                  CE82     GND                     
                                  CE84     PVCCIN_CPU1             
                                  CF3      TP_P3E_CPU1_PE2_RSR_TXN<7>
                                  CF5      PVCCIO_CPU1             
                                  CF7      TP_P3E_CPU1_PE2_RSR_RXP<5>
                                  CF9      GND                     
                                  CF11     TP_CPU1_UPI2_RSVD_DJ20  
                                  CF13     TP_CPU1_UPI2_RSVD_DH19  
                                  CF15     GND                     
                                  CF17     GND                     
                                  CF19     PVCCMCP_CPU1            
                                  CF21     PVCCMCP_CPU1            
                                  CF23     PVCCMCP_CPU1            
                                  CF25     RST_CD_CPU1_POR_N       
                                  CF27     PVCCIO_CPU1             
                                  CF61     PVCCIN_CPU1             
                                  CF63     GND                     
                                  CF65     PVSA_CPU1               
                                  CF67     PVSA_CPU1               
                                  CF69     GND                     
                                  CF71     GND                     
                                  CF73     PVSA_CPU1               
                                  CF75     PVSA_CPU1               
                                  CF77     GND                     
                                  CF79     TP_CPU1_RSVD_101        
                                  CF81     TP_CPU1_RSVD_100        
                                  CF83     GND                     
                                  CF85     PVCCIN_CPU1             
                                  CG2      TP_P3E_CPU1_PE2_RSR_TXN<6>
                                  CG4      TP_CPU1_DMI_TX_DN0      
                                  CG6      GND                     
                                  CG8      TP_P3E_CPU1_PE2_RSR_RXN<5>
                                  CG10     TP_CPU1_RSVD_99         
                                  CG12     TP_CPU1_UPI2_RSVD_DJ18  
                                  CG14     PVCCIO_CPU1             
                                  CG16     GND                     
                                  CG18     GND                     
                                  CG20     PVCCMCP_CPU1            
                                  CG22     GND                     
                                  CG24     TP_CPU1_RSVD_97         
                                  CG26     PVCCMCP_CPU1            
                                  CG60     PVCCIN_CPU1             
                                  CG62     GND                     
                                  CG64     PVSA_CPU1               
                                  CG66     PVSA_CPU1               
                                  CG68     GND                     
                                  CG70     M_M_DQS_DP<17>          
                                  CG72     GND                     
                                  CG74     PVSA_CPU1               
                                  CG76     VSENSE_PVSA_CPU1_SKT_VRTN
                                  CG78     TP_CPU1_RSVD_95         
                                  CG80     GND                     
                                  CG82     TP_CPU1_RSVD_94         
                                  CG84     PVCCIN_CPU1             
                                  CH1      GND                     
                                  CH3      GND                     
                                  CH5      TP_CPU1_DMI_TX_DP0      
                                  CH7      TP_P3E_CPU1_PE2_RSR_RXP<4>
                                  CH9      PVCCIO_CPU1             
                                  CH11     TP_CPU1_UPI2_RSVD_DG20  
                                  CH13     TP_CPU1_UPI2_RSVD_DH17  
                                  CH15     GND                     
                                  CH17     GND                     
                                  CH19     GND                     
                                  CH21     PVCCMCP_CPU1            
                                  CH23     PVCCMCP_CPU1            
                                  CH25     TP_CPU1_RSVD_91         
                                  CH27     PVCCIO_CPU1             
                                  CH61     PVCCIN_CPU1             
                                  CH63     GND                     
                                  CH65     PVSA_CPU1               
                                  CH67     GND                     
                                  CH69     M_M_ECC<6>              
                                  CH71     M_M_ECC<0>              
                                  CH73     GND                     
                                  CH75     PVSA_CPU1               
                                  CH77     TP_CPU1_RSVD_90         
                                  CH79     GND                     
                                  CH81     GND                     
                                  CH83     GND                     
                                  CH85     PVCCIN_CPU1             
                                  CJ2      GND                     
                                  CJ4      TP_CPU1_DMI_TX_DN1      
                                  CJ6      GND                     
                                  CJ8      GND                     
                                  CJ10     GND                     
                                  CJ12     GND                     
                                  CJ14     TP_CPU1_UPI2_RSVD_DK17  
                                  CJ16     GND                     
                                  CJ18     GND                     
                                  CJ20     PVCCMCP_CPU1            
                                  CJ22     PVCCMCP_CPU1            
                                  CJ24     PVCCMCP_CPU1            
                                  CJ26     PVCCMCP_CPU1            
                                  CJ28     PVCCIO_CPU1             
                                  CJ60     PVCCIN_CPU1             
                                  CJ62     GND                     
                                  CJ64     PVSA_CPU1               
                                  CJ66     PVSA_CPU1               
                                  CJ68     M_M_ECC<2>              
                                  CJ70     M_M_DQS_DN<17>          
                                  CJ72     M_M_ECC<4>              
                                  CJ74     GND                     
                                  CJ76     GND                     
                                  CJ78     GND                     
                                  CJ80     M_L_DQ<5>               
                                  CJ82     GND                     
                                  CJ84     GND                     
                                  CJ86     GND                     
                                  CK1      TP_P3E_CPU1_PE2_RSR_TXP<4>
                                  CK3      TP_P3E_CPU1_PE2_RSR_TXP<5>
                                  CK5      PVCCIO_CPU1             
                                  CK7      TP_P3E_CPU1_PE2_RSR_RXN<4>
                                  CK9      TP_CPU1_DMI_RX_DN0      
                                  CK11     GND                     
                                  CK13     TP_CPU1_UPI2_RSVD_DF17  
                                  CK15     GND                     
                                  CK17     GND                     
                                  CK19     TP_CPU1_RSVD_85         
                                  CK21     GND                     
                                  CK23     PVCCMCP_CPU1            
                                  CK25     PVCCMCP_CPU1            
                                  CK27     GND                     
                                  CK29     A_CPU1_UPI2_RBIAS       
                                  CK59     PVCCIN_CPU1             
                                  CK61     PVCCIN_CPU1             
                                  CK63     GND                     
                                  CK65     GND                     
                                  CK67     GND                     
                                  CK69     GND                     
                                  CK71     GND                     
                                  CK73     GND                     
                                  CK75     GND                     
                                  CK77     TP_CPU1_RSVD_82         
                                  CK79     M_L_DQ<4>               
                                  CK81     M_L_DQ<1>               
                                  CK83     GND                     
                                  CK85     GND                     
                                  CL2      TP_P3E_CPU1_PE2_RSR_TXN<5>
                                  CL4      TP_CPU1_DMI_TX_DP1      
                                  CL6      TP_P3E_CPU1_PE2_RSR_RXP<3>
                                  CL8      GND                     
                                  CL10     TP_CPU1_DMI_RX_DP0      
                                  CL12     PVCCIO_CPU1             
                                  CL14     GND                     
                                  CL16     GND                     
                                  CL18     GND                     
                                  CL20     PVCCIO_CPU1             
                                  CL22     GND                     
                                  CL24     PVCCMCP_CPU1            
                                  CL26     PVCCMCP_CPU1            
                                  CL28     A_CPU1_UPI2_RBIAS       
                                  CL30     A_CPU1_PE012_RBIAS      
                                  CL58     PVCCIN_CPU1             
                                  CL60     PVCCIN_CPU1             
                                  CL62     GND                     
                                  CL64     GND                     
                                  CL66     GND                     
                                  CL68     M_M_ECC<3>              
                                  CL70     M_M_DQS_DP<8>           
                                  CL72     M_M_ECC<5>              
                                  CL74     GND                     
                                  CL76     GND                     
                                  CL78     GND                     
                                  CL80     GND                     
                                  CL82     M_L_DQS_DN<0>           
                                  CL84     M_K_DQ<4>               
                                  CL86     M_K_DQ<5>               
                                  CM1      TP_P3E_CPU1_PE2_RSR_TXN<4>
                                  CM3      TP_CPU1_DMI_TX_DP2      
                                  CM5      GND                     
                                  CM7      TP_P3E_CPU1_PE2_RSR_RXN<3>
                                  CM9      TP_P3E_CPU1_PE2_RSR_RXP<1>
                                  CM11     TP_CPU1_DMI_RX_DN1      
                                  CM13     TP_CPU1_UPI2_RSVD_DG18  
                                  CM15     PVCCIO_CPU1             
                                  CM19     GND                     
                                  CM21     GND                     
                                  CM23     PVCCMCP_CPU1            
                                  CM25     PVCCMCP_CPU1            
                                  CM27     GND                     
                                  CM29     GND                     
                                  CM31     GND                     
                                  CM57     PVCCIN_CPU1             
                                  CM59     PVCCIN_CPU1             
                                  CM61     GND                     
                                  CM63     GND                     
                                  CM65     M_M_DQS_DP<12>          
                                  CM67     GND                     
                                  CM69     M_M_ECC<7>              
                                  CM71     M_M_ECC<1>              
                                  CM73     GND                     
                                  CM75     M_M_DQ<5>               
                                  CM77     GND                     
                                  CM79     M_L_DQ<0>               
                                  CM81     M_L_DQS_DP<0>           
                                  CM83     GND                     
                                  CM85     GND                     
                                  CN2      GND                     
                                  CN4      TP_CPU1_DMI_TX_DN2      
                                  CN6      PVCCIO_CPU1             
                                  CN8      TP_P3E_CPU1_PE2_RSR_RXP<2>
                                  CN10     TP_CPU1_DMI_RX_DP1      
                                  CN12     GND                     
                                  CN14     GND                     
                                  CN18     GND                     
                                  CN20     GND                     
                                  CN22     TP_CPU1_KTI2_AMONV      
                                  CN24     PVCCMCP_CPU1            
                                  CN26     GND                     
                                  CN28     PD_CPU1_MCP01_DMON      
                                  CN30     A_CPU1_PE012_RBIAS      
                                  CN32     GND                     
                                  CN56     PVCCIN_CPU1             
                                  CN58     PVCCIN_CPU1             
                                  CN60     GND                     
                                  CN62     GND                     
                                  CN64     M_M_DQ<30>              
                                  CN66     M_M_DQ<24>              
                                  CN68     GND                     
                                  CN70     M_M_DQS_DN<8>           
                                  CN74     M_M_DQ<4>               
                                  CN76     M_M_DQ<1>               
                                  CN78     GND                     
                                  CN80     M_L_DQS_DN<9>           
                                  CN82     M_L_DQ<7>               
                                  CN84     M_K_DQ<0>               
                                  CN86     M_K_DQ<1>               
                                  CP1      GND                     
                                  CP3      TP_P3E_CPU1_PE2_RSR_TXP<3>
                                  CP5      TP_CPU1_DMI_TX_DN3      
                                  CP7      TP_P3E_CPU1_PE2_RSR_RXN<2>
                                  CP9      TP_P3E_CPU1_PE2_RSR_RXN<1>
                                  CP11     TP_CPU1_DMI_RX_DP2      
                                  CP13     PVCCIO_CPU1             
                                  CP19     GND                     
                                  CP21     GND                     
                                  CP23     PVCCMCP_CPU1            
                                  CP25     GND                     
                                  CP27     CLK_100M_CPU1_BCLK1_DP  
                                  CP29     A_CPU1_PE3_RBIAS        
                                  CP31     TP_CPU1_RSVD_73         
                                  CP33     PVCCIN_CPU1             
                                  CP55     PVCCIN_CPU1             
                                  CP57     PVCCIN_CPU1             
                                  CP59     GND                     
                                  CP61     M_K_CPU_VREF            
                                  CP63     M_M_DQ<26>              
                                  CP65     M_M_DQS_DN<12>          
                                  CP67     M_M_DQ<28>              
                                  CP69     GND                     
                                  CP73     GND                     
                                  CP75     GND                     
                                  CP77     M_M_DQS_DN<0>           
                                  CP79     M_L_DQS_DP<9>           
                                  CP81     GND                     
                                  CP83     GND                     
                                  CP85     M_K_DQS_DP<9>           
                                  CR2      TP_P3E_CPU1_PE2_RSR_TXP<2>
                                  CR4      TP_CPU1_DMI_TX_DP3      
                                  CR6      GND                     
                                  CR8      TP_P3E_CPU1_PE2_RSR_RXP<0>
                                  CR10     GND                     
                                  CR12     TP_CPU1_DMI_RX_DN2      
                                  CR14     TP_CPU1_UPI2_RSVD_DE16  
                                  CR18     GND                     
                                  CR20     GND                     
                                  CR22     GND                     
                                  CR24     GND                     
                                  CR26     CLK_100M_CPU1_BCLK1_DN  
                                  CR28     PWRGD_CPU1_DRAMPWROK_KLM_G
                                  CR30     A_CPU1_PE3_RBIAS        
                                  CR32     GND                     
                                  CR34     PVCCIN_CPU1             
                                  CR54     PVCCIN_CPU1             
                                  CR56     PVCCIN_CPU1             
                                  CR58     GND                     
                                  CR60     TP_CPU1_RSVD_72         
                                  CR62     GND                     
                                  CR64     GND                     
                                  CR66     GND                     
                                  CR68     GND                     
                                  CR74     M_M_DQ<0>               
                                  CR76     M_M_DQS_DP<0>           
                                  CR78     GND                     
                                  CR80     M_L_DQ<6>               
                                  CR82     M_L_DQ<3>               
                                  CR84     M_K_DQS_DN<9>           
                                  CR86     GND                     
                                  CT1      TP_P3E_CPU1_PE2_RSR_TXN<2>
                                  CT3      TP_P3E_CPU1_PE2_RSR_TXN<3>
                                  CT5      TP_CPU1_RSVD_70         
                                  CT7      GND                     
                                  CT9      TP_P3E_CPU1_PE2_RSR_RXN<0>
                                  CT11     TP_CPU1_DMI_RX_DN3      
                                  CT13     GND                     
                                  CT19     GND                     
                                  CT21     GND                     
                                  CT23     PVCCMCP_CPU1            
                                  CT25     CLK_100M_CPU1_BCLK2_DN  
                                  CT27     GND                     
                                  CT29     GND                     
                                  CT31     A_CPU1_MCP01_RBIAS      
                                  CT33     GND                     
                                  CT35     GND                     
                                  CT37     PVCCIN_CPU1             
                                  CT39     PVCCIN_CPU1             
                                  CT41     PVCCIN_CPU1             
                                  CT53     PVCCIN_CPU1             
                                  CT55     PVCCIN_CPU1             
                                  CT57     GND                     
                                  CT59     SMB_PIROM_CPU1_SCL      
                                  CT61     M_L_CPU_VREF            
                                  CT63     M_M_DQ<27>              
                                  CT65     M_M_DQS_DP<3>           
                                  CT67     M_M_DQ<29>              
                                  CT69     TP_CPU1_RSVD_69         
                                  CT73     GND                     
                                  CT75     M_M_DQS_DN<9>           
                                  CT77     M_M_DQ<7>               
                                  CT79     GND                     
                                  CT81     M_L_DQ<2>               
                                  CT83     GND                     
                                  CT85     GND                     
                                  CU2      TP_P3E_CPU1_PE2_RSR_TXP<1>
                                  CU4      GND                     
                                  CU6      TP_CPU1_RSVD_67         
                                  CU8      TP_P3E_CPU1_PE1_MP_RXP<0>
                                  CU10     P3E_CPU1_PE3_MP_RXP<15> 
                                  CU12     PVCCIO_CPU1             
                                  CU14     TP_CPU1_UPI2_RSVD_DD17  
                                  CU18     PVCCIO_CPU1             
                                  CU20     GND                     
                                  CU22     GND                     
                                  CU24     PVCCMCP_CPU1            
                                  CU26     CLK_100M_CPU1_BCLK2_DP  
                                  CU28     GND                     
                                  CU30     GND                     
                                  CU32     A_CPU1_MCP01_RBIAS      
                                  CU34     GND                     
                                  CU36     GND                     
                                  CU38     PVCCIN_CPU1             
                                  CU40     PVCCIN_CPU1             
                                  CU42     PVCCIN_CPU1             
                                  CU52     PVCCIN_CPU1             
                                  CU54     PVCCIN_CPU1             
                                  CU56     GND                     
                                  CU58     PU_PIROM_CPU1_ADDR0     
                                  CU60     TP_CPU1_RSVD_66         
                                  CU62     GND                     
                                  CU64     M_M_DQ<31>              
                                  CU66     M_M_DQ<25>              
                                  CU68     GND                     
                                  CU74     M_M_DQS_DP<9>           
                                  CU76     GND                     
                                  CU78     GND                     
                                  CU80     GND                     
                                  CU82     GND                     
                                  CU84     M_K_DQS_DN<0>           
                                  CU86     GND                     
                                  CV1      GND                     
                                  CV3      TP_P3E_CPU1_PE2_RSR_TXN<1>
                                  CV5      P3E_CPU1_PE3_MP_TXP<15> 
                                  CV7      PVCCIO_CPU1             
                                  CV9      P3E_CPU1_PE3_MP_RXN<15> 
                                  CV11     TP_CPU1_DMI_RX_DP3      
                                  CV13     TP_CPU1_UPI2_RSVD_DD15  
                                  CV17     GND                     
                                  CV19     GND                     
                                  CV21     PVCCIO_CPU1             
                                  CV23     PVCCMCP_CPU1            
                                  CV25     GND                     
                                  CV27     GND                     
                                  CV29     M_M_DQS_DP<16>          
                                  CV31     GND                     
                                  CV33     GND                     
                                  CV35     M_M_DQS_DP<15>          
                                  CV37     GND                     
                                  CV39     GND                     
                                  CV41     GND                     
                                  CV51     PVCCIN_CPU1             
                                  CV53     GND                     
                                  CV55     GND                     
                                  CV57     PD_PIROM_CPU1_ADDR1     
                                  CV59     FM_CPU1_SM_WP           
                                  CV61     M_M_CPU_VREF            
                                  CV63     GND                     
                                  CV65     M_M_DQS_DN<3>           
                                  CV67     GND                     
                                  CV69     TP_CPU1_RSVD_64         
                                  CV73     GND                     
                                  CV75     M_M_DQ<6>               
                                  CV77     M_M_DQ<3>               
                                  CV79     GND                     
                                  CV81     GND                     
                                  CV83     GND                     
                                  CV85     M_K_DQS_DP<0>           
                                  CW2      TP_P3E_CPU1_PE1_MP_TXP<0>
                                  CW4      TP_P3E_CPU1_PE2_RSR_TXP<0>
                                  CW6      GND                     
                                  CW8      TP_P3E_CPU1_PE1_MP_RXN<0>
                                  CW10     P3E_CPU1_PE3_MP_RXP<14> 
                                  CW12     GND                     
                                  CW14     TP_CPU1_UPI2_RSVD_DF15  
                                  CW16     TP_CPU1_UPI2_RSVD_DB15  
                                  CW18     GND                     
                                  CW20     GND                     
                                  CW22     TP_CPU1_KTI2_DFX_DN     
                                  CW24     PVCCMCP_CPU1            
                                  CW26     GND                     
                                  CW28     M_M_DQ<62>              
                                  CW30     M_M_DQ<56>              
                                  CW32     GND                     
                                  CW34     M_M_DQ<54>              
                                  CW36     M_M_DQ<48>              
                                  CW38     GND                     
                                  CW40     GND                     
                                  CW42     GND                     
                                  CW46     PVCCIN_CPU1             
                                  CW48     PVCCIN_CPU1             
                                  CW50     PVCCIN_CPU1             
                                  CW52     GND                     
                                  CW54     GND                     
                                  CW56     PD_PIROM_CPU1_ADDR2     
                                  CW58     SMB_PIROM_CPU1_SDA      
                                  CW60     TP_CPU1_RSVD_61         
                                  CW62     TP_CPU1_RSVD_60         
                                  CW64     GND                     
                                  CW66     GND                     
                                  CW68     GND                     
                                  CW72     FM_CPU1_PKGID1          
                                  CW74     GND                     
                                  CW76     M_M_DQ<2>               
                                  CW78     GND                     
                                  CW80     M_L_DQ<13>              
                                  CW82     GND                     
                                  CW84     M_K_DQ<7>               
                                  CW86     M_K_DQ<6>               
                                  CY1      GND                     
                                  CY3      TP_P3E_CPU1_PE2_RSR_TXN<0>
                                  CY5      P3E_CPU1_PE3_MP_TXN<15> 
                                  CY7      TP_P3E_CPU1_PE1_MP_RXP<1>
                                  CY9      GND                     
                                  CY11     P3E_CPU1_PE3_MP_RXN<14> 
                                  CY13     GND                     
                                  CY15     GND                     
                                  CY17     PVCCIO_CPU1             
                                  CY19     GND                     
                                  CY21     GND                     
                                  CY23     TP_CPU1_RSVD_59         
                                  CY25     PVCCMCP_CPU1            
                                  CY27     M_M_DQ<58>              
                                  CY29     M_M_DQS_DN<16>          
                                  CY31     M_M_DQ<60>              
                                  CY33     M_M_DQ<50>              
                                  CY35     M_M_DQS_DN<15>          
                                  CY37     M_M_DQ<52>              
                                  CY39     TP_CPU1_RSVD_57         
                                  CY41     GND                     
                                  CY45     GND                     
                                  CY47     PVCCIN_CPU1             
                                  CY49     PVCCIN_CPU1             
                                  CY51     GND                     
                                  CY53     TP_CPU1_RSVD_56         
                                  CY55     P3V3_STBY               
                                  CY57     TP_CPU1_RSVD_55         
                                  CY59     GND                     
                                  CY61     GND                     
                                  CY63     TP_CPU1_RSVD_54         
                                  CY65     GND                     
                                  CY67     M_K_DQS_DP<17>          
                                  CY69     GND                     
                                  CY71     FM_CPU1_PROC_ID0        
                                  CY73     TP_CPU1_RSVD_53         
                                  CY75     GND                     
                                  CY77     GND                     
                                  CY79     M_L_DQ<12>              
                                  CY81     M_L_DQ<9>               
                                  CY83     GND                     
                                  CY85     GND                     
                                  D3       GND                     
                                  D5       TP_CPU1_RSVD_287        
                                  D7       PVCCIO_CPU1             
                                  D9       UPI_CPU1_CPU0_P1P1_DP<7>
                                  D11      GND                     
                                  D13      GND                     
                                  D15      UPI_CPU1_CPU0_P1P1_DN<12>
                                  D17      TP_CPU1_RSVD_286        
                                  D25      GND                     
                                  D27      GND                     
                                  D29      GND                     
                                  D31      GND                     
                                  D33      GND                     
                                  D35      GND                     
                                  D37      GND                     
                                  D39      GND                     
                                  D41      GND                     
                                  D43      GND                     
                                  D45      PVDDQ_GHJ               
                                  D47      M_G_CS_N<2>             
                                  D49      M_G_CS_N<5>             
                                  D51      M_G_MA<16>              
                                  D53      M_G_PAR                 
                                  D55      M_G_CLK_DP<0>           
                                  D57      M_G_MA<2>               
                                  D59      M_G_MA<6>               
                                  D61      M_G_BG<0>               
                                  D63      M_G_CKE<3>              
                                  D65      TP_CPU1_RSVD_285        
                                  D71      M_H_DQ<26>              
                                  D73      M_H_DQS_DP<12>          
                                  D75      M_H_DQ<24>              
                                  D77      GND                     
                                  D79      M_H_DQS_DN<11>          
                                  D81      GND                     
                                  D83      TP_CPU1_RSVD_284        
                                  DA2      TP_P3E_CPU1_PE1_MP_TXN<0>
                                  DA4      P3E_CPU1_PE3_MP_TXP<14> 
                                  DA6      GND                     
                                  DA8      TP_P3E_CPU1_PE1_MP_RXN<1>
                                  DA10     TP_P3E_CPU1_PE1_MP_RXP<3>
                                  DA12     P3E_CPU1_PE3_MP_RXP<13> 
                                  DA14     PVCCIO_CPU1             
                                  DA16     TP_CPU1_UPI2_RSVD_DC16  
                                  DA18     GND                     
                                  DA20     GND                     
                                  DA22     GND                     
                                  DA24     PVCCMCP_CPU1            
                                  DA26     GND                     
                                  DA28     GND                     
                                  DA30     GND                     
                                  DA32     GND                     
                                  DA34     GND                     
                                  DA36     GND                     
                                  DA38     GND                     
                                  DA40     TP_CPU1_RSVD_51         
                                  DA42     M_M_DQ<36>              
                                  DA44     GND                     
                                  DA46     GND                     
                                  DA48     GND                     
                                  DA50     GND                     
                                  DA52     TP_CPU1_RSVD_50         
                                  DA54     TP_CPU1_RSVD_49         
                                  DA56     TP_CPU1_RSVD_48         
                                  DA58     M_M_MA<9>               
                                  DA60     M_M_MA<11>              
                                  DA62     M_M_BG<0>               
                                  DA64     GND                     
                                  DA66     M_K_ECC<6>              
                                  DA68     M_K_ECC<0>              
                                  DA70     GND                     
                                  DA72     FM_CPU1_PKGID2          
                                  DA74     GND                     
                                  DA76     GND                     
                                  DA78     GND                     
                                  DA80     GND                     
                                  DA82     M_L_DQS_DN<1>           
                                  DA84     M_K_DQ<3>               
                                  DA86     M_K_DQ<2>               
                                  DB1      TP_P3E_CPU1_PE1_MP_TXP<1>
                                  DB3      GND                     
                                  DB5      P3E_CPU1_PE3_MP_TXN<14> 
                                  DB7      GND                     
                                  DB9      TP_P3E_CPU1_PE1_MP_RXP<2>
                                  DB11     P3E_CPU1_PE3_MP_RXN<13> 
                                  DB13     GND                     
                                  DB15     TP_CPU1_UPI2_RSVD_CW16  
                                  DB17     GND                     
                                  DB19     GND                     
                                  DB21     GND                     
                                  DB23     GND                     
                                  DB25     GND                     
                                  DB27     M_M_DQ<59>              
                                  DB29     M_M_DQS_DP<7>           
                                  DB31     M_M_DQ<61>              
                                  DB33     M_M_DQ<51>              
                                  DB35     M_M_DQS_DP<6>           
                                  DB37     M_M_DQ<53>              
                                  DB39     GND                     
                                  DB41     GND                     
                                  DB45     SVID_DIO0_CPU1          
                                  DB47     GND                     
                                  DB49     GND                     
                                  DB51     PD_CPU1_TEST13          
                                  DB53     PVDDQ_KLM               
                                  DB55     PVDDQ_KLM               
                                  DB57     PVDDQ_KLM               
                                  DB59     PVDDQ_KLM               
                                  DB61     PVDDQ_KLM               
                                  DB63     PVDDQ_KLM               
                                  DB65     M_K_ECC<2>              
                                  DB67     M_K_DQS_DN<17>          
                                  DB69     M_K_ECC<4>              
                                  DB71     FM_CPU1_PROC_ID1        
                                  DB73     GND                     
                                  DB75     M_M_DQ<13>              
                                  DB77     GND                     
                                  DB79     M_L_DQ<8>               
                                  DB81     M_L_DQS_DP<1>           
                                  DB83     GND                     
                                  DB85     GND                     
                                  DC2      TP_P3E_CPU1_PE1_MP_TXN<1>
                                  DC4      TP_P3E_CPU1_PE1_MP_TXP<3>
                                  DC6      P3E_CPU1_PE3_MP_TXP<13> 
                                  DC8      TP_P3E_CPU1_PE1_MP_RXN<2>
                                  DC10     TP_P3E_CPU1_PE1_MP_RXN<3>
                                  DC12     P3E_CPU1_PE3_MP_RXN<12> 
                                  DC14     GND                     
                                  DC16     TP_CPU1_UPI2_RSVD_DA16  
                                  DC18     PVCCIO_CPU1             
                                  DC20     GND                     
                                  DC22     GND                     
                                  DC24     GND                     
                                  DC26     GND                     
                                  DC28     M_M_DQ<63>              
                                  DC30     M_M_DQ<57>              
                                  DC32     GND                     
                                  DC34     M_M_DQ<55>              
                                  DC36     M_M_DQ<49>              
                                  DC38     GND                     
                                  DC40     M_M_DQS_DP<13>          
                                  DC42     GND                     
                                  DC44     SVID_CLK0_CPU1          
                                  DC46     TP_CPU1_RSVD_47         
                                  DC48     A_CPU1_KLM_RCOMP0       
                                  DC50     PD_CPU1_TEST14          
                                  DC52     TP_CPU1_RSVD_46         
                                  DC54     M_M_MA<15>              
                                  DC56     M_M_BA<1>               
                                  DC58     M_M_MA<1>               
                                  DC60     M_M_MA<7>               
                                  DC62     M_M_ACT_N               
                                  DC64     GND                     
                                  DC66     GND                     
                                  DC68     GND                     
                                  DC70     GND                     
                                  DC72     FM_CPU1_PKGID0          
                                  DC74     M_M_DQ<12>              
                                  DC76     M_M_DQ<9>               
                                  DC78     GND                     
                                  DC80     M_L_DQS_DN<10>          
                                  DC82     M_L_DQ<14>              
                                  DC84     GND                     
                                  DC86     GND                     
                                  DD3      TP_P3E_CPU1_PE1_MP_TXP<2>
                                  DD5      P3E_CPU1_PE3_MP_TXN<13> 
                                  DD7      PVCCIO_CPU1             
                                  DD9      TP_P3E_CPU1_PE1_MP_RXP<4>
                                  DD11     GND                     
                                  DD13     P3E_CPU1_PE3_MP_RXP<12> 
                                  DD15     TP_CPU1_UPI2_RSVD_CV13  
                                  DD17     TP_CPU1_UPI2_RSVD_CU14  
                                  DD19     GND                     
                                  DD21     GND                     
                                  DD23     GND                     
                                  DD25     M_L_DQ<58>              
                                  DD27     GND                     
                                  DD29     M_M_DQS_DN<7>           
                                  DD31     GND                     
                                  DD33     GND                     
                                  DD35     M_M_DQS_DN<6>           
                                  DD37     GND                     
                                  DD39     M_M_DQ<38>              
                                  DD41     M_M_DQ<32>              
                                  DD45     PVDDQ_KLM               
                                  DD47     A_CPU1_KLM_RCOMP1       
                                  DD49     A_CPU1_KLM_RCOMP2       
                                  DD51     TP_CPU1_RSVD_45         
                                  DD53     M_M_MA<13>              
                                  DD55     M_M_MA<10>              
                                  DD57     M_M_MA<2>               
                                  DD59     M_M_MA<8>               
                                  DD61     M_M_ALERT_N             
                                  DD63     M_M_CKE<1>              
                                  DD65     M_K_ECC<3>              
                                  DD67     M_K_DQS_DP<8>           
                                  DD69     M_K_ECC<5>              
                                  DD71     GND                     
                                  DD73     GND                     
                                  DD75     GND                     
                                  DD77     M_M_DQS_DN<1>           
                                  DD79     M_L_DQS_DP<10>          
                                  DD81     GND                     
                                  DD83     GND                     
                                  DD85     M_K_DQ<12>              
                                  DE2      TP_P3E_CPU1_PE1_MP_TXN<2>
                                  DE4      TP_P3E_CPU1_PE1_MP_TXN<3>
                                  DE6      GND                     
                                  DE8      GND                     
                                  DE10     TP_P3E_CPU1_PE1_MP_RXN<4>
                                  DE12     P3E_CPU1_PE3_MP_RXP<10> 
                                  DE14     PVCCIO_CPU1             
                                  DE16     TP_CPU1_UPI2_RSVD_CR14  
                                  DE18     GND                     
                                  DE20     GND                     
                                  DE22     GND                     
                                  DE24     GND                     
                                  DE26     M_L_DQS_DP<16>          
                                  DE28     GND                     
                                  DE30     GND                     
                                  DE32     M_M_DQS_DP<14>          
                                  DE34     GND                     
                                  DE36     GND                     
                                  DE38     M_M_DQ<34>              
                                  DE40     M_M_DQS_DN<13>          
                                  DE42     M_M_DQ<37>              
                                  DE44     SVID_ALERT0_CPU1_N      
                                  DE46     M_M_MA<17>              
                                  DE48     GND                     
                                  DE50     GND                     
                                  DE52     GND                     
                                  DE54     GND                     
                                  DE56     GND                     
                                  DE58     GND                     
                                  DE60     GND                     
                                  DE62     GND                     
                                  DE64     GND                     
                                  DE66     M_K_ECC<7>              
                                  DE68     M_K_ECC<1>              
                                  DE70     GND                     
                                  DE72     GND                     
                                  DE74     M_M_DQ<8>               
                                  DE76     M_M_DQS_DP<1>           
                                  DE78     GND                     
                                  DE80     M_L_DQ<10>              
                                  DE82     M_L_DQ<15>              
                                  DE84     M_K_DQ<13>              
                                  DF3      TP_P3E_CPU1_PE1_MP_TXP<4>
                                  DF5      GND                     
                                  DF7      GND                     
                                  DF9      TP_P3E_CPU1_PE1_MP_RXP<5>
                                  DF11     P3E_CPU1_PE3_MP_RXP<11> 
                                  DF13     PVCCIO_CPU1             
                                  DF15     TP_CPU1_UPI2_RSVD_CW14  
                                  DF17     TP_CPU1_UPI2_RSVD_CK13  
                                  DF19     GND                     
                                  DF21     PVCCIO_CPU1             
                                  DF23     GND                     
                                  DF25     M_L_DQ<62>              
                                  DF27     M_L_DQ<56>              
                                  DF29     GND                     
                                  DF31     M_M_DQ<46>              
                                  DF33     M_M_DQ<40>              
                                  DF35     GND                     
                                  DF37     GND                     
                                  DF39     GND                     
                                  DF41     GND                     
                                  DF45     M_M_C<2>                
                                  DF47     M_M_ODT<3>              
                                  DF49     M_M_CS_N<1>             
                                  DF51     M_M_CS_N<4>             
                                  DF53     M_M_MA<0>               
                                  DF55     M_M_CLK_DN<1>           
                                  DF57     M_M_CLK_DN<3>           
                                  DF59     M_M_MA<5>               
                                  DF61     M_M_BG<1>               
                                  DF63     M_M_CKE<3>              
                                  DF65     GND                     
                                  DF67     M_K_DQS_DN<8>           
                                  DF69     GND                     
                                  DF71     M_M_DQ<20>              
                                  DF73     GND                     
                                  DF75     M_M_DQS_DN<10>          
                                  DF77     M_M_DQ<14>              
                                  DF79     GND                     
                                  DF81     M_L_DQ<11>              
                                  DF83     GND                     
                                  DF85     GND                     
                                  DG2      GND                     
                                  DG4      TP_P3E_CPU1_PE1_MP_TXN<4>
                                  DG6      P3E_CPU1_PE3_MP_TXP<12> 
                                  DG8      PVCCIO_CPU1             
                                  DG10     P3E_CPU1_PE3_MP_RXN<11> 
                                  DG12     P3E_CPU1_PE3_MP_RXN<10> 
                                  DG14     GND                     
                                  DG16     GND                     
                                  DG18     TP_CPU1_UPI2_RSVD_CM13  
                                  DG20     TP_CPU1_UPI2_RSVD_CH11  
                                  DG22     GND                     
                                  DG24     GND                     
                                  DG26     M_L_DQS_DN<16>          
                                  DG28     M_L_DQ<60>              
                                  DG30     M_M_DQ<42>              
                                  DG32     M_M_DQS_DN<14>          
                                  DG34     M_M_DQ<44>              
                                  DG36     TP_CPU1_RSVD_44         
                                  DG38     M_M_DQ<35>              
                                  DG40     M_M_DQS_DN<4>           
                                  DG42     M_M_DQ<33>              
                                  DG44     SVID_CLK1_CPU1          
                                  DG46     M_M_CS_N<3>             
                                  DG48     M_M_ODT<1>              
                                  DG50     M_M_ODT<0>              
                                  DG52     M_M_MA<16>              
                                  DG54     M_M_CLK_DP<1>           
                                  DG56     M_M_CLK_DP<3>           
                                  DG58     M_M_MA<3>               
                                  DG60     M_M_MA<12>              
                                  DG62     M_M_CKE<0>              
                                  DG64     TP_CPU1_RSVD_43         
                                  DG66     GND                     
                                  DG68     GND                     
                                  DG70     M_M_DQ<16>              
                                  DG72     M_M_DQ<21>              
                                  DG74     M_M_DQS_DP<10>          
                                  DG76     GND                     
                                  DG78     GND                     
                                  DG80     GND                     
                                  DG82     GND                     
                                  DG84     M_K_DQ<8>               
                                  DH3      TP_P3E_CPU1_PE1_MP_TXP<5>
                                  DH5      P3E_CPU1_PE3_MP_TXP<11> 
                                  DH7      PVCCIO_CPU1             
                                  DH9      TP_P3E_CPU1_PE1_MP_RXN<5>
                                  DH11     P3E_CPU1_PE3_MP_RXP<9>  
                                  DH13     GND                     
                                  DH15     GND                     
                                  DH17     TP_CPU1_UPI2_RSVD_CH13  
                                  DH19     TP_CPU1_UPI2_RSVD_CF13  
                                  DH21     GND                     
                                  DH23     GND                     
                                  DH25     GND                     
                                  DH27     GND                     
                                  DH29     GND                     
                                  DH31     GND                     
                                  DH33     GND                     
                                  DH35     GND                     
                                  DH37     GND                     
                                  DH39     M_M_DQ<39>              
                                  DH41     GND                     
                                  DH45     PVDDQ_KLM               
                                  DH47     PVDDQ_KLM               
                                  DH49     PVDDQ_KLM               
                                  DH51     PVDDQ_KLM               
                                  DH53     PVDDQ_KLM               
                                  DH55     PVDDQ_KLM               
                                  DH57     PVDDQ_KLM               
                                  DH59     PVDDQ_KLM               
                                  DH61     PVDDQ_KLM               
                                  DH63     PVDDQ_KLM               
                                  DH65     TP_CPU1_RSVD_42         
                                  DH67     GND                     
                                  DH69     M_M_DQS_DP<11>          
                                  DH71     GND                     
                                  DH73     GND                     
                                  DH75     M_M_DQ<10>              
                                  DH77     M_M_DQ<15>              
                                  DH79     GND                     
                                  DH81     GND                     
                                  DH83     GND                     
                                  DH85     M_K_DQ<9>               
                                  DJ2      GND                     
                                  DJ4      P3E_CPU1_PE3_MP_TXN<11> 
                                  DJ6      P3E_CPU1_PE3_MP_TXN<12> 
                                  DJ8      TP_P3E_CPU1_PE1_MP_RXP<6>
                                  DJ10     GND                     
                                  DJ12     P3E_CPU1_PE3_MP_RXN<9>  
                                  DJ14     P3E_CPU1_PE3_MP_RXP<7>  
                                  DJ16     PVCCIO_CPU1             
                                  DJ18     TP_CPU1_UPI2_RSVD_CG12  
                                  DJ20     TP_CPU1_UPI2_RSVD_CF11  
                                  DJ22     GND                     
                                  DJ24     M_L_DQ<59>              
                                  DJ26     M_L_DQS_DP<7>           
                                  DJ28     M_L_DQ<61>              
                                  DJ30     M_M_DQ<43>              
                                  DJ32     M_M_DQS_DP<5>           
                                  DJ34     M_M_DQ<45>              
                                  DJ36     TP_CPU1_RSVD_41         
                                  DJ38     GND                     
                                  DJ40     M_M_DQS_DP<4>           
                                  DJ42     GND                     
                                  DJ44     SVID_DIO1_CPU1          
                                  DJ46     M_M_CS_N<2>             
                                  DJ48     M_M_CS_N<5>             
                                  DJ50     M_M_MA<14>              
                                  DJ52     M_M_BA<0>               
                                  DJ54     M_M_CLK_DP<0>           
                                  DJ56     M_M_CLK_DP<2>           
                                  DJ58     M_M_MA<4>               
                                  DJ60     M_L_MA<8>               
                                  DJ62     M_L_BG<0>               
                                  DJ64     PVDDQ_KLM               
                                  DJ66     TP_CPU1_RSVD_40         
                                  DJ68     GND                     
                                  DJ70     M_M_DQS_DN<11>          
                                  DJ72     M_M_DQ<17>              
                                  DJ74     GND                     
                                  DJ76     M_M_DQ<11>              
                                  DJ78     GND                     
                                  DJ80     M_K_DQ<21>              
                                  DJ82     GND                     
                                  DJ84     GND                     
                                  DK3      TP_P3E_CPU1_PE1_MP_TXN<5>
                                  DK5      P3E_CPU1_PE3_MP_TXP<10> 
                                  DK7      GND                     
                                  DK9      TP_P3E_CPU1_PE1_MP_RXN<6>
                                  DK11     TP_P3E_CPU1_PE1_RSR3_RXP<8>
                                  DK13     P3E_CPU1_PE3_MP_RXP<8>  
                                  DK15     TP_CPU1_RSVD_39         
                                  DK17     TP_CPU1_UPI2_RSVD_CJ14  
                                  DK19     TP_CPU1_UPI2_RSVD_CD11  
                                  DK21     PVCCIO_CPU1             
                                  DK23     GND                     
                                  DK25     M_L_DQ<63>              
                                  DK27     M_L_DQ<57>              
                                  DK29     GND                     
                                  DK31     M_M_DQ<47>              
                                  DK33     M_M_DQ<41>              
                                  DK35     GND                     
                                  DK37     TP_CPU1_RSVD_38         
                                  DK39     GND                     
                                  DK41     GND                     
                                  DK45     M_M_CS_N<7>             
                                  DK47     M_L_CS_N<3>             
                                  DK49     M_M_ODT<2>              
                                  DK51     M_M_CS_N<0>             
                                  DK53     M_M_PAR                 
                                  DK55     M_M_CLK_DN<0>           
                                  DK57     M_M_CLK_DN<2>           
                                  DK59     M_M_MA<6>               
                                  DK61     M_L_MA<7>               
                                  DK63     M_M_CKE<2>              
                                  DK65     TP_CPU1_RSVD_37         
                                  DK67     TP_CPU1_RSVD_36         
                                  DK69     M_M_DQ<22>              
                                  DK71     M_M_DQS_DP<2>           
                                  DK73     GND                     
                                  DK75     GND                     
                                  DK77     GND                     
                                  DK79     M_K_DQ<20>              
                                  DK81     M_K_DQ<17>              
                                  DK83     GND                     
                                  DK85     GND                     
                                  DL2      TP_P3E_CPU1_PE1_MP_TXP<6>
                                  DL4      GND                     
                                  DL6      P3E_CPU1_PE3_MP_TXN<10> 
                                  DL8      GND                     
                                  DL10     TP_P3E_CPU1_PE1_MP_RXP<7>
                                  DL12     P3E_CPU1_PE3_MP_RXN<8>  
                                  DL14     P3E_CPU1_PE3_MP_RXN<7>  
                                  DL16     GND                     
                                  DL18     GND                     
                                  DL20     TP_CPU1_UPI2_RSVD_CE12  
                                  DL22     GND                     
                                  DL24     GND                     
                                  DL26     M_L_DQS_DN<7>           
                                  DL28     GND                     
                                  DL30     GND                     
                                  DL32     M_M_DQS_DN<5>           
                                  DL34     GND                     
                                  DL36     GND                     
                                  DL38     TP_CPU1_RSVD_35         
                                  DL40     GND                     
                                  DL42     M_L_DQ<36>              
                                  DL44     SVID_ALERT1_CPU1_N      
                                  DL46     PVDDQ_KLM               
                                  DL48     PVDDQ_KLM               
                                  DL50     PVDDQ_KLM               
                                  DL52     PVDDQ_KLM               
                                  DL54     PVDDQ_KLM               
                                  DL56     PVDDQ_KLM               
                                  DL58     PVDDQ_KLM               
                                  DL60     PVDDQ_KLM               
                                  DL62     PVDDQ_KLM               
                                  DL64     M_L_CKE<2>              
                                  DL66     TP_CPU1_RSVD_34         
                                  DL68     GND                     
                                  DL70     GND                     
                                  DL72     M_M_DQS_DN<2>           
                                  DL74     GND                     
                                  DL76     GND                     
                                  DL78     GND                     
                                  DL80     GND                     
                                  DL82     M_K_DQS_DN<2>           
                                  DL84     M_K_DQS_DP<10>          
                                  DM3      TP_P3E_CPU1_PE1_MP_TXN<6>
                                  DM5      P3E_CPU1_PE3_MP_TXP<9>  
                                  DM7      P3E_CPU1_PE3_MP_TXN<8>  
                                  DM9      TP_P3E_CPU1_PE1_MP_RXN<7>
                                  DM11     TP_P3E_CPU1_PE1_RSR3_RXN<8>
                                  DM13     P3E_CPU1_PE3_MP_RXP<6>  
                                  DM15     GND                     
                                  DM17     PVCCIO_CPU1             
                                  DM19     GND                     
                                  DM21     TP_CPU1_UPI2_RSVD_CC10  
                                  DM23     M_K_DQS_DN<16>          
                                  DM25     GND                     
                                  DM27     GND                     
                                  DM29     M_K_DQS_DN<15>          
                                  DM31     GND                     
                                  DM33     GND                     
                                  DM35     M_K_DQS_DP<14>          
                                  DM37     GND                     
                                  DM39     GND                     
                                  DM41     M_L_DQS_DP<13>          
                                  DM45     M_M_CS_N<6>             
                                  DM47     M_L_ODT<3>              
                                  DM49     M_L_CS_N<5>             
                                  DM51     M_L_MA<14>              
                                  DM53     M_L_BA<0>               
                                  DM55     M_L_CLK_DN<0>           
                                  DM57     M_L_CLK_DN<2>           
                                  DM59     M_L_MA<6>               
                                  DM61     M_L_BG<1>               
                                  DM63     M_L_CKE<0>              
                                  DM65     GND                     
                                  DM67     TP_CPU1_RSVD_33         
                                  DM69     M_M_DQ<18>              
                                  DM71     M_M_DQ<23>              
                                  DM73     GND                     
                                  DM75     M_K_DQS_DP<12>          
                                  DM77     GND                     
                                  DM79     M_K_DQ<16>              
                                  DM81     M_K_DQS_DP<2>           
                                  DM83     GND                     
                                  DM85     M_K_DQS_DN<10>          
                                  DN2      GND                     
                                  DN4      TP_P3E_CPU1_PE1_MP_TXN<7>
                                  DN6      P3E_CPU1_PE3_MP_TXP<8>  
                                  DN8      PVCCIO_CPU1             
                                  DN10     TP_P3E_CPU1_PE1_RSR3_RXP<9>
                                  DN12     GND                     
                                  DN14     P3E_CPU1_PE3_MP_RXN<6>  
                                  DN16     P3E_CPU1_PE3_MP_RXP<4>  
                                  DN18     GND                     
                                  DN20     TP_CPU1_UPI2_RSVD_CB11  
                                  DN22     GND                     
                                  DN24     M_K_DQ<56>              
                                  DN26     GND                     
                                  DN28     M_K_DQ<54>              
                                  DN30     M_K_DQ<48>              
                                  DN32     GND                     
                                  DN34     M_K_DQ<46>              
                                  DN36     M_K_DQ<40>              
                                  DN38     GND                     
                                  DN40     M_L_DQ<38>              
                                  DN42     M_L_DQ<37>              
                                  DN44     GND                     
                                  DN46     M_L_CS_N<7>             
                                  DN48     M_L_ODT<1>              
                                  DN50     M_L_CS_N<1>             
                                  DN52     M_L_MA<16>              
                                  DN54     M_L_CLK_DP<0>           
                                  DN56     M_L_CLK_DP<2>           
                                  DN58     M_L_MA<5>               
                                  DN60     M_L_MA<12>              
                                  DN62     TP_CPU1_RSVD_32         
                                  DN64     M_L_CKE<1>              
                                  DN66     TP_CPU1_RSVD_31         
                                  DN68     GND                     
                                  DN70     M_M_DQ<19>              
                                  DN72     GND                     
                                  DN74     M_K_DQ<30>              
                                  DN76     M_K_DQ<24>              
                                  DN78     GND                     
                                  DN80     M_K_DQS_DN<11>          
                                  DN82     M_K_DQ<23>              
                                  DN84     M_K_DQS_DN<1>           
                                  DP3      TP_P3E_CPU1_PE1_MP_TXP<7>
                                  DP5      P3E_CPU1_PE3_MP_TXN<9>  
                                  DP7      P3E_CPU1_PE3_MP_TXP<7>  
                                  DP9      GND                     
                                  DP11     TP_P3E_CPU1_PE1_RSR3_RXN<9>
                                  DP13     TP_P3E_CPU1_PE1_RSR3_RXP<11>
                                  DP15     P3E_CPU1_PE3_MP_RXP<5>  
                                  DP17     TP_CPU1_RSVD_30         
                                  DP19     PVCCIO_CPU1             
                                  DP21     TP_CPU1_UPI2_RSVD_CA12  
                                  DP23     M_K_DQS_DP<16>          
                                  DP25     M_K_DQ<60>              
                                  DP27     M_K_DQ<50>              
                                  DP29     M_K_DQS_DP<15>          
                                  DP31     M_K_DQ<52>              
                                  DP33     M_K_DQ<42>              
                                  DP35     M_K_DQS_DN<14>          
                                  DP37     M_K_DQ<44>              
                                  DP39     M_L_DQ<34>              
                                  DP41     M_L_DQS_DN<13>          
                                  DP45     GND                     
                                  DP47     GND                     
                                  DP49     GND                     
                                  DP51     GND                     
                                  DP53     GND                     
                                  DP55     GND                     
                                  DP57     GND                     
                                  DP59     GND                     
                                  DP61     GND                     
                                  DP63     GND                     
                                  DP65     TP_CPU1_RSVD_29         
                                  DP67     GND                     
                                  DP69     GND                     
                                  DP71     GND                     
                                  DP73     M_K_DQ<26>              
                                  DP75     M_K_DQS_DN<12>          
                                  DP77     M_K_DQ<28>              
                                  DP79     M_K_DQS_DP<11>          
                                  DP81     GND                     
                                  DP83     GND                     
                                  DP85     M_K_DQS_DP<1>           
                                  DR2      PVCCIO_CPU1             
                                  DR4      TP_P3E_CPU1_PE1_RSR3_TXP<8>
                                  DR6      GND                     
                                  DR8      P3E_CPU1_PE3_MP_TXN<7>  
                                  DR10     PVCCIO_CPU1             
                                  DR12     TP_P3E_CPU1_PE1_RSR3_RXP<10>
                                  DR14     P3E_CPU1_PE3_MP_RXN<5>  
                                  DR16     P3E_CPU1_PE3_MP_RXN<4>  
                                  DR18     P3E_CPU1_PE3_MP_RXP<3>  
                                  DR20     GND                     
                                  DR22     GND                     
                                  DR24     GND                     
                                  DR26     GND                     
                                  DR28     GND                     
                                  DR30     GND                     
                                  DR32     GND                     
                                  DR34     GND                     
                                  DR36     GND                     
                                  DR38     GND                     
                                  DR40     GND                     
                                  DR42     GND                     
                                  DR44     TP_CPU1_RSVD_28         
                                  DR46     M_L_CS_N<2>             
                                  DR48     M_L_MA<17>              
                                  DR50     M_L_ODT<0>              
                                  DR52     M_L_MA<15>              
                                  DR54     M_L_CLK_DN<1>           
                                  DR56     M_L_CLK_DP<3>           
                                  DR58     M_L_MA<3>               
                                  DR60     M_L_MA<11>              
                                  DR62     M_L_ACT_N               
                                  DR64     M_L_CKE<3>              
                                  DR66     GND                     
                                  DR68     GND                     
                                  DR70     GND                     
                                  DR72     GND                     
                                  DR74     GND                     
                                  DR76     GND                     
                                  DR78     GND                     
                                  DR80     M_K_DQ<22>              
                                  DR82     M_K_DQ<19>              
                                  DR84     M_K_DQ<14>              
                                  DT3      GND                     
                                  DT5      TP_P3E_CPU1_PE1_RSR3_TXN<8>
                                  DT7      TP_P3E_CPU1_PE1_RSR3_TXP<12>
                                  DT9      P3E_CPU1_PE3_MP_TXP<6>  
                                  DT11     TP_P3E_CPU1_PE1_RSR3_RXN<10>
                                  DT13     TP_P3E_CPU1_PE1_RSR3_RXN<11>
                                  DT15     TP_P3E_CPU1_PE1_RSR3_RXP<15>
                                  DT17     GND                     
                                  DT19     P3E_CPU1_PE3_MP_RXN<3>  
                                  DT21     TP_CPU1_UPI2_RSVD_CC12  
                                  DT23     M_K_DQS_DP<7>           
                                  DT25     M_K_DQ<61>              
                                  DT27     M_K_DQ<51>              
                                  DT29     M_K_DQS_DP<6>           
                                  DT31     M_K_DQ<53>              
                                  DT33     M_K_DQ<43>              
                                  DT35     M_K_DQS_DP<5>           
                                  DT37     M_K_DQ<45>              
                                  DT39     M_L_DQ<35>              
                                  DT41     M_L_DQS_DP<4>           
                                  DT45     M_L_CS_N<6>             
                                  DT47     M_L_C<2>                
                                  DT49     M_L_ODT<2>              
                                  DT51     M_L_MA<13>              
                                  DT53     M_L_CLK_DP<1>           
                                  DT55     M_L_MA<10>              
                                  DT57     M_L_CLK_DN<3>           
                                  DT59     M_L_MA<4>               
                                  DT61     M_L_ALERT_N             
                                  DT63     M_K_MA<12>              
                                  DT65     GND                     
                                  DT67     M_L_DQS_DP<17>          
                                  DT69     GND                     
                                  DT71     TP_CPU1_RSVD_27         
                                  DT73     M_K_DQ<27>              
                                  DT75     M_K_DQS_DP<3>           
                                  DT77     M_K_DQ<29>              
                                  DT79     GND                     
                                  DT81     M_K_DQ<18>              
                                  DT83     GND                     
                                  DT85     GND                     
                                  DU2      TP_P3E_CPU1_PE1_RSR3_TXP<9>
                                  DU4      TP_P3E_CPU1_PE1_RSR3_TXP<10>
                                  DU6      TP_P3E_CPU1_PE1_RSR3_TXN<11>
                                  DU8      P3E_CPU1_PE3_MP_TXN<6>  
                                  DU10     GND                     
                                  DU12     TP_P3E_CPU1_PE1_RSR3_RXP<12>
                                  DU14     GND                     
                                  DU16     TP_P3E_CPU1_PE1_RSR3_RXN<15>
                                  DU18     P3E_CPU1_PE3_MP_RXP<1>  
                                  DU20     PVCCIO_CPU1             
                                  DU22     GND                     
                                  DU24     M_K_DQ<57>              
                                  DU26     GND                     
                                  DU28     M_K_DQ<55>              
                                  DU30     M_K_DQ<49>              
                                  DU32     GND                     
                                  DU34     M_K_DQ<47>              
                                  DU36     M_K_DQ<41>              
                                  DU38     GND                     
                                  DU40     M_L_DQ<39>              
                                  DU42     M_L_DQ<32>              
                                  DU44     TP_CPU1_RSVD_26         
                                  DU46     PVDDQ_KLM               
                                  DU48     PVDDQ_KLM               
                                  DU50     PVDDQ_KLM               
                                  DU52     PVDDQ_KLM               
                                  DU54     PVDDQ_KLM               
                                  DU56     PVDDQ_KLM               
                                  DU58     PVDDQ_KLM               
                                  DU60     PVDDQ_KLM               
                                  DU62     PVDDQ_KLM               
                                  DU64     PVDDQ_KLM               
                                  DU66     M_L_ECC<6>              
                                  DU68     M_L_ECC<4>              
                                  DU70     GND                     
                                  DU72     GND                     
                                  DU74     M_K_DQ<31>              
                                  DU76     M_K_DQ<25>              
                                  DU78     GND                     
                                  DU80     GND                     
                                  DU82     GND                     
                                  DU84     GND                     
                                  DV3      TP_P3E_CPU1_PE1_RSR3_TXN<9>
                                  DV5      TP_P3E_CPU1_PE1_RSR3_TXP<11>
                                  DV7      TP_P3E_CPU1_PE1_RSR3_TXN<12>
                                  DV9      P3E_CPU1_PE3_MP_TXP<5>  
                                  DV11     PVCCIO_CPU1             
                                  DV13     TP_P3E_CPU1_PE1_RSR3_RXN<12>
                                  DV15     TP_P3E_CPU1_PE1_RSR3_RXP<14>
                                  DV17     P3E_CPU1_PE3_MP_RXP<2>  
                                  DV19     GND                     
                                  DV21     GND                     
                                  DV23     M_K_DQS_DN<7>           
                                  DV25     GND                     
                                  DV27     GND                     
                                  DV29     M_K_DQS_DN<6>           
                                  DV31     GND                     
                                  DV33     GND                     
                                  DV35     M_K_DQS_DN<5>           
                                  DV37     GND                     
                                  DV39     GND                     
                                  DV41     M_L_DQS_DN<4>           
                                  DV45     M_K_CS_N<6>             
                                  DV47     M_K_C<2>                
                                  DV49     M_K_MA<15>              
                                  DV51     M_L_CS_N<0>             
                                  DV53     M_L_PAR                 
                                  DV55     M_L_BA<1>               
                                  DV57     M_L_MA<2>               
                                  DV59     M_L_MA<9>               
                                  DV61     TP_CPU1_RSVD_25         
                                  DV63     M_KLM_RST_N             
                                  DV65     M_L_ECC<2>              
                                  DV67     M_L_DQS_DN<17>          
                                  DV69     M_L_ECC<5>              
                                  DV71     TP_CPU1_RSVD_24         
                                  DV73     GND                     
                                  DV75     M_K_DQS_DN<3>           
                                  DV77     GND                     
                                  DV79     M_L_DQS_DP<11>          
                                  DV81     GND                     
                                  DV83     M_K_DQ<10>              
                                  DV85     M_K_DQ<15>              
                                  DW2      GND                     
                                  DW4      TP_P3E_CPU1_PE1_RSR3_TXN<10>
                                  DW6      TP_P3E_CPU1_PE1_RSR3_TXP<13>
                                  DW8      GND                     
                                  DW10     P3E_CPU1_PE3_MP_TXN<5>  
                                  DW12     GND                     
                                  DW14     TP_P3E_CPU1_PE1_RSR3_RXN<13>
                                  DW16     P3E_CPU1_PE3_MP_RXN<2>  
                                  DW18     P3E_CPU1_PE3_MP_RXN<1>  
                                  DW20     GND                     
                                  DW22     M_K_DQ<63>              
                                  DW24     GND                     
                                  DW26     M_L_DQS_DP<15>          
                                  DW28     GND                     
                                  DW30     GND                     
                                  DW32     M_L_DQS_DP<14>          
                                  DW34     GND                     
                                  DW36     GND                     
                                  DW38     M_K_DQS_DP<13>          
                                  DW40     GND                     
                                  DW42     M_L_DQ<33>              
                                  DW44     TP_CPU1_RSVD_23         
                                  DW46     TP_CPU1_RSVD_22         
                                  DW48     M_K_MA<13>              
                                  DW50     M_L_CS_N<4>             
                                  DW52     M_L_MA<0>               
                                  DW54     M_K_MA<10>              
                                  DW56     M_K_CLK_DN<2>           
                                  DW58     M_L_MA<1>               
                                  DW60     M_K_ACT_N               
                                  DW62     M_K_BG<1>               
                                  DW64     GND                     
                                  DW66     GND                     
                                  DW68     GND                     
                                  DW70     GND                     
                                  DW72     GND                     
                                  DW74     GND                     
                                  DW76     GND                     
                                  DW78     M_L_DQ<22>              
                                  DW80     M_L_DQ<16>              
                                  DW82     GND                     
                                  DW84     GND                     
                                  DY3      TP_CPU1_RSVD_21         
                                  DY5      GND                     
                                  DY7      TP_P3E_CPU1_PE1_RSR3_TXN<13>
                                  DY9      P3E_CPU1_PE3_MP_TXP<4>  
                                  DY11     P3E_CPU1_PE3_MP_TXN<3>  
                                  DY13     TP_P3E_CPU1_PE1_RSR3_RXP<13>
                                  DY15     TP_P3E_CPU1_PE1_RSR3_RXN<14>
                                  DY17     P3E_CPU1_PE3_MP_RXP<0>  
                                  DY19     GND                     
                                  DY21     M_K_DQ<58>              
                                  DY23     GND                     
                                  DY25     M_L_DQ<54>              
                                  DY27     M_L_DQ<52>              
                                  DY29     GND                     
                                  DY31     M_L_DQ<46>              
                                  DY33     M_L_DQ<44>              
                                  DY35     GND                     
                                  DY37     M_K_DQ<38>              
                                  DY39     M_K_DQ<36>              
                                  DY41     GND                     
                                  DY45     GND                     
                                  DY47     GND                     
                                  DY49     GND                     
                                  DY51     GND                     
                                  DY53     GND                     
                                  DY55     GND                     
                                  DY57     GND                     
                                  DY59     GND                     
                                  DY61     GND                     
                                  DY63     GND                     
                                  DY65     M_L_ECC<3>              
                                  DY67     M_L_DQS_DP<8>           
                                  DY69     M_L_ECC<0>              
                                  DY71     GND                     
                                  DY73     M_L_DQS_DP<12>          
                                  DY75     GND                     
                                  DY77     M_L_DQ<18>              
                                  DY79     M_L_DQS_DN<11>          
                                  DY81     M_L_DQ<20>              
                                  DY83     M_K_DQ<11>              
                                  DY85     GND                     
                                  E2       TP_CPU1_RSVD_283        
                                  E4       TP_CPU1_RSVD_282        
                                  E6       GND                     
                                  E8       GND                     
                                  E10      UPI_CPU1_CPU0_P1P1_DN<8>
                                  E12      UPI_CPU1_CPU0_P1P1_DN<10>
                                  E14      UPI_CPU1_CPU0_P1P1_DP<12>
                                  E16      GND                     
                                  E18      GND                     
                                  E20      GND                     
                                  E22      GND                     
                                  E24      TP_CPU1_RSVD_281        
                                  E26      M_H_DQ<51>              
                                  E28      M_H_DQS_DP<6>           
                                  E30      M_H_DQ<52>              
                                  E32      M_H_DQ<43>              
                                  E34      M_H_DQS_DP<5>           
                                  E36      M_H_DQ<44>              
                                  E38      M_G_DQ<35>              
                                  E40      M_G_DQS_DP<4>           
                                  E42      M_G_DQ<36>              
                                  E46      PVDDQ_GHJ               
                                  E48      PVDDQ_GHJ               
                                  E50      PVDDQ_GHJ               
                                  E52      PVDDQ_GHJ               
                                  E54      PVDDQ_GHJ               
                                  E56      PVDDQ_GHJ               
                                  E58      PVDDQ_GHJ               
                                  E60      PVDDQ_GHJ               
                                  E62      PVDDQ_GHJ               
                                  E64      PVDDQ_GHJ               
                                  E66      GND                     
                                  E72      GND                     
                                  E74      GND                     
                                  E76      GND                     
                                  E78      M_H_DQ<22>              
                                  E80      M_H_DQ<16>              
                                  E82      GND                     
                                  E84      TP_CPU1_RSVD_280        
                                  EA4      TP_CPU1_RSVD_20         
                                  EA6      GND                     
                                  EA8      TP_P3E_CPU1_PE1_RSR3_TXN<14>
                                  EA10     P3E_CPU1_PE3_MP_TXP<3>  
                                  EA12     PVCCIO_CPU1             
                                  EA14     GND                     
                                  EA16     GND                     
                                  EA18     P3E_CPU1_PE3_MP_RXN<0>  
                                  EA20     GND                     
                                  EA22     GND                     
                                  EA24     M_L_DQ<50>              
                                  EA26     M_L_DQS_DN<15>          
                                  EA28     M_L_DQ<53>              
                                  EA30     M_L_DQ<42>              
                                  EA32     M_L_DQS_DN<14>          
                                  EA34     M_L_DQ<45>              
                                  EA36     M_K_DQ<34>              
                                  EA38     M_K_DQS_DN<13>          
                                  EA40     M_K_DQ<37>              
                                  EA42     GND                     
                                  EA44     TP_CPU1_RSVD_19         
                                  EA46     M_K_MA<17>              
                                  EA48     M_K_ODT<3>              
                                  EA50     M_K_ODT<2>              
                                  EA52     M_K_MA<16>              
                                  EA54     M_K_BA<1>               
                                  EA56     M_K_CLK_DP<2>           
                                  EA58     M_K_MA<5>               
                                  EA60     M_K_MA<7>               
                                  EA62     M_K_CKE<2>              
                                  EA64     GND                     
                                  EA66     M_L_ECC<7>              
                                  EA68     M_L_ECC<1>              
                                  EA70     GND                     
                                  EA72     M_L_DQ<30>              
                                  EA74     M_L_DQ<28>              
                                  EA76     GND                     
                                  EA78     GND                     
                                  EA80     GND                     
                                  EA82     GND                     
                                  EA84     GND                     
                                  EB3      TP_CPU1_RSVD_18         
                                  EB5      TP_CPU1_RSVD_17         
                                  EB7      TP_P3E_CPU1_PE1_RSR3_TXP<14>
                                  EB9      P3E_CPU1_PE3_MP_TXN<4>  
                                  EB11     P3E_CPU1_PE3_MP_TXP<2>  
                                  EB13     GND                     
                                  EB15     PVCCIO_CPU1             
                                  EB21     M_K_DQ<59>              
                                  EB23     GND                     
                                  EB25     GND                     
                                  EB27     GND                     
                                  EB29     GND                     
                                  EB31     GND                     
                                  EB33     GND                     
                                  EB35     GND                     
                                  EB37     GND                     
                                  EB39     GND                     
                                  EB41     GND                     
                                  EB45     M_K_CS_N<7>             
                                  EB47     M_K_CS_N<3>             
                                  EB49     M_K_CS_N<5>             
                                  EB51     M_K_CS_N<4>             
                                  EB53     M_K_MA<0>               
                                  EB55     M_K_CLK_DP<0>           
                                  EB57     M_K_MA<3>               
                                  EB59     M_K_MA<8>               
                                  EB61     M_K_MA<11>              
                                  EB63     M_K_CKE<3>              
                                  EB65     GND                     
                                  EB67     M_L_DQS_DN<8>           
                                  EB69     GND                     
                                  EB71     M_L_DQ<26>              
                                  EB73     M_L_DQS_DN<12>          
                                  EB75     M_L_DQ<29>              
                                  EB77     M_L_DQ<19>              
                                  EB79     M_L_DQS_DP<2>           
                                  EB81     M_L_DQ<21>              
                                  EB83     GND                     
                                  EB85     TP_CPU1_RSVD_16         
                                  EC4      TP_CPU1_RSVD_14         
                                  EC6      GND                     
                                  EC8      TP_P3E_CPU1_PE1_RSR3_TXP<15>
                                  EC10     GND                     
                                  EC12     P3E_CPU1_PE3_MP_TXN<2>  
                                  EC14     P3E_CPU1_PE3_MP_TXP<0>  
                                  EC16     TP_CPU1_RSVD_15         
                                  EC22     M_K_DQ<62>              
                                  EC24     M_L_DQ<51>              
                                  EC26     M_L_DQS_DP<6>           
                                  EC28     M_L_DQ<48>              
                                  EC30     M_L_DQ<43>              
                                  EC32     M_L_DQS_DP<5>           
                                  EC34     M_L_DQ<40>              
                                  EC36     M_K_DQ<35>              
                                  EC38     M_K_DQS_DP<4>           
                                  EC40     M_K_DQ<32>              
                                  EC42     GND                     
                                  EC44     TP_CPU1_RSVD_13         
                                  EC46     PVDDQ_KLM               
                                  EC48     PVDDQ_KLM               
                                  EC50     PVDDQ_KLM               
                                  EC52     PVDDQ_KLM               
                                  EC54     PVDDQ_KLM               
                                  EC56     PVDDQ_KLM               
                                  EC58     PVDDQ_KLM               
                                  EC60     PVDDQ_KLM               
                                  EC62     PVDDQ_KLM               
                                  EC70     GND                     
                                  EC72     GND                     
                                  EC74     GND                     
                                  EC76     GND                     
                                  EC78     M_L_DQ<23>              
                                  EC80     M_L_DQ<17>              
                                  EC82     GND                     
                                  EC84     TP_CPU1_RSVD_12         
                                  ED5      TP_CPU1_RSVD_10         
                                  ED7      GND                     
                                  ED9      TP_P3E_CPU1_PE1_RSR3_TXN<15>
                                  ED11     GND                     
                                  ED13     P3E_CPU1_PE3_MP_TXP<1>  
                                  ED15     GND                     
                                  ED23     GND                     
                                  ED25     M_L_DQ<55>              
                                  ED27     M_L_DQ<49>              
                                  ED29     GND                     
                                  ED31     M_L_DQ<47>              
                                  ED33     M_L_DQ<41>              
                                  ED35     GND                     
                                  ED37     M_K_DQ<39>              
                                  ED39     M_K_DQ<33>              
                                  ED41     GND                     
                                  ED45     TP_CPU1_RSVD_11         
                                  ED47     M_K_CS_N<2>             
                                  ED49     M_K_CS_N<1>             
                                  ED51     M_K_MA<14>              
                                  ED53     M_K_PAR                 
                                  ED55     M_K_CLK_DN<0>           
                                  ED57     M_K_MA<1>               
                                  ED59     M_K_MA<4>               
                                  ED61     M_K_BG<0>               
                                  ED63     M_K_ALERT_N             
                                  ED69     GND                     
                                  ED71     M_L_DQ<27>              
                                  ED73     M_L_DQS_DP<3>           
                                  ED75     M_L_DQ<24>              
                                  ED77     GND                     
                                  ED79     M_L_DQS_DN<2>           
                                  ED81     GND                     
                                  ED83     TP_CPU1_RSVD_9          
                                  EE6      TP_CPU1_RSVD_6          
                                  EE8      GND                     
                                  EE10     PVCCIO_CPU1             
                                  EE12     P3E_CPU1_PE3_MP_TXN<1>  
                                  EE14     P3E_CPU1_PE3_MP_TXN<0>  
                                  EE16     TP_CPU1_RSVD_8          
                                  EE24     GND                     
                                  EE26     M_L_DQS_DN<6>           
                                  EE28     GND                     
                                  EE30     GND                     
                                  EE32     M_L_DQS_DN<5>           
                                  EE34     GND                     
                                  EE36     GND                     
                                  EE38     M_K_DQS_DN<4>           
                                  EE40     GND                     
                                  EE44     PVDDQ_KLM               
                                  EE46     TP_CPU1_RSVD_7          
                                  EE48     M_K_ODT<1>              
                                  EE50     M_K_ODT<0>              
                                  EE52     M_K_BA<0>               
                                  EE54     M_K_CLK_DP<1>           
                                  EE56     M_K_CLK_DP<3>           
                                  EE58     M_K_MA<2>               
                                  EE60     M_K_MA<6>               
                                  EE62     M_K_CKE<0>              
                                  EE70     GND                     
                                  EE72     M_L_DQ<31>              
                                  EE74     M_L_DQ<25>              
                                  EE76     GND                     
                                  EE78     GND                     
                                  EE80     GND                     
                                  EE82     TP_CPU1_RSVD_5          
                                  EE84     TP_CPU1_RSVD_4          
                                  EF45     PVDDQ_KLM               
                                  EF47     TP_CPU1_RSVD_3          
                                  EF49     PVDDQ_KLM               
                                  EF51     M_K_CS_N<0>             
                                  EF53     PVDDQ_KLM               
                                  EF55     M_K_CLK_DN<1>           
                                  EF57     M_K_CLK_DN<3>           
                                  EF59     PVDDQ_KLM               
                                  EF61     M_K_MA<9>               
                                  EF63     M_K_CKE<1>              
                                  EF71     GND                     
                                  EF73     M_L_DQS_DN<3>           
                                  EF75     GND                     
                                  EF77     TP_CPU1_RSVD_2          
                                  EF79     GND                     
                                  EF81     TP_CPU1_RSVD_1          
                                  EF83     TP_CPU1_RSVD_0          
                                  F3       TP_CPU1_RSVD_279        
                                  F5       GND                     
                                  F7       UPI_CPU1_CPU0_P1P1_DP<4>
                                  F9       UPI_CPU1_CPU0_P1P1_DN<7>
                                  F11      UPI_CPU1_CPU0_P1P1_DP<8>
                                  F13      UPI_CPU1_CPU0_P1P1_DN<11>
                                  F15      UPI_CPU1_CPU0_P1P1_DN<13>
                                  F17      GND                     
                                  F19      GND                     
                                  F21      UPI_CPU1_CPU0_P1P1_DP<18>
                                  F23      TP_CPU1_RSVD_278        
                                  F25      GND                     
                                  F27      M_H_DQ<55>              
                                  F29      M_H_DQ<53>              
                                  F31      GND                     
                                  F33      M_H_DQ<47>              
                                  F35      M_H_DQ<45>              
                                  F37      GND                     
                                  F39      M_G_DQ<39>              
                                  F41      M_G_DQ<37>              
                                  F43      GND                     
                                  F45      M_G_CS_N<6>             
                                  F47      M_G_CS_N<3>             
                                  F49      M_G_CS_N<1>             
                                  F51      M_G_MA<14>              
                                  F53      M_G_MA<0>               
                                  F55      M_G_CLK_DN<0>           
                                  F57      M_G_MA<1>               
                                  F59      M_G_MA<5>               
                                  F61      M_G_MA<9>               
                                  F63      M_G_BG<1>               
                                  F65      TP_CPU1_RSVD_277        
                                  F67      GND                     
                                  F69      GND                     
                                  F71      M_H_DQ<27>              
                                  F73      M_H_DQS_DP<3>           
                                  F75      M_H_DQ<28>              
                                  F77      M_H_DQ<18>              
                                  F79      M_H_DQS_DP<11>          
                                  F81      M_H_DQ<20>              
                                  F83      TP_CPU1_RSVD_276        
                                  G2       TP_CPU1_RSVD_275        
                                  G4       GND                     
                                  G6       UPI_CPU1_CPU0_P1P1_DN<4>
                                  G8       GND                     
                                  G10      UPI_CPU1_CPU0_P1P1_DN<9>
                                  G12      UPI_CPU1_CPU0_P1P1_DP<10>
                                  G14      UPI_CPU1_CPU0_P1P1_DP<11>
                                  G16      UPI_CPU1_CPU0_P1P1_DP<14>
                                  G18      UPI_CPU1_CPU0_P1P1_DN<16>
                                  G20      UPI_CPU1_CPU0_P1P1_DN<18>
                                  G22      GND                     
                                  G24      GND                     
                                  G26      GND                     
                                  G28      M_H_DQS_DN<6>           
                                  G30      GND                     
                                  G32      GND                     
                                  G34      M_H_DQS_DN<5>           
                                  G36      GND                     
                                  G38      GND                     
                                  G40      M_G_DQS_DN<4>           
                                  G42      GND                     
                                  G46      M_G_C<2>                
                                  G48      M_G_ODT<3>              
                                  G50      M_G_ODT<2>              
                                  G52      M_G_CS_N<0>             
                                  G54      M_G_BA<1>               
                                  G56      M_G_CLK_DP<2>           
                                  G58      M_G_MA<4>               
                                  G60      M_G_MA<7>               
                                  G62      M_G_MA<11>              
                                  G64      TP_CPU1_RSVD_274        
                                  G66      GND                     
                                  G68      M_H_DQS_DN<17>          
                                  G70      GND                     
                                  G72      M_H_DQ<31>              
                                  G74      M_H_DQ<29>              
                                  G76      GND                     
                                  G78      GND                     
                                  G80      GND                     
                                  G82      GND                     
                                  G84      TP_CPU1_RSVD_273        
                                  H1       TP_CPU1_RSVD_272        
                                  H3       GND                     
                                  H5       UPI_CPU1_CPU0_P1P1_DP<3>
                                  H7       UPI_CPU1_CPU0_P1P1_DN<5>
                                  H9       UPI_CPU1_CPU0_P1P1_DP<9>
                                  H11      GND                     
                                  H13      PVCCIO_CPU1             
                                  H15      UPI_CPU1_CPU0_P1P1_DP<13>
                                  H17      UPI_CPU1_CPU0_P1P1_DN<14>
                                  H19      UPI_CPU1_CPU0_P1P1_DP<17>
                                  H21      UPI_CPU1_CPU0_P1P1_DP<19>
                                  H23      M_G_DQ<62>              
                                  H25      GND                     
                                  H27      GND                     
                                  H29      GND                     
                                  H31      GND                     
                                  H33      GND                     
                                  H35      GND                     
                                  H37      GND                     
                                  H39      GND                     
                                  H41      GND                     
                                  H43      M_H_DQ<33>              
                                  H45      GND                     
                                  H47      GND                     
                                  H49      GND                     
                                  H51      GND                     
                                  H53      GND                     
                                  H55      GND                     
                                  H57      GND                     
                                  H59      GND                     
                                  H61      GND                     
                                  H63      GND                     
                                  H65      GND                     
                                  H67      M_H_ECC<6>              
                                  H69      M_H_ECC<1>              
                                  H71      GND                     
                                  H73      M_H_DQS_DN<3>           
                                  H75      GND                     
                                  H77      M_H_DQ<19>              
                                  H79      M_H_DQS_DP<2>           
                                  H81      M_H_DQ<21>              
                                  H83      TP_CPU1_RSVD_271        
                                  H85      TP_CPU1_RSVD_270        
                                  J2       PVCCIO_CPU1             
                                  J4       GND                     
                                  J6       UPI_CPU1_CPU0_P1P1_DN<3>
                                  J8       UPI_CPU1_CPU0_P1P1_DN<6>
                                  J10      PVCCIO_CPU1             
                                  J12      GND                     
                                  J14      GND                     
                                  J16      GND                     
                                  J18      UPI_CPU1_CPU0_P1P1_DP<16>
                                  J20      UPI_CPU1_CPU0_P1P1_DN<17>
                                  J22      GND                     
                                  J24      M_G_DQS_DN<16>          
                                  J26      GND                     
                                  J28      GND                     
                                  J30      M_G_DQS_DN<15>          
                                  J32      GND                     
                                  J34      GND                     
                                  J36      M_G_DQS_DN<14>          
                                  J38      GND                     
                                  J40      GND                     
                                  J42      M_H_DQS_DN<13>          
                                  J46      TP_CPU1_RSVD_269        
                                  J48      M_G_MA<13>              
                                  J50      M_H_CS_N<4>             
                                  J52      M_H_MA<0>               
                                  J54      M_G_MA<10>              
                                  J56      M_G_CLK_DN<2>           
                                  J58      M_H_MA<1>               
                                  J60      M_G_ACT_N               
                                  J62      TP_CPU1_RSVD_268        
                                  J64      M_G_MA<12>              
                                  J66      M_H_ECC<2>              
                                  J68      M_H_DQS_DP<17>          
                                  J70      M_H_ECC<0>              
                                  J72      GND                     
                                  J74      GND                     
                                  J76      GND                     
                                  J78      M_H_DQ<23>              
                                  J80      M_H_DQ<17>              
                                  J82      GND                     
                                  J84      GND                     
                                  J86      GND                     
                                  K1       GND                     
                                  K3       UPI_CPU1_CPU0_P1P1_DN<1>
                                  K5       UPI_CPU1_CPU0_P1P1_DN<2>
                                  K7       UPI_CPU1_CPU0_P1P1_DP<5>
                                  K9       UPI_CPU1_CPU0_P1P1_DP<6>
                                  K11      GND                     
                                  K13      GND                     
                                  K15      PVCCIO_CPU1             
                                  K17      GND                     
                                  K19      UPI_CPU1_CPU0_P1P1_DN<15>
                                  K21      UPI_CPU1_CPU0_P1P1_DN<19>
                                  K23      M_G_DQ<63>              
                                  K25      M_G_DQ<56>              
                                  K27      GND                     
                                  K29      M_G_DQ<54>              
                                  K31      M_G_DQ<48>              
                                  K33      GND                     
                                  K35      M_G_DQ<46>              
                                  K37      M_G_DQ<40>              
                                  K39      GND                     
                                  K41      M_H_DQ<38>              
                                  K43      M_H_DQ<32>              
                                  K45      M_G_CS_N<7>             
                                  K47      M_G_MA<17>              
                                  K49      M_G_MA<15>              
                                  K51      M_H_CS_N<0>             
                                  K53      M_H_PAR                 
                                  K55      M_H_BA<1>               
                                  K57      M_H_MA<2>               
                                  K59      M_H_MA<9>               
                                  K61      TP_CPU1_RSVD_267        
                                  K63      M_H_CKE<2>              
                                  K65      GND                     
                                  K67      GND                     
                                  K69      GND                     
                                  K71      GND                     
                                  K73      GND                     
                                  K75      M_G_DQS_DN<12>          
                                  K77      GND                     
                                  K79      M_H_DQS_DN<2>           
                                  K81      GND                     
                                  K83      GND                     
                                  K85      GND                     
                                  L2       GND                     
                                  L4       UPI_CPU1_CPU0_P1P1_DP<1>
                                  L6       GND                     
                                  L8       GND                     
                                  L10      GND                     
                                  L12      UPI_CPU0_CPU1_P1P1_DN<7>
                                  L14      PVCCIO_CPU1             
                                  L16      PVCCIO_CPU1             
                                  L18      UPI_CPU1_CPU0_P1P1_DP<15>
                                  L20      GND                     
                                  L22      GND                     
                                  L24      M_G_DQS_DP<16>          
                                  L26      M_G_DQ<60>              
                                  L28      M_G_DQ<50>              
                                  L30      M_G_DQS_DP<15>          
                                  L32      M_G_DQ<52>              
                                  L34      M_G_DQ<42>              
                                  L36      M_G_DQS_DP<14>          
                                  L38      M_G_DQ<44>              
                                  L40      M_H_DQ<34>              
                                  L42      M_H_DQS_DP<13>          
                                  L46      PVDDQ_GHJ               
                                  L48      PVDDQ_GHJ               
                                  L50      PVDDQ_GHJ               
                                  L52      PVDDQ_GHJ               
                                  L54      PVDDQ_GHJ               
                                  L56      PVDDQ_GHJ               
                                  L58      PVDDQ_GHJ               
                                  L60      PVDDQ_GHJ               
                                  L62      PVDDQ_GHJ               
                                  L64      M_H_CKE<3>              
                                  L66      M_H_ECC<3>              
                                  L68      M_H_DQS_DP<8>           
                                  L70      M_H_ECC<4>              
                                  L72      GND                     
                                  L74      M_G_DQ<30>              
                                  L76      M_G_DQ<24>              
                                  L78      GND                     
                                  L80      GND                     
                                  L82      GND                     
                                  L84      M_G_DQ<11>              
                                  L86      M_G_DQ<10>              
                                  M1       UPI_CPU1_CPU0_P0P0_DN<0>
                                  M3       UPI_CPU1_CPU0_P1P1_DP<0>
                                  M5       UPI_CPU1_CPU0_P1P1_DP<2>
                                  M7       PVCCIO_CPU1             
                                  M9       PVCCIO_CPU1             
                                  M11      PVCCIO_CPU1             
                                  M13      UPI_CPU0_CPU1_P1P1_DN<8>
                                  M15      GND                     
                                  M17      GND                     
                                  M19      GND                     
                                  M21      PVCCIO_CPU1             
                                  M23      GND                     
                                  M25      GND                     
                                  M27      GND                     
                                  M29      GND                     
                                  M31      GND                     
                                  M33      GND                     
                                  M35      GND                     
                                  M37      GND                     
                                  M39      GND                     
                                  M41      GND                     
                                  M43      GND                     
                                  M45      M_H_CS_N<6>             
                                  M47      M_H_C<2>                
                                  M49      M_H_ODT<2>              
                                  M51      M_H_MA<13>              
                                  M53      M_H_CLK_DN<0>           
                                  M55      M_H_MA<10>              
                                  M57      M_H_CLK_DP<2>           
                                  M59      M_H_MA<4>               
                                  M61      M_H_BG<0>               
                                  M63      TP_CPU1_RSVD_266        
                                  M65      GND                     
                                  M67      M_H_ECC<7>              
                                  M69      M_H_ECC<5>              
                                  M71      GND                     
                                  M73      M_G_DQ<26>              
                                  M75      M_G_DQS_DP<12>          
                                  M77      M_G_DQ<28>              
                                  M79      GND                     
                                  M81      M_G_DQ<19>              
                                  M83      GND                     
                                  M85      GND                     
                                  N2       UPI_CPU1_CPU0_P0P0_DP<0>
                                  N4       GND                     
                                  N6       GND                     
                                  N8       GND                     
                                  N10      UPI_CPU0_CPU1_P1P1_DP<4>
                                  N12      UPI_CPU0_CPU1_P1P1_DP<7>
                                  N14      UPI_CPU0_CPU1_P1P1_DP<8>
                                  N16      UPI_CPU0_CPU1_P1P1_DN<11>
                                  N18      PVCCIO_CPU1             
                                  N20      GND                     
                                  N22      GND                     
                                  N24      M_G_DQS_DN<7>           
                                  N26      M_G_DQ<61>              
                                  N28      M_G_DQ<51>              
                                  N30      M_G_DQS_DP<6>           
                                  N32      M_G_DQ<53>              
                                  N34      M_G_DQ<43>              
                                  N36      M_G_DQS_DP<5>           
                                  N38      M_G_DQ<45>              
                                  N40      M_H_DQ<35>              
                                  N42      M_H_DQS_DN<4>           
                                  N46      M_H_CS_N<2>             
                                  N48      M_H_MA<17>              
                                  N50      M_H_ODT<0>              
                                  N52      M_H_MA<15>              
                                  N54      M_H_CLK_DP<0>           
                                  N56      M_H_CLK_DN<2>           
                                  N58      M_H_MA<3>               
                                  N60      M_H_BG<1>               
                                  N62      M_H_CKE<0>              
                                  N64      PVDDQ_GHJ               
                                  N66      GND                     
                                  N68      M_H_DQS_DN<8>           
                                  N70      GND                     
                                  N72      GND                     
                                  N74      GND                     
                                  N76      GND                     
                                  N78      GND                     
                                  N80      M_G_DQ<23>              
                                  N82      M_G_DQ<18>              
                                  N84      M_G_DQ<15>              
                                  N86      M_G_DQ<14>              
                                  P1       UPI_CPU1_CPU0_P0P0_DP<1>
                                  P3       UPI_CPU1_CPU0_P1P1_DN<0>
                                  P5       PVCCIO_CPU1             
                                  P7       UPI_CPU0_CPU1_P1P1_DN<1>
                                  P9       UPI_CPU0_CPU1_P1P1_DN<4>
                                  P11      GND                     
                                  P13      UPI_CPU0_CPU1_P1P1_DP<9>
                                  P15      GND                     
                                  P17      UPI_CPU0_CPU1_P1P1_DP<11>
                                  P19      UPI_CPU0_CPU1_P1P1_DP<14>
                                  P21      UPI_CPU0_CPU1_P1P1_DN<16>
                                  P23      M_G_DQ<58>              
                                  P25      M_G_DQ<57>              
                                  P27      GND                     
                                  P29      M_G_DQ<55>              
                                  P31      M_G_DQ<49>              
                                  P33      GND                     
                                  P35      M_G_DQ<47>              
                                  P37      M_G_DQ<41>              
                                  P39      GND                     
                                  P41      M_H_DQ<39>              
                                  P43      M_H_DQ<36>              
                                  P45      GND                     
                                  P47      GND                     
                                  P49      GND                     
                                  P51      GND                     
                                  P53      GND                     
                                  P55      GND                     
                                  P57      GND                     
                                  P59      GND                     
                                  P61      GND                     
                                  P63      GND                     
                                  P65      TP_CPU1_RSVD_265        
                                  P67      GND                     
                                  P69      GND                     
                                  P71      GND                     
                                  P73      M_G_DQ<27>              
                                  P75      M_G_DQS_DP<3>           
                                  P77      M_G_DQ<29>              
                                  P79      M_G_DQS_DN<2>           
                                  P81      GND                     
                                  P83      GND                     
                                  P85      M_G_DQS_DP<1>           
                                  R2       GND                     
                                  R4       GND                     
                                  R6       UPI_CPU0_CPU1_P1P1_DN<0>
                                  R8       UPI_CPU0_CPU1_P1P1_DP<3>
                                  R10      UPI_CPU0_CPU1_P1P1_DN<5>
                                  R12      UPI_CPU0_CPU1_P1P1_DN<9>
                                  R14      GND                     
                                  R16      UPI_CPU0_CPU1_P1P1_DN<10>
                                  R18      GND                     
                                  R20      UPI_CPU0_CPU1_P1P1_DN<14>
                                  R22      GND                     
                                  R24      M_G_DQS_DP<7>           
                                  R26      GND                     
                                  R28      GND                     
                                  R30      M_G_DQS_DN<6>           
                                  R32      GND                     
                                  R34      GND                     
                                  R36      M_G_DQS_DN<5>           
                                  R38      GND                     
                                  R40      GND                     
                                  R42      M_H_DQS_DP<4>           
                                  R46      M_H_CS_N<7>             
                                  R48      M_H_ODT<1>              
                                  R50      M_H_CS_N<1>             
                                  R52      M_H_MA<16>              
                                  R54      M_H_CLK_DN<1>           
                                  R56      M_H_CLK_DN<3>           
                                  R58      M_H_MA<5>               
                                  R60      M_H_MA<11>              
                                  R62      TP_CPU1_RSVD_264        
                                  R64      M_H_CKE<1>              
                                  R66      TP_CPU1_RSVD_263        
                                  R68      GND                     
                                  R70      M_J_DQ<18>              
                                  R72      GND                     
                                  R74      M_G_DQ<31>              
                                  R76      M_G_DQ<25>              
                                  R78      GND                     
                                  R80      M_G_DQS_DP<2>           
                                  R82      M_G_DQ<22>              
                                  R84      M_G_DQS_DN<1>           
                                  R86      GND                     
                                  T1       UPI_CPU1_CPU0_P0P0_DN<1>
                                  T3       PVCCIO_CPU1             
                                  T5       UPI_CPU0_CPU1_P1P1_DP<0>
                                  T7       UPI_CPU0_CPU1_P1P1_DP<1>
                                  T9       UPI_CPU0_CPU1_P1P1_DN<3>
                                  T11      UPI_CPU0_CPU1_P1P1_DP<6>
                                  T13      GND                     
                                  T15      UPI_CPU0_CPU1_P1P1_DP<10>
                                  T17      GND                     
                                  T19      UPI_CPU0_CPU1_P1P1_DP<15>
                                  T21      UPI_CPU0_CPU1_P1P1_DP<16>
                                  T23      M_G_DQ<59>              
                                  T25      GND                     
                                  T27      M_H_DQS_DN<16>          
                                  T29      GND                     
                                  T31      GND                     
                                  T33      M_J_DQS_DN<14>          
                                  T35      GND                     
                                  T37      GND                     
                                  T39      M_J_DQS_DN<13>          
                                  T41      GND                     
                                  T43      M_H_DQ<37>              
                                  T45      M_J_CS_N<6>             
                                  T47      M_H_ODT<3>              
                                  T49      M_H_CS_N<5>             
                                  T51      M_H_MA<14>              
                                  T53      M_H_BA<0>               
                                  T55      M_H_CLK_DP<1>           
                                  T57      M_H_CLK_DP<3>           
                                  T59      M_H_MA<6>               
                                  T61      M_H_MA<12>              
                                  T63      M_H_ACT_N               
                                  T65      GND                     
                                  T67      TP_CPU1_RSVD_262        
                                  T69      M_J_DQ<19>              
                                  T71      M_J_DQ<22>              
                                  T73      GND                     
                                  T75      M_G_DQS_DN<3>           
                                  T77      GND                     
                                  T79      M_G_DQ<17>              
                                  T81      M_G_DQS_DP<11>          
                                  T83      GND                     
                                  T85      GND                     
                                  U2       GND                     
                                  U4       GND                     
                                  U6       GND                     
                                  U8       UPI_CPU0_CPU1_P1P1_DP<2>
                                  U10      UPI_CPU0_CPU1_P1P1_DP<5>
                                  U12      UPI_CPU0_CPU1_P1P1_DN<6>
                                  U14      PVCCIO_CPU1             
                                  U16      UPI_CPU0_CPU1_P1P1_DP<12>
                                  U18      UPI_CPU0_CPU1_P1P1_DN<15>
                                  U20      GND                     
                                  U22      GND                     
                                  U24      GND                     
                                  U26      M_H_DQ<62>              
                                  U28      M_H_DQ<56>              
                                  U30      GND                     
                                  U32      M_J_DQ<46>              
                                  U34      M_J_DQ<40>              
                                  U36      GND                     
                                  U38      M_J_DQ<38>              
                                  U40      M_J_DQ<32>              
                                  U42      GND                     
                                  U46      PVDDQ_GHJ               
                                  U48      PVDDQ_GHJ               
                                  U50      PVDDQ_GHJ               
                                  U52      PVDDQ_GHJ               
                                  U54      PVDDQ_GHJ               
                                  U56      PVDDQ_GHJ               
                                  U58      PVDDQ_GHJ               
                                  U60      PVDDQ_GHJ               
                                  U62      PVDDQ_GHJ               
                                  U64      M_GHJ_RST_N             
                                  U66      TP_CPU1_RSVD_261        
                                  U68      GND                     
                                  U70      GND                     
                                  U72      M_J_DQS_DN<11>          
                                  U74      GND                     
                                  U76      GND                     
                                  U78      GND                     
                                  U80      GND                     
                                  U82      M_G_DQS_DN<11>          
                                  U84      M_G_DQS_DN<10>          
                                  U86      GND                     
                                  V1       GND                     
                                  V3       UPI_CPU1_CPU0_P0P0_DN<2>
                                  V5       GND                     
                                  V7       UPI_CPU0_CPU1_P1P1_DN<2>
                                  V9       GND                     
                                  V11      GND                     
                                  V13      GND                     
                                  V15      GND                     
                                  V17      UPI_CPU0_CPU1_P1P1_DN<13>
                                  V19      UPI_CPU0_CPU1_P1P1_DN<17>
                                  V21      GND                     
                                  V23      GND                     
                                  V25      M_H_DQ<58>              
                                  V27      M_H_DQS_DP<16>          
                                  V29      M_H_DQ<60>              
                                  V31      M_J_DQ<42>              
                                  V33      M_J_DQS_DP<14>          
                                  V35      M_J_DQ<44>              
                                  V37      M_J_DQ<34>              
                                  V39      M_J_DQS_DP<13>          
                                  V41      M_J_DQ<36>              
                                  V43      GND                     
                                  V45      M_J_CS_N<7>             
                                  V47      M_H_CS_N<3>             
                                  V49      M_J_ODT<2>              
                                  V51      M_J_CS_N<0>             
                                  V53      M_J_PAR                 
                                  V55      M_J_CLK_DP<1>           
                                  V57      M_J_CLK_DP<3>           
                                  V59      M_J_MA<5>               
                                  V61      M_H_MA<7>               
                                  V63      M_J_CKE<2>              
                                  V65      TP_CPU1_RSVD_260        
                                  V67      TP_CPU1_RSVD_259        
                                  V69      M_J_DQ<23>              
                                  V71      M_J_DQS_DP<11>          
                                  V73      GND                     
                                  V75      GND                     
                                  V77      GND                     
                                  V79      M_G_DQ<21>              
                                  V81      M_G_DQ<16>              
                                  V83      GND                     
                                  V85      M_G_DQS_DP<10>          
                                  W2       UPI_CPU1_CPU0_P0P0_DP<3>
                                  W4       PVCCIO_CPU1             
                                  W6       PVCCIO_CPU1             
                                  W8       GND                     
                                  W10      PVCCIO_CPU1             
                                  W12      GND                     
                                  W14      XDP_CPU_TMS             
                                  W16      UPI_CPU0_CPU1_P1P1_DN<12>
                                  W18      UPI_CPU0_CPU1_P1P1_DP<13>
                                  W20      UPI_CPU0_CPU1_P1P1_DN<18>
                                  W22      GND                     
                                  W24      GND                     
                                  W26      GND                     
                                  W28      GND                     
                                  W30      GND                     
                                  W32      GND                     
                                  W34      GND                     
                                  W36      GND                     
                                  W38      GND                     
                                  W40      GND                     
                                  W42      GND                     
                                  W46      M_J_CS_N<2>             
                                  W48      M_J_CS_N<5>             
                                  W50      M_J_MA<14>              
                                  W52      M_J_BA<0>               
                                  W54      M_J_CLK_DN<1>           
                                  W56      M_J_CLK_DN<3>           
                                  W58      M_J_MA<3>               
                                  W60      M_H_MA<8>               
                                  W62      M_H_ALERT_N             
                                  W64      PVDDQ_GHJ               
                                  W66      TP_CPU1_RSVD_258        
                                  W68      GND                     
                                  W70      M_J_DQS_DP<2>           
                                  W72      M_J_DQ<16>              
                                  W74      GND                     
                                  W76      M_J_DQ<11>              
                                  W78      GND                     
                                  W80      M_G_DQ<20>              
                                  W82      GND                     
                                  W84      M_G_DQ<9>               
                                  W86      M_G_DQ<8>               
                                  Y1       UPI_CPU1_CPU0_P0P0_DN<3>
                                  Y3       UPI_CPU1_CPU0_P0P0_DP<2>
                                  Y5       GND                     
                                  Y7       GND                     
                                  Y9       GND                     
                                  Y11      TP_XDP_CPU1_OBSDATA_B3_MBP5_N
                                  Y13      XDP_CPU_TRST_N          
                                  Y15      GND                     
                                  Y17      GND                     
                                  Y19      UPI_CPU0_CPU1_P1P1_DP<17>
                                  Y21      UPI_CPU0_CPU1_P1P1_DP<18>
                                  Y23      FM_CPU1_RC_ERROR_N      
                                  Y25      M_H_DQ<59>              
                                  Y27      M_H_DQS_DP<7>           
                                  Y29      M_H_DQ<61>              
                                  Y31      M_J_DQ<43>              
                                  Y33      M_J_DQS_DP<5>           
                                  Y35      M_J_DQ<45>              
                                  Y37      M_J_DQ<35>              
                                  Y39      M_J_DQS_DP<4>           
                                  Y41      M_J_DQ<37>              
                                  Y43      A_CPU1_GHJ_RCOMP0       
                                  Y45      PVDDQ_GHJ               
                                  Y47      PVDDQ_GHJ               
                                  Y49      PVDDQ_GHJ               
                                  Y51      PVDDQ_GHJ               
                                  Y53      PVDDQ_GHJ               
                                  Y55      PVDDQ_GHJ               
                                  Y57      PVDDQ_GHJ               
                                  Y59      PVDDQ_GHJ               
                                  Y61      PVDDQ_GHJ               
                                  Y63      PVDDQ_GHJ               
                                  Y65      TP_CPU1_RSVD_256        
                                  Y67      GND                     
                                  Y69      M_J_DQS_DN<2>           
                                  Y71      GND                     
                                  Y73      GND                     
                                  Y75      M_J_DQ<15>              
                                  Y77      M_J_DQ<10>              
                                  Y79      GND                     
                                  Y81      GND                     
                                  Y83      GND                     
                                  Y85      GND                     
U2M1             NC7SB3157_SMLF-IC,C99406-001 1        JTAG_MCP_CPU0_TDI       
                                  2        GND                     
                                  3        JTAG_MCP_CPU1_TDI       
                                  4        JTAG_MCP_MUX_TDI        
                                  5        P3V3_STBY               
                                  6        FM_CPU0_CD_PRES         
U2P1             TTL1G07_A_SOP-74LVC1G07,IC,C88B 2        FM_M2_SSD_PEDET         
                                  4        FM_M2_DET_LVC3          
U2R1             TTL2G14_SMLF-74LVC2G14,IC,D184B 1        FP_NMI_BTN              
                                  3        FP_NMI_BTN_OUT_N        
                                  4        FP_NMI_BTN              
                                  6        FP_NMI_BTN_R_N          
U2T1             PI3B3257A_TSSOPLF-IC,E16801-001 1        FM_BIOS_SPI_BMC_CTRL    
                                  2        SPI_PCH_IO2_R1          
                                  3        TP_SPI_SWITCH1_3        
                                  4        SPI_BIOS_SOCKET_IO2     
                                  5        SPI_PCH_IO3_R1          
                                  6        TP_SPI_SWITCH1_6        
                                  7        SPI_BIOS_SOCKET_IO3     
                                  8        GND                     
                                  9        TP_SPI_SWITCH1_9        
                                  10       TP_SPI_SWITCH1_10       
                                  11       TP_SPI_SWITCH1_11       
                                  12       TP_SPI_SWITCH1_12       
                                  13       TP_SPI_SWITCH1_13       
                                  14       TP_SPI_SWITCH1_14       
                                  15       GND                     
                                  16       P3V3_STBY               
U2T2             TTL1G32_A_SOT-74LVC1G32,IC,E60B 1        FM_BACKUP_BIOS_SEL_N    
                                  2        SPI_SWITCH_CS0_N        
                                  4        SPI_CS0_SECONDARY_N     
U2T3             TTL1G32_A_SOT-74LVC1G32,IC,E60B 1        FM_DUAL_BIOS_SEL_N      
                                  2        SPI_SWITCH_CS0_N        
                                  4        SPI_CS0_PRIMARY_N       
U2T4             GTL2014_SM-IC,D66151-001 1        PD_GTL2104_4_DIR        
                                  2        H_CPU1_PROCHOT_G_R_N    
                                  3        H_CPU0_PROCHOT_G_R_N    
                                  4        P0V7_GTL2104_5_VREF     
                                  5        H_CPU_ERR1_GTL_N        
                                  6        H_CPU_ERR0_GTL_N        
                                  7        GND                     
                                  8        GND                     
                                  9        FM_CPU_ERR0_LVT3_R_N    
                                  10       FM_CPU_ERR1_LVT3_R_N    
                                  11       GND                     
                                  12       FM_CPU0_PROCHOT_LVT3_R_N
                                  13       FM_CPU1_PROCHOT_LVT3_R_N
                                  14       P3V3                    
U3B1             PCA9617_SSOP-IC,G81764-001-GNDA 1        PVCCIO_CPU1             
                                  2        SMB_DDR_KLM_SCL_G       
                                  3        SMB_DDR_KLM_SDA_G       
                                  5        TP_SMB_DDR_KLM_EN       
                                  6        SMB_DDR_KLM_VPP_SDA_R   
                                  7        SMB_DDR_KLM_VPP_SCL_R   
                                  8        PVPP_KLM                
U3P1             GTL2014_SM-IC,D66151-001 1        PU_GTL2014_1_DIR        
                                  2        PWRGD_CPU0_DRAMPWROK_DEF_G
                                  3        PWRGD_CPU0_DRAMPWROK_ABC_G
                                  4        PD_GTL2014_1_VREF       
                                  5        RST_CPU0_G_N            
                                  6        PWRGD_CPU0_G            
                                  7        GND                     
                                  8        GND                     
                                  9        PWRGD_CPU0_LVC3         
                                  10       RST_CPU0_LVC3_N         
                                  11       GND                     
                                  12       PWRGD_DRAMPWRGD         
                                  13       PWRGD_DRAMPWRGD         
                                  14       P3V3_STBY               
U3P2             GTL2014_SM-IC,D66151-001 1        PD_GTL2104_DIR_1        
                                  2        PWRGD_CPUPWRGD_GTL      
                                  3        H_CPU1_FIVR_FAULT_G     
                                  4        P0V7_GTL2104_VREF_1     
                                  5        H_CPU_CATERR_G_N        
                                  6        H_CPU1_THERMTRIP_G_N    
                                  7        GND                     
                                  8        GND                     
                                  9        FM_CPU1_THERMTRIP_LVT3_R_N
                                  10       FM_CPU_CATERR_LVT3_R2_N 
                                  11       GND                     
                                  12       FM_CPU1_FIVR_FAULT_R_LVT3
                                  13       PWRGD_CPUPWRGD_R1       
                                  14       P3V3                    
U3T1             W25Q256_XSOI-IC,H25002-001 1        PU_BIOS_SPI_HOLD1_N     
                                  2        P3V3_STBY               
                                  3        PU_SPI1_RST             
                                  4        TP_SPI_1_6              
                                  5        TP_SPI_1_5              
                                  6        TP_SPI_1_4              
                                  7        SPI_CS0_SECONDARY_R_N   
                                  8        SPI_MISO_R1             
                                  9        PU_BIOS_SPI_WP1_N       
                                  10       GND                     
                                  11       TP_SPI_1_3              
                                  12       TP_SPI_1_2              
                                  13       TP_SPI_1_1              
                                  14       TP_SPI_1_0              
                                  15       SPI_SWITCH_MOSI_R1      
                                  16       SPI_CLK_R1              
U4B1             MAX9634_SOT-IC,H35789-001 1        GND                     
                                  2        GND                     
                                  3        VR_PVDDQ_DEF_AIINSEN_R  
                                  4        P12V_NVDIMM_DEF         
                                  5        P12V_STBY               
U4C1             ADM4073_SM-EMPTY,G12194-001 1        GND                     
                                  2        GND                     
                                  3        VR_FET_SW_P12V_PVCCIN_CPU0_R
                                  4        VR_FET_SW_P12V_PVCCIN_CPU0_R
                                  5        VR_FET_SW_P12V_STBY_PVCCIN_CPU0
                                  6        PVCCIN_PVSA_CPU0_IINSEN 
U4C2             GTL2014_SM-IC,D66151-001 1        PU_GTL2014_2_DIR        
                                  2        PWRGD_CPU1_DRAMPWROK_KLM_G
                                  3        PWRGD_CPU1_DRAMPWROK_GHJ_G
                                  4        PD_GTL2014_2_VREF       
                                  5        RST_CPU1_G_N            
                                  6        PWRGD_CPU1_G            
                                  7        GND                     
                                  8        GND                     
                                  9        PWRGD_CPU1_LVC3         
                                  10       RST_CPU1_LVC3_N         
                                  11       GND                     
                                  12       PWRGD_DRAMPWRGD         
                                  13       PWRGD_DRAMPWRGD         
                                  14       P3V3_STBY               
U4F1             MAX9634_SOT-IC,H35789-001 1        GND                     
                                  2        GND                     
                                  3        VR_PVDDQ_ABC_AIINSEN_R  
                                  4        P12V_NVDIMM_ABC         
                                  5        P12V_STBY               
U4G1             PCA9617_SSOP-IC,G81764-001-GNDA 1        PVCCIO_CPU1             
                                  2        SMB_DDR_GHJ_SCL_G       
                                  3        SMB_DDR_GHJ_SDA_G       
                                  5        TP_SMB_DDR_GHJ_EN       
                                  6        SMB_DDR_GHJ_VPP_SDA_R   
                                  7        SMB_DDR_GHJ_VPP_SCL_R   
                                  8        PVPP_GHJ                
U4R1             74CBTLV1G125_SMLF-IC,C88177-00A 1        FM_CPU0_PKGID1          
                                  2        P1V8_MCP_CPU0           
                                  4        JTAG_MCP_CPU0_TDI_R     
U5D1             SKX_EXT_B_BGA1-IC,TBD A4       TP_CPU0_RSVD_304        
                                  A6       TP_CPU0_RSVD_303        
                                  A8       PVPP_ABC                
                                  A10      PVPP_ABC                
                                  A12      PVPP_ABC                
                                  A14      P1V8_MCP_CPU0           
                                  A16      P1V8_MCP_CPU0           
                                  A24      TP_CPU0_RSVD_300        
                                  A26      GND                     
                                  A28      M_B_DQS_DN<15>          
                                  A30      GND                     
                                  A32      GND                     
                                  A34      M_B_DQS_DN<14>          
                                  A36      GND                     
                                  A38      GND                     
                                  A40      M_A_DQS_DN<13>          
                                  A42      GND                     
                                  AA2      UPI_CPU0_CPU1_P0P0_DP<15>
                                  AA4      GND                     
                                  AA6      UPI_CPU1_CPU0_P0P0_DP<17>
                                  AA8      UPI_CPU1_CPU0_P0P0_DN<18>
                                  AA10     PVCCIO_CPU0             
                                  AA12     TP_XDP_CPU0_OBSDATA_A2_MBP4_N
                                  AA14     XDP_CPU_TCK0            
                                  AA16     GND                     
                                  AA18     GND                     
                                  AA20     UPI_CPU1_CPU0_P1P1_DP<0>
                                  AA22     GND                     
                                  AA24     GND                     
                                  AA26     M_B_DQ<63>              
                                  AA28     M_B_DQ<57>              
                                  AA30     GND                     
                                  AA32     M_C_DQ<47>              
                                  AA34     M_C_DQ<41>              
                                  AA36     GND                     
                                  AA38     M_C_DQ<39>              
                                  AA40     M_C_DQ<33>              
                                  AA42     GND                     
                                  AA46     M_C_CS_N<3>             
                                  AA48     M_C_ODT<1>              
                                  AA50     M_C_ODT<0>              
                                  AA52     M_C_MA<16>              
                                  AA54     M_C_CLK_DN<0>           
                                  AA56     M_C_CLK_DN<2>           
                                  AA58     M_C_MA<4>               
                                  AA60     M_C_BG<0>               
                                  AA62     M_C_CKE<0>              
                                  AA64     GND                     
                                  AA66     GND                     
                                  AA68     GND                     
                                  AA70     M_C_DQ<17>              
                                  AA72     M_C_DQ<20>              
                                  AA74     M_C_DQS_DN<1>           
                                  AA76     GND                     
                                  AA78     GND                     
                                  AA80     GND                     
                                  AA82     GND                     
                                  AA84     M_A_DQ<13>              
                                  AA86     M_A_DQ<12>              
                                  AB1      GND                     
                                  AB3      UPI_CPU0_CPU1_P0P0_DN<15>
                                  AB5      GND                     
                                  AB7      UPI_CPU1_CPU0_P0P0_DN<17>
                                  AB9      UPI_CPU1_CPU0_P0P0_DP<19>
                                  AB11     GND                     
                                  AB13     FM_CPU0_SKTOCC_LVT3_N   
                                  AB15     H_CPU0_THERMTRIP_G_N    
                                  AB17     TP_CPU0_PROCDIS_G_N     
                                  AB19     UPI_CPU1_CPU0_P1P1_DN<0>
                                  AB21     GND                     
                                  AB23     GND                     
                                  AB25     GND                     
                                  AB27     M_B_DQS_DN<7>           
                                  AB29     GND                     
                                  AB31     GND                     
                                  AB33     M_C_DQS_DN<5>           
                                  AB35     GND                     
                                  AB37     GND                     
                                  AB39     M_C_DQS_DN<4>           
                                  AB41     GND                     
                                  AB43     A_CPU0_ABC_RCOMP1       
                                  AB45     M_C_C<2>                
                                  AB47     M_C_ODT<3>              
                                  AB49     M_C_CS_N<1>             
                                  AB51     M_C_CS_N<4>             
                                  AB53     M_C_MA<0>               
                                  AB55     M_C_CLK_DP<0>           
                                  AB57     M_C_CLK_DP<2>           
                                  AB59     M_C_MA<6>               
                                  AB61     M_C_ACT_N               
                                  AB63     M_C_CKE<3>              
                                  AB65     GND                     
                                  AB67     M_A_DQS_DN<17>          
                                  AB69     GND                     
                                  AB71     M_C_DQ<21>              
                                  AB73     GND                     
                                  AB75     M_C_DQS_DP<1>           
                                  AB77     M_C_DQ<14>              
                                  AB79     GND                     
                                  AB81     M_B_DQ<11>              
                                  AB83     GND                     
                                  AB85     GND                     
                                  AC2      UPI_CPU0_CPU1_P0P0_DN<14>
                                  AC4      PVCCIO_CPU0             
                                  AC6      UPI_CPU1_CPU0_P0P0_DP<16>
                                  AC8      UPI_CPU1_CPU0_P0P0_DP<18>
                                  AC10     UPI_CPU1_CPU0_P0P0_DN<19>
                                  AC12     XDP_CPU_OBSFN_B1_MBP7_N 
                                  AC14     XDP_CPU_TDI             
                                  AC16     H_CPU0_PROCHOT_G_N      
                                  AC18     GND                     
                                  AC20     PVCCIO_CPU0             
                                  AC22     GND                     
                                  AC24     M_C_DQS_DN<16>          
                                  AC26     GND                     
                                  AC28     GND                     
                                  AC30     M_C_DQS_DN<15>          
                                  AC32     GND                     
                                  AC34     GND                     
                                  AC36     PVCCIO_CPU0             
                                  AC38     GND                     
                                  AC40     GND                     
                                  AC42     A_CPU0_ABC_RCOMP2       
                                  AC46     M_C_MA<17>              
                                  AC48     GND                     
                                  AC50     GND                     
                                  AC52     GND                     
                                  AC54     GND                     
                                  AC56     GND                     
                                  AC58     GND                     
                                  AC60     GND                     
                                  AC62     GND                     
                                  AC64     GND                     
                                  AC66     M_A_ECC<6>              
                                  AC68     M_A_ECC<0>              
                                  AC70     GND                     
                                  AC72     GND                     
                                  AC74     M_C_DQ<9>               
                                  AC76     M_C_DQS_DP<10>          
                                  AC78     GND                     
                                  AC80     M_B_DQ<15>              
                                  AC82     M_B_DQ<10>              
                                  AC84     GND                     
                                  AC86     GND                     
                                  AD1      UPI_CPU0_CPU1_P0P0_DP<14>
                                  AD3      GND                     
                                  AD5      UPI_CPU1_CPU0_P0P0_DN<16>
                                  AD7      GND                     
                                  AD9      GND                     
                                  AD11     GND                     
                                  AD13     GND                     
                                  AD15     GND                     
                                  AD17     SMB_DDR_DEF_SDA_G_R     
                                  AD19     GND                     
                                  AD21     GND                     
                                  AD23     M_C_DQ<62>              
                                  AD25     M_C_DQ<56>              
                                  AD27     GND                     
                                  AD29     M_C_DQ<54>              
                                  AD31     M_C_DQ<48>              
                                  AD33     GND                     
                                  AD35     PVCCIO_CPU0             
                                  AD37     PVCCIO_CPU0             
                                  AD39     GND                     
                                  AD41     VSENSE_PMAX_CPU0        
                                  AD43     GND                     
                                  AD45     PVDDQ_ABC               
                                  AD47     TP_CPU0_RSVD_254        
                                  AD49     TP_CPU0_RSVD_253        
                                  AD51     TP_CPU0_RSVD_252        
                                  AD53     M_C_MA<13>              
                                  AD55     M_C_MA<10>              
                                  AD57     M_C_MA<2>               
                                  AD59     M_C_MA<8>               
                                  AD61     M_C_ALERT_N             
                                  AD63     M_C_CKE<1>              
                                  AD65     M_A_ECC<2>              
                                  AD67     M_A_DQS_DP<17>          
                                  AD69     M_A_ECC<4>              
                                  AD71     GND                     
                                  AD73     GND                     
                                  AD75     GND                     
                                  AD77     M_C_DQS_DN<10>          
                                  AD79     M_B_DQS_DN<1>           
                                  AD81     GND                     
                                  AD83     GND                     
                                  AD85     GND                     
                                  AE2      UPI_CPU0_CPU1_P0P0_DN<12>
                                  AE4      GND                     
                                  AE6      UPI_CPU1_CPU0_P0P0_DN<15>
                                  AE8      GND                     
                                  AE10     PVCCIO_CPU0             
                                  AE12     XDP_CPU_OBSFN_B0_MBP6_N 
                                  AE14     XDP_CPU0_TDO            
                                  AE16     GND                     
                                  AE18     SMB_DDR_DEF_SCL_G_R     
                                  AE20     PU_CPU0_LEGACY_SKT      
                                  AE22     M_C_DQ<58>              
                                  AE24     M_C_DQS_DP<16>          
                                  AE26     M_C_DQ<60>              
                                  AE28     M_C_DQ<50>              
                                  AE30     M_C_DQS_DP<15>          
                                  AE32     M_C_DQ<52>              
                                  AE34     PVCCIO_CPU0             
                                  AE36     PVCCIO_CPU0             
                                  AE38     GND                     
                                  AE40     GND                     
                                  AE42     GND                     
                                  AE46     TP_CPU0_RSVD_251        
                                  AE48     TP_CPU0_RSVD_250        
                                  AE50     TP_CPU0_RSVD_249        
                                  AE52     TP_CPU0_RSVD_248        
                                  AE54     M_C_MA<15>              
                                  AE56     M_C_BA<1>               
                                  AE58     M_C_MA<1>               
                                  AE60     M_C_MA<7>               
                                  AE62     M_C_BG<1>               
                                  AE64     GND                     
                                  AE66     GND                     
                                  AE68     GND                     
                                  AE70     GND                     
                                  AE72     TP_CPU0_RSVD_247        
                                  AE74     M_C_DQ<13>              
                                  AE76     M_C_DQ<8>               
                                  AE78     GND                     
                                  AE80     M_B_DQS_DP<1>           
                                  AE82     M_B_DQ<14>              
                                  AE84     M_A_DQ<3>               
                                  AE86     M_A_DQ<2>               
                                  AF1      GND                     
                                  AF3      UPI_CPU0_CPU1_P0P0_DP<13>
                                  AF5      PVCCIO_CPU0             
                                  AF7      UPI_CPU1_CPU0_P0P0_DP<14>
                                  AF9      GND                     
                                  AF11     TP_XDP_CPU0_OBSDATA_A1_MBP3_N
                                  AF13     H_CPU0_MEMDEF_MEMHOT_G_N
                                  AF15     H_CPU0_FAST_WAKE_N      
                                  AF17     SMB_DDR_ABC_SDA_G_R     
                                  AF19     TP_CPU0_RSVD_246        
                                  AF21     GND                     
                                  AF23     GND                     
                                  AF25     GND                     
                                  AF27     GND                     
                                  AF29     GND                     
                                  AF31     GND                     
                                  AF33     GND                     
                                  AF35     PVCCIO_CPU0             
                                  AF37     GND                     
                                  AF39     GND                     
                                  AF41     GND                     
                                  AF43     PVCCIN_CPU0             
                                  AF45     PD_CPU0_RSVD_TEST_1     
                                  AF47     TP_CPU0_RSVD_245        
                                  AF49     TP_CPU0_RSVD_244        
                                  AF51     TP_CPU0_RSVD_243        
                                  AF53     TP_CPU0_RSVD_242        
                                  AF55     PVDDQ_ABC               
                                  AF57     PVDDQ_ABC               
                                  AF59     PVDDQ_ABC               
                                  AF61     PVDDQ_ABC               
                                  AF63     PVDDQ_ABC               
                                  AF65     M_A_ECC<3>              
                                  AF67     M_A_DQS_DP<8>           
                                  AF69     M_A_ECC<5>              
                                  AF71     TP_CPU0_RSVD_241        
                                  AF73     GND                     
                                  AF75     M_C_DQ<12>              
                                  AF77     GND                     
                                  AF79     M_B_DQ<9>               
                                  AF81     M_B_DQS_DP<10>          
                                  AF83     GND                     
                                  AF85     GND                     
                                  AG2      UPI_CPU0_CPU1_P0P0_DP<12>
                                  AG4      UPI_CPU0_CPU1_P0P0_DN<13>
                                  AG6      UPI_CPU1_CPU0_P0P0_DP<15>
                                  AG8      UPI_CPU1_CPU0_P0P0_DN<14>
                                  AG10     TP_XDP_CPU0_OBSDATA_A0_MBP2_N
                                  AG12     GND                     
                                  AG14     GND                     
                                  AG16     XDP_CPU_PRDY_N          
                                  AG18     GND                     
                                  AG20     TP_CPU0_RSVD_240        
                                  AG22     M_C_DQ<59>              
                                  AG24     M_C_DQS_DP<7>           
                                  AG26     M_C_DQ<61>              
                                  AG28     M_C_DQ<51>              
                                  AG30     M_C_DQS_DP<6>           
                                  AG32     M_C_DQ<53>              
                                  AG34     PVCCIO_CPU0             
                                  AG36     GND                     
                                  AG38     PVCCIN_CPU0             
                                  AG40     PVCCIN_CPU0             
                                  AG42     PVCCIN_CPU0             
                                  AG46     PD_CPU0_RSVD_TEST_2     
                                  AG48     TP_CPU0_RSVD_239        
                                  AG50     TP_CPU0_RSVD_238        
                                  AG52     TP_CPU0_RSVD_237        
                                  AG54     TP_CPU0_RSVD_236        
                                  AG56     TP_CPU0_RSVD_235        
                                  AG58     M_C_MA<9>               
                                  AG60     M_C_MA<11>              
                                  AG62     M_C_MA<12>              
                                  AG64     GND                     
                                  AG66     M_A_ECC<7>              
                                  AG68     M_A_ECC<1>              
                                  AG70     GND                     
                                  AG72     TP_CPU0_RSVD_234        
                                  AG74     GND                     
                                  AG76     GND                     
                                  AG78     GND                     
                                  AG80     GND                     
                                  AG82     M_B_DQS_DN<10>          
                                  AG84     M_A_DQ<7>               
                                  AG86     M_A_DQ<6>               
                                  AH1      GND                     
                                  AH3      UPI_CPU0_CPU1_P0P0_DN<11>
                                  AH5      GND                     
                                  AH7      UPI_CPU1_CPU0_P0P0_DP<13>
                                  AH9      PVCCIO_CPU0             
                                  AH11     XDP_CPU_MBP1_N          
                                  AH13     H_CPU0_MEMABC_MEMHOT_G_N
                                  AH15     TP_CPU0_RSVD_233        
                                  AH19     TP_CPU0_RSVD_232        
                                  AH21     GND                     
                                  AH23     M_C_DQ<63>              
                                  AH25     M_C_DQ<57>              
                                  AH27     GND                     
                                  AH29     M_C_DQ<55>              
                                  AH31     M_C_DQ<49>              
                                  AH33     GND                     
                                  AH35     GND                     
                                  AH37     PVCCIN_CPU0             
                                  AH39     PVCCIN_CPU0             
                                  AH41     PVCCIN_CPU0             
                                  AH45     GND                     
                                  AH47     GND                     
                                  AH49     GND                     
                                  AH51     GND                     
                                  AH53     GND                     
                                  AH55     TP_CPU0_RSVD_231        
                                  AH57     TP_CPU0_RSVD_230        
                                  AH59     GND                     
                                  AH61     GND                     
                                  AH63     M_C_CPU_VREF            
                                  AH65     GND                     
                                  AH67     M_A_DQS_DN<8>           
                                  AH69     GND                     
                                  AH71     TP_CPU0_RSVD_229        
                                  AH73     TP_CPU0_RSVD_228        
                                  AH75     GND                     
                                  AH77     GND                     
                                  AH79     M_B_DQ<13>              
                                  AH81     M_B_DQ<8>               
                                  AH83     GND                     
                                  AH85     M_A_DQS_DP<0>           
                                  AJ2      UPI_CPU0_CPU1_P0P0_DP<11>
                                  AJ4      GND                     
                                  AJ6      UPI_CPU1_CPU0_P0P0_DN<13>
                                  AJ8      GND                     
                                  AJ10     XDP_CPU_MBP0_N          
                                  AJ12     H_CPU0_ERR0_G_N         
                                  AJ14     PU_CPU0_EAR_N           
                                  AJ18     SMB_DDR_ABC_SCL_G_R     
                                  AJ20     TP_CPU0_RSVD_227        
                                  AJ22     GND                     
                                  AJ24     M_C_DQS_DN<7>           
                                  AJ26     GND                     
                                  AJ28     GND                     
                                  AJ30     M_C_DQS_DN<6>           
                                  AJ32     GND                     
                                  AJ34     GND                     
                                  AJ36     PVCCIN_CPU0             
                                  AJ46     GND                     
                                  AJ48     GND                     
                                  AJ50     GND                     
                                  AJ52     GND                     
                                  AJ54     GND                     
                                  AJ56     TP_CPU0_RSVD_226        
                                  AJ58     TP_CPU0_RSVD_225        
                                  AJ60     TP_CPU0_RSVD_224        
                                  AJ62     TP_CPU0_RSVD_223        
                                  AJ64     M_A_CPU_VREF            
                                  AJ66     GND                     
                                  AJ68     GND                     
                                  AJ70     TP_CPU0_RSVD_222        
                                  AJ74     GND                     
                                  AJ76     M_C_DQ<3>               
                                  AJ78     GND                     
                                  AJ80     M_B_DQ<12>              
                                  AJ82     GND                     
                                  AJ84     M_A_DQS_DN<0>           
                                  AJ86     GND                     
                                  AK1      UPI_CPU0_CPU1_P0P0_DP<10>
                                  AK3      UPI_CPU0_CPU1_P0P0_DP<9>
                                  AK5      UPI_CPU1_CPU0_P0P0_DP<12>
                                  AK7      UPI_CPU1_CPU0_P0P0_DN<11>
                                  AK9      GND                     
                                  AK11     H_CPU0_ERR1_G_N         
                                  AK13     GND                     
                                  AK19     GND                     
                                  AK21     VSENSE_P1V8MCP_CPU0_SKT_VSEN
                                  AK23     GND                     
                                  AK25     GND                     
                                  AK27     CLK_322M_OSC_CPU0_RC_DP 
                                  AK29     GND                     
                                  AK31     GND                     
                                  AK33     GND                     
                                  AK35     PVCCIN_CPU0             
                                  AK45     PVCCIN_CPU0             
                                  AK47     PVCCIN_CPU0             
                                  AK49     PVCCIN_CPU0             
                                  AK51     PVCCIN_CPU0             
                                  AK53     PVCCIN_CPU0             
                                  AK55     GND                     
                                  AK57     TP_CPU0_RSVD_219        
                                  AK59     TP_CPU0_RSVD_218        
                                  AK61     TP_CPU0_RSVD_217        
                                  AK63     M_B_CPU_VREF            
                                  AK65     GND                     
                                  AK67     GND                     
                                  AK69     TP_CPU0_RSVD_216        
                                  AK73     GND                     
                                  AK75     M_C_DQ<7>               
                                  AK77     M_C_DQ<2>               
                                  AK79     GND                     
                                  AK81     GND                     
                                  AK83     GND                     
                                  AK85     GND                     
                                  AL2      UPI_CPU0_CPU1_P0P0_DN<10>
                                  AL4      GND                     
                                  AL6      UPI_CPU1_CPU0_P0P0_DN<12>
                                  AL8      UPI_CPU1_CPU0_P0P0_DP<10>
                                  AL10     GND                     
                                  AL12     H_CPU0_ERR2_G_N         
                                  AL14     H_CPU0_CATERR_G_N       
                                  AL18     TP_CPU0_PE_HP_SDA       
                                  AL20     VSENSE_P1V8MCP_CPU0_SKT_VRTN
                                  AL22     TP_CPU0_RSVD_214        
                                  AL24     GND                     
                                  AL26     CLK_322M_OSC_CPU0_RC_DN 
                                  AL28     PVCCIO_CPU0             
                                  AL30     GND                     
                                  AL32     GND                     
                                  AL34     PVCCIN_CPU0             
                                  AL46     PVCCIN_CPU0             
                                  AL48     PVCCIN_CPU0             
                                  AL50     PVCCIN_CPU0             
                                  AL52     PVCCIN_CPU0             
                                  AL54     PVCCIN_CPU0             
                                  AL56     GND                     
                                  AL58     TP_CPU0_RSVD_212        
                                  AL60     TP_CPU0_RSVD_211        
                                  AL62     TP_CPU0_RSVD_210        
                                  AL64     GND                     
                                  AL66     M_C_DQS_DN<12>          
                                  AL68     GND                     
                                  AL74     M_C_DQS_DN<0>           
                                  AL76     GND                     
                                  AL78     GND                     
                                  AL80     GND                     
                                  AL82     GND                     
                                  AL84     M_A_DQS_DN<9>           
                                  AL86     GND                     
                                  AM1      GND                     
                                  AM3      UPI_CPU0_CPU1_P0P0_DN<9>
                                  AM5      PVCCIO_CPU0             
                                  AM7      UPI_CPU1_CPU0_P0P0_DP<11>
                                  AM9      UPI_CPU1_CPU0_P0P0_DN<10>
                                  AM11     PU_CPU0_TSC_SYNC        
                                  AM13     TP_CPU0_RSVD_TEST_3     
                                  AM19     TP_CPU0_PE_HP_SCL       
                                  AM21     PVCCMCP_CPU0            
                                  AM23     TP_CPU0_RSVD_208        
                                  AM25     PVCCMCP_CPU0            
                                  AM27     CLK_100M_CPU0_RC_REFCLK0_DP
                                  AM29     PVCCIO_CPU0             
                                  AM31     GND                     
                                  AM33     PVCCIN_CPU0             
                                  AM53     PVCCIN_CPU0             
                                  AM55     PVCCIN_CPU0             
                                  AM57     GND                     
                                  AM59     TP_CPU0_RSVD_205        
                                  AM61     TP_CPU0_RSVD_204        
                                  AM63     GND                     
                                  AM65     M_C_DQ<30>              
                                  AM67     M_C_DQ<24>              
                                  AM69     GND                     
                                  AM73     GND                     
                                  AM75     M_C_DQS_DP<0>           
                                  AM77     M_C_DQ<6>               
                                  AM79     GND                     
                                  AM81     M_B_DQ<3>               
                                  AM83     GND                     
                                  AM85     M_A_DQS_DP<9>           
                                  AN2      GND                     
                                  AN4      UPI_CPU0_CPU1_P0P0_DN<8>
                                  AN6      GND                     
                                  AN8      UPI_CPU1_CPU0_P0P0_DP<9>
                                  AN10     PVCCIO_CPU0             
                                  AN12     TP_CPU0_RSVD_TEST_4     
                                  AN14     TP_CPU0_RSVD_TEST_5     
                                  AN18     PVCCMCP_CPU0            
                                  AN20     H_CPU0_MSMI_G_N         
                                  AN22     PVCCMCP_CPU0            
                                  AN24     PVCCMCP_CPU0            
                                  AN26     PVCCMCP_CPU0            
                                  AN28     GND                     
                                  AN30     PWRGD_CPU0_DRAMPWROK_ABC_G
                                  AN32     PVCCIN_CPU0             
                                  AN54     PVCCIN_CPU0             
                                  AN56     PVCCIN_CPU0             
                                  AN58     GND                     
                                  AN60     TP_CPU0_RSVD_199        
                                  AN62     TP_CPU0_RSVD_198        
                                  AN64     M_C_DQ<26>              
                                  AN66     M_C_DQS_DP<12>          
                                  AN68     M_C_DQ<28>              
                                  AN74     M_C_DQ<1>               
                                  AN76     M_C_DQS_DP<9>           
                                  AN78     GND                     
                                  AN80     M_B_DQ<7>               
                                  AN82     M_B_DQ<2>               
                                  AN84     M_A_DQ<1>               
                                  AN86     M_A_DQ<0>               
                                  AP1      UPI_CPU0_CPU1_P0P0_DP<7>
                                  AP3      UPI_CPU0_CPU1_P0P0_DP<8>
                                  AP5      GND                     
                                  AP7      UPI_CPU1_CPU0_P0P0_DN<9>
                                  AP9      GND                     
                                  AP11     TP_NMI_CPU0             
                                  AP13     GND                     
                                  AP17     XDP_CPU_PWR_DEBUG_N     
                                  AP19     GND                     
                                  AP21     RST_CPU0_G_N            
                                  AP23     PVCCMCP_CPU0            
                                  AP25     PVCCMCP_CPU0            
                                  AP27     CLK_100M_CPU0_RC_REFCLK0_DN
                                  AP29     A_CPU0_UPI01_RBIAS      
                                  AP31     GND                     
                                  AP55     PVCCIN_CPU0             
                                  AP57     PVCCIN_CPU0             
                                  AP59     GND                     
                                  AP61     TP_CPU0_RSVD_194        
                                  AP63     GND                     
                                  AP65     GND                     
                                  AP67     GND                     
                                  AP69     GND                     
                                  AP73     GND                     
                                  AP75     GND                     
                                  AP77     M_C_DQS_DN<9>           
                                  AP79     M_B_DQS_DN<0>           
                                  AP81     GND                     
                                  AP83     GND                     
                                  AP85     GND                     
                                  AR2      UPI_CPU0_CPU1_P0P0_DP<6>
                                  AR4      UPI_CPU0_CPU1_P0P0_DP<5>
                                  AR6      GND                     
                                  AR8      UPI_CPU1_CPU0_P0P0_DN<8>
                                  AR10     GND                     
                                  AR12     XDP_CPU_PREQ_N          
                                  AR14     H_PM_SYNC_GTL_R1        
                                  AR16     TP_CPU0_TEST_6          
                                  AR18     PU_CPU0_SAFE_MODE_BOOT  
                                  AR20     PVCCMCP_CPU0            
                                  AR22     PVCCMCP_CPU0            
                                  AR24     GND                     
                                  AR26     PVCCMCP_CPU0            
                                  AR28     PVCCIO_CPU0             
                                  AR30     GND                     
                                  AR56     PVCCIN_CPU0             
                                  AR58     PVCCIN_CPU0             
                                  AR60     GND                     
                                  AR62     TP_CPU0_RSVD_190        
                                  AR64     M_C_DQ<27>              
                                  AR66     M_C_DQS_DP<3>           
                                  AR68     M_C_DQ<29>              
                                  AR72     GND                     
                                  AR74     M_C_DQ<5>               
                                  AR76     M_C_DQ<0>               
                                  AR78     GND                     
                                  AR80     M_B_DQS_DP<0>           
                                  AR82     M_B_DQ<6>               
                                  AR84     M_A_DQ<5>               
                                  AR86     M_A_DQ<4>               
                                  AT1      UPI_CPU0_CPU1_P0P0_DN<7>
                                  AT3      UPI_CPU0_CPU1_P0P0_DN<6>
                                  AT5      PVCCIO_CPU0             
                                  AT7      PVCCIO_CPU0             
                                  AT9      UPI_CPU1_CPU0_P0P0_DP<7>
                                  AT11     PVCCIO_CPU0             
                                  AT13     TP_CPU0_RSVD_189        
                                  AT15     GND                     
                                  AT17     GND                     
                                  AT19     H_PMSYNC_CLK_24M_CPU0   
                                  AT21     GND                     
                                  AT23     PVCCMCP_CPU0            
                                  AT25     PVCCMCP_CPU0            
                                  AT27     GND                     
                                  AT29     A_CPU0_UPI01_RBIAS      
                                  AT57     PVCCIN_CPU0             
                                  AT59     PVCCIN_CPU0             
                                  AT61     GND                     
                                  AT63     GND                     
                                  AT65     M_C_DQ<31>              
                                  AT67     M_C_DQ<25>              
                                  AT69     GND                     
                                  AT71     M_C_DQS_DN<17>          
                                  AT73     GND                     
                                  AT75     M_C_DQ<4>               
                                  AT77     GND                     
                                  AT79     M_B_DQ<1>               
                                  AT81     M_B_DQS_DP<9>           
                                  AT83     GND                     
                                  AT85     GND                     
                                  AU2      GND                     
                                  AU4      UPI_CPU0_CPU1_P0P0_DN<5>
                                  AU6      GND                     
                                  AU8      UPI_CPU1_CPU0_P0P0_DP<8>
                                  AU10     UPI_CPU1_CPU0_P0P0_DN<7>
                                  AU12     PECI_CPU_G              
                                  AU14     H_CPU0_FIVR_FAULT_G     
                                  AU16     PU_CPU0_SOCKET_ID_1     
                                  AU18     TP_CPU0_TEST_7          
                                  AU20     TP_CPU0_SOCKET_ID_2     
                                  AU22     PU_CPU0_SOCKET_ID_0     
                                  AU24     CLK_100M_CPU0_BCLK0_DN  
                                  AU26     GND                     
                                  AU28     GND                     
                                  AU58     PVCCIN_CPU0             
                                  AU60     PVCCIN_CPU0             
                                  AU62     GND                     
                                  AU64     GND                     
                                  AU66     M_C_DQS_DN<3>           
                                  AU68     GND                     
                                  AU70     M_C_ECC<6>              
                                  AU72     M_C_ECC<0>              
                                  AU74     GND                     
                                  AU76     GND                     
                                  AU78     GND                     
                                  AU80     GND                     
                                  AU82     M_B_DQS_DN<9>           
                                  AU84     GND                     
                                  AU86     GND                     
                                  AV1      GND                     
                                  AV3      GND                     
                                  AV5      UPI_CPU0_CPU1_P0P0_DN<4>
                                  AV7      GND                     
                                  AV9      UPI_CPU1_CPU0_P0P0_DP<3>
                                  AV11     GND                     
                                  AV13     GND                     
                                  AV15     PD_CPU0_TXT_PLTEN       
                                  AV17     PU_CPU0_FRMAGENT        
                                  AV19     GND                     
                                  AV21     XDP_PRESENT_N           
                                  AV23     GND                     
                                  AV25     GND                     
                                  AV27     PVCCIO_CPU0             
                                  AV59     PVCCIN_CPU0             
                                  AV61     PVCCIN_CPU0             
                                  AV63     GND                     
                                  AV65     GND                     
                                  AV67     GND                     
                                  AV69     M_C_ECC<2>              
                                  AV71     M_C_DQS_DP<17>          
                                  AV73     M_C_ECC<4>              
                                  AV75     GND                     
                                  AV77     TP_CPU0_RSVD_186        
                                  AV79     M_B_DQ<5>               
                                  AV81     M_B_DQ<0>               
                                  AV83     GND                     
                                  AV85     VSENSE_VCCINR2PMAX_CPU0 
                                  AW2      GND                     
                                  AW4      UPI_CPU0_CPU1_P0P0_DP<4>
                                  AW6      PVCCIO_CPU0             
                                  AW8      UPI_CPU1_CPU0_P0P0_DN<3>
                                  AW10     GND                     
                                  AW12     PD_CPU0_DMIMODE_OVERRIDE
                                  AW14     PD_CPU0_KSFC_DIS        
                                  AW16     TP_CPU0_TEST_8          
                                  AW18     PU_CPU0_TXT_AGENT       
                                  AW20     TP_CPU0_TEST_9          
                                  AW22     TP_CPU0_TEST_10         
                                  AW24     CLK_100M_CPU0_BCLK0_DP  
                                  AW26     PVCCIO_CPU0             
                                  AW60     PVCCIN_CPU0             
                                  AW62     GND                     
                                  AW64     TP_CPU0_RSVD_184        
                                  AW66     GND                     
                                  AW68     GND                     
                                  AW70     GND                     
                                  AW72     GND                     
                                  AW74     GND                     
                                  AW76     TP_CPU0_RSVD_183        
                                  AW78     GND                     
                                  AW80     M_B_DQ<4>               
                                  AW82     GND                     
                                  AW84     GND                     
                                  AW86     VSENSE_VCCINR2PMAX_CPU0 
                                  AY3      UPI_CPU0_CPU1_P0P0_DP<3>
                                  AY5      GND                     
                                  AY7      UPI_CPU1_CPU0_P0P0_DP<6>
                                  AY9      UPI_CPU1_CPU0_P0P0_DN<2>
                                  AY11     PVCCIO_CPU0             
                                  AY13     TP_CPU0_RSVD_TEST_11    
                                  AY15     GND                     
                                  AY17     GND                     
                                  AY19     PD_CPU0_TEST12          
                                  AY21     GND                     
                                  AY23     GND                     
                                  AY25     GND                     
                                  AY27     PVCCIO_CPU0             
                                  AY61     PVCCIN_CPU0             
                                  AY63     GND                     
                                  AY65     TP_CPU0_RSVD_182        
                                  AY67     TP_CPU0_RSVD_181        
                                  AY69     M_C_ECC<3>              
                                  AY71     M_C_DQS_DP<8>           
                                  AY73     M_C_ECC<5>              
                                  AY75     TP_CPU0_RSVD_180        
                                  AY77     TP_CPU0_RSVD_179        
                                  AY79     GND                     
                                  AY81     GND                     
                                  AY83     TP_CPU0_RSVD_255        
                                  AY85     VSENSE_PVCCIN_CPU0_SKT_VRTN
                                  B3       TP_CPU0_RSVD_299        
                                  B5       GND                     
                                  B7       TP_CPU0_RSVD_298        
                                  B9       GND                     
                                  B11      PVPP_ABC                
                                  B13      P1V8_MCP_CPU0           
                                  B15      P1V8_MCP_CPU0           
                                  B17      P1V8_MCP_CPU0           
                                  B25      GND                     
                                  B27      M_B_DQ<54>              
                                  B29      M_B_DQ<49>              
                                  B31      GND                     
                                  B33      M_B_DQ<46>              
                                  B35      M_B_DQ<41>              
                                  B37      GND                     
                                  B39      M_A_DQ<38>              
                                  B41      M_A_DQ<33>              
                                  B43      GND                     
                                  B47      PVDDQ_ABC               
                                  B49      PVDDQ_ABC               
                                  B51      M_A_CS_N<4>             
                                  B53      PVDDQ_ABC               
                                  B55      M_A_CLK_DP<1>           
                                  B57      M_A_CLK_DP<3>           
                                  B59      PVDDQ_ABC               
                                  B61      M_A_ALERT_N             
                                  B63      M_A_CKE<2>              
                                  B71      GND                     
                                  B73      M_B_DQS_DN<12>          
                                  B75      GND                     
                                  B77      TP_CPU0_RSVD_293        
                                  B79      GND                     
                                  B81      TP_CPU0_RSVD_292        
                                  BA2      GND                     
                                  BA4      UPI_CPU0_CPU1_P0P0_DN<3>
                                  BA6      GND                     
                                  BA8      UPI_CPU1_CPU0_P0P0_DN<6>
                                  BA10     UPI_CPU1_CPU0_P0P0_DP<0>
                                  BA12     GND                     
                                  BA14     TP_CPU0_RSVD_178        
                                  BA16     TP_CPU0_RSVD_177        
                                  BA18     TP_CPU0_RSVD_176        
                                  BA20     PD_CPU0_BIST_ENABLE     
                                  BA22     TP_CPU0_RSVD_175        
                                  BA24     PVCCIO_CPU0             
                                  BA26     PVCCIO_CPU0             
                                  BA60     PVCCIN_CPU0             
                                  BA62     GND                     
                                  BA64     TP_CPU0_RSVD_174        
                                  BA66     TP_CPU0_RSVD_173        
                                  BA68     GND                     
                                  BA70     M_C_ECC<7>              
                                  BA72     M_C_ECC<1>              
                                  BA74     GND                     
                                  BA76     TP_CPU0_RSVD_172        
                                  BA78     TP_CPU0_RSVD_171        
                                  BA80     GND                     
                                  BA82     TP_CPU0_RSVD_170        
                                  BA84     GND                     
                                  BA86     VSENSE_PVCCIN_CPU0_SKT_VSEN
                                  BB3      UPI_CPU0_CPU1_P0P0_DN<2>
                                  BB5      PVCCIO_CPU0             
                                  BB7      UPI_CPU1_CPU0_P0P0_DP<5>
                                  BB9      UPI_CPU1_CPU0_P0P0_DP<2>
                                  BB11     UPI_CPU1_CPU0_P0P0_DN<0>
                                  BB13     TP_CPU0_RSVD_169        
                                  BB15     TP_CPU0_RSVD_168        
                                  BB17     TP_CPU0_RSVD_167        
                                  BB19     GND                     
                                  BB21     TP_CPU0_RSVD_166        
                                  BB23     GND                     
                                  BB25     CLK_100M_CPU0_RC_REFCLK1_DN
                                  BB27     PVCCIO_CPU0             
                                  BB61     PVCCIN_CPU0             
                                  BB63     GND                     
                                  BB65     TP_CPU0_RSVD_164        
                                  BB67     TP_CPU0_RSVD_163        
                                  BB69     GND                     
                                  BB71     M_C_DQS_DN<8>           
                                  BB73     GND                     
                                  BB75     GND                     
                                  BB77     GND                     
                                  BB79     GND                     
                                  BB81     GND                     
                                  BB83     GND                     
                                  BB85     PVCCIN_CPU0             
                                  BC2      UPI_CPU0_CPU1_P0P0_DP<2>
                                  BC4      GND                     
                                  BC6      UPI_CPU1_CPU0_P0P0_DN<5>
                                  BC8      GND                     
                                  BC10     UPI_CPU1_CPU0_P0P0_DP<1>
                                  BC12     GND                     
                                  BC14     TP_CPU0_RSVD_162        
                                  BC16     GND                     
                                  BC18     TP_CPU0_RSVD_161        
                                  BC20     TP_CPU0_RSVD_160        
                                  BC22     TP_CPU0_RSVD_159        
                                  BC24     PWRGD_CPU0_G            
                                  BC26     PVCCIO_CPU0             
                                  BC60     PVCCIN_CPU0             
                                  BC62     PVCCIN_CPU0             
                                  BC64     TP_CPU0_RSVD_158        
                                  BC66     TP_CPU0_RSVD_157        
                                  BC68     TP_CPU0_RSVD_156        
                                  BC70     GND                     
                                  BC72     GND                     
                                  BC74     GND                     
                                  BC76     GND                     
                                  BC78     GND                     
                                  BC80     GND                     
                                  BC82     GND                     
                                  BC84     PVCCIN_CPU0             
                                  BD3      UPI_CPU0_CPU1_P0P0_DP<1>
                                  BD5      GND                     
                                  BD7      UPI_CPU1_CPU0_P0P0_DN<4>
                                  BD9      UPI_CPU1_CPU0_P0P0_DN<1>
                                  BD11     GND                     
                                  BD13     PVCCMCP_CPU0            
                                  BD15     GND                     
                                  BD17     TP_CPU0_RSVD_155        
                                  BD19     TP_CPU0_RSVD_154        
                                  BD21     GND                     
                                  BD23     H_CPU0_BMCINIT          
                                  BD25     CLK_100M_CPU0_RC_REFCLK1_DP
                                  BD27     GND                     
                                  BD61     PVCCIN_CPU0             
                                  BD63     GND                     
                                  BD65     TP_CPU0_RSVD_152        
                                  BD67     TP_CPU0_RSVD_151        
                                  BD69     TP_CPU0_RSVD_150        
                                  BD71     GND                     
                                  BD73     PVCCIN_CPU0             
                                  BD75     PVCCIN_CPU0             
                                  BD77     PVCCIN_CPU0             
                                  BD79     PVCCIN_CPU0             
                                  BD81     PVCCIN_CPU0             
                                  BD83     PVCCIN_CPU0             
                                  BD85     PVCCIN_CPU0             
                                  BE4      GND                     
                                  BE6      GND                     
                                  BE8      GND                     
                                  BE10     GND                     
                                  BE12     PVCCMCP_CPU0            
                                  BE14     PVCCMCP_CPU0            
                                  BE16     CLK_156M_OSC_CPU0_HFI_DN
                                  BE18     TP_CPU0_RSVD_149        
                                  BE20     TP_CPU0_RSVD_148        
                                  BE22     TP_CPU0_RSVD_147        
                                  BE24     PVCCIO_CPU0             
                                  BE26     GND                     
                                  BE60     PVCCIN_CPU0             
                                  BE62     PVCCIN_CPU0             
                                  BE64     GND                     
                                  BE66     GND                     
                                  BE68     GND                     
                                  BE70     GND                     
                                  BE72     PVCCIN_CPU0             
                                  BE74     PVCCIN_CPU0             
                                  BE76     PVCCIN_CPU0             
                                  BE78     PVCCIN_CPU0             
                                  BE80     PVCCIN_CPU0             
                                  BE82     PVCCIN_CPU0             
                                  BE84     PVCCIN_CPU0             
                                  BF3      UPI_CPU0_CPU1_P0P0_DN<1>
                                  BF5      VSENSE_PVCCIO_CPU0_SKT_VRTN
                                  BF7      UPI_CPU1_CPU0_P0P0_DP<4>
                                  BF9      GND                     
                                  BF11     PVCCMCP_CPU0            
                                  BF13     PVCCMCP_CPU0            
                                  BF15     GND                     
                                  BF17     GND                     
                                  BF19     GND                     
                                  BF21     TP_CPU0_RSVD_146        
                                  BF23     PVCCIO_CPU0             
                                  BF25     GND                     
                                  BF27     PVCCIO_CPU0             
                                  BF61     PVCCIN_CPU0             
                                  BF63     GND                     
                                  BF65     GND                     
                                  BF67     GND                     
                                  BF69     GND                     
                                  BF71     GND                     
                                  BF73     PVCCIN_CPU0             
                                  BF75     PVCCIN_CPU0             
                                  BF77     PVCCIN_CPU0             
                                  BF79     PVCCIN_CPU0             
                                  BF81     PVCCIN_CPU0             
                                  BF83     PVCCIN_CPU0             
                                  BF85     PVCCIN_CPU0             
                                  BG4      UPI_CPU0_CPU1_P0P0_DN<0>
                                  BG6      GND                     
                                  BG8      GND                     
                                  BG10     GND                     
                                  BG12     PVCCMCP_CPU0            
                                  BG14     PVCCMCP_CPU0            
                                  BG16     CLK_156M_OSC_CPU0_HFI_DP
                                  BG18     TP_CPU0_RSVD_145        
                                  BG20     TP_CPU0_RSVD_144        
                                  BG22     GND                     
                                  BG24     GND                     
                                  BG26     PVCCIO_CPU0             
                                  BG60     PVCCIN_CPU0             
                                  BG62     PVCCIN_CPU0             
                                  BG64     PVCCIN_CPU0             
                                  BG66     PVCCIN_CPU0             
                                  BG68     PVCCIN_CPU0             
                                  BG70     PVCCIN_CPU0             
                                  BG72     GND                     
                                  BG74     GND                     
                                  BG76     GND                     
                                  BG78     GND                     
                                  BG80     GND                     
                                  BG82     GND                     
                                  BG84     PVCCIN_CPU0             
                                  BH3      UPI_CPU0_CPU1_P0P0_DP<0>
                                  BH5      VSENSE_PVCCIO_CPU0_SKT_VSEN
                                  BH7      GND                     
                                  BH9      GND                     
                                  BH11     GND                     
                                  BH13     PVCCMCP_CPU0            
                                  BH15     GND                     
                                  BH17     GND                     
                                  BH19     PVCCMCP_CPU0            
                                  BH21     GND                     
                                  BH23     SMB_HFI1_CPU0_LVC2_SDA  
                                  BH25     PVCCIO_CPU0             
                                  BH27     PVCCIO_CPU0             
                                  BH61     PVCCIN_CPU0             
                                  BH63     PVCCIN_CPU0             
                                  BH65     PVCCIN_CPU0             
                                  BH67     PVCCIN_CPU0             
                                  BH69     PVCCIN_CPU0             
                                  BH71     PVCCIN_CPU0             
                                  BH73     PVCCIN_CPU0             
                                  BH75     PVCCIN_CPU0             
                                  BH77     PVCCIN_CPU0             
                                  BH79     PVCCIN_CPU0             
                                  BH81     PVCCIN_CPU0             
                                  BH83     PVCCIN_CPU0             
                                  BJ4      GND                     
                                  BJ6      GND                     
                                  BJ8      P3E_CPU0_PE2_SS_RXP<14> 
                                  BJ10     P3E_CPU0_PE2_SS_RXP<15> 
                                  BJ12     PVCCMCP_CPU0            
                                  BJ14     PVCCMCP_CPU0            
                                  BJ16     PVCCMCP_CPU0            
                                  BJ18     PVCCMCP_CPU0            
                                  BJ20     PVCCMCP_CPU0            
                                  BJ22     SMB_HFI1_CPU0_LVC2_SCL  
                                  BJ24     PVCCIO_CPU0             
                                  BJ26     PVCCIO_CPU0             
                                  BJ60     PVCCIN_CPU0             
                                  BJ62     PVCCIN_CPU0             
                                  BJ64     PVCCIN_CPU0             
                                  BJ66     PVCCIN_CPU0             
                                  BJ68     PVCCIN_CPU0             
                                  BJ70     PVCCIN_CPU0             
                                  BJ72     PVCCIN_CPU0             
                                  BJ74     PVCCIN_CPU0             
                                  BJ76     PVCCIN_CPU0             
                                  BJ78     PVCCIN_CPU0             
                                  BJ80     PVCCIN_CPU0             
                                  BJ82     PVCCIN_CPU0             
                                  BJ84     PVCCIN_CPU0             
                                  BK3      GND                     
                                  BK5      P3E_CPU0_PE2_SS_TXP<15> 
                                  BK7      GND                     
                                  BK9      P3E_CPU0_PE2_SS_RXN<15> 
                                  BK11     GND                     
                                  BK13     PVCCMCP_CPU0            
                                  BK15     PVCCMCP_CPU0            
                                  BK17     PVCCMCP_CPU0            
                                  BK19     GND                     
                                  BK21     LED_HFI0_CPU0_N         
                                  BK23     RST_HFI1_CPU0_LVT2_N    
                                  BK25     PVCCIO_CPU0             
                                  BK27     PVCCIO_CPU0             
                                  BK61     PVCCIN_CPU0             
                                  BK63     PVCCIN_CPU0             
                                  BK65     PVCCIN_CPU0             
                                  BK67     PVCCIN_CPU0             
                                  BK69     PVCCIN_CPU0             
                                  BK71     PVCCIN_CPU0             
                                  BK73     PVCCIN_CPU0             
                                  BK75     PVCCIN_CPU0             
                                  BK77     PVCCIN_CPU0             
                                  BK79     PVCCIN_CPU0             
                                  BK81     PVCCIN_CPU0             
                                  BK83     PVCCIN_CPU0             
                                  BL4      P3E_CPU0_PE2_SS_TXN<14> 
                                  BL6      GND                     
                                  BL8      P3E_CPU0_PE2_SS_RXN<14> 
                                  BL10     GND                     
                                  BL12     GND                     
                                  BL14     PVCCMCP_CPU0            
                                  BL16     VSENSE_PVCCMCP_CPU0_SKT_VRTN
                                  BL18     PVCCMCP_CPU0            
                                  BL20     PVCCMCP_CPU0            
                                  BL22     GND                     
                                  BL24     GND                     
                                  BL26     PVCCIO_CPU0             
                                  BL60     PVCCIN_CPU0             
                                  BL62     PVCCIN_CPU0             
                                  BL64     GND                     
                                  BL66     GND                     
                                  BL68     GND                     
                                  BL70     GND                     
                                  BL72     GND                     
                                  BL74     GND                     
                                  BL76     GND                     
                                  BL78     GND                     
                                  BL80     GND                     
                                  BL82     GND                     
                                  BL84     PVCCIN_CPU0             
                                  BM3      P3E_CPU0_PE2_SS_TXP<14> 
                                  BM5      P3E_CPU0_PE2_SS_TXN<15> 
                                  BM7      P3E_CPU0_PE2_SS_RXP<13> 
                                  BM9      GND                     
                                  BM11     PVCCIOMCP_CPU0          
                                  BM13     GND                     
                                  BM15     GND                     
                                  BM17     PVCCMCP_CPU0            
                                  BM19     PVCCMCP_CPU0            
                                  BM21     IRQ_HFI1_CPU0_LVT2_N    
                                  BM23     LED_HFI1_CPU0_N         
                                  BM25     GND                     
                                  BM27     PVCCIO_CPU0             
                                  BM61     PVCCIN_CPU0             
                                  BM63     PVCCIN_CPU0             
                                  BM65     PVCCIN_CPU0             
                                  BM67     PVCCIN_CPU0             
                                  BM69     PVCCIN_CPU0             
                                  BM71     PVCCIN_CPU0             
                                  BM73     PVCCIN_CPU0             
                                  BM75     PVCCIN_CPU0             
                                  BM77     PVCCIN_CPU0             
                                  BM79     PVCCIN_CPU0             
                                  BM81     PVCCIN_CPU0             
                                  BM83     PVCCIN_CPU0             
                                  BN4      P3E_CPU0_PE2_SS_TXP<13> 
                                  BN6      GND                     
                                  BN8      P3E_CPU0_PE2_SS_RXN<13> 
                                  BN10     GND                     
                                  BN12     PVCCIOMCP_CPU0          
                                  BN14     PVCCIOMCP_CPU0          
                                  BN16     VSENSE_PVCCMCP_CPU0_SKT_VSEN
                                  BN18     PVCCMCP_CPU0            
                                  BN20     GND                     
                                  BN22     SMB_HFI0_CPU0_LVC2_SCL  
                                  BN24     RST_HFI0_CPU0_LVT2_N    
                                  BN26     GND                     
                                  BN60     PVCCIN_CPU0             
                                  BN62     PVCCIN_CPU0             
                                  BN64     PVCCIN_CPU0             
                                  BN66     PVCCIN_CPU0             
                                  BN68     PVCCIN_CPU0             
                                  BN70     PVCCIN_CPU0             
                                  BN72     PVCCIN_CPU0             
                                  BN74     PVCCIN_CPU0             
                                  BN76     PVCCIN_CPU0             
                                  BN78     PVCCIN_CPU0             
                                  BN80     PVCCIN_CPU0             
                                  BN82     PVCCIN_CPU0             
                                  BN84     PVCCIN_CPU0             
                                  BP3      GND                     
                                  BP5      P3E_CPU0_PE2_SS_TXN<13> 
                                  BP7      P3E_CPU0_PE2_SS_RXP<11> 
                                  BP9      P3E_CPU0_PE2_SS_RXP<12> 
                                  BP11     PVCCIOMCP_CPU0          
                                  BP13     PVCCIOMCP_CPU0          
                                  BP15     PVCCIOMCP_CPU0          
                                  BP17     PVCCMCP_CPU0            
                                  BP19     IRQ_HFI0_CPU0_LVT2_N    
                                  BP21     PVCCMCP_CPU0            
                                  BP23     SMB_HFI0_CPU0_LVC2_SDA  
                                  BP25     PVCCIO_CPU0             
                                  BP27     GND                     
                                  BP61     PVCCIN_CPU0             
                                  BP63     PVCCIN_CPU0             
                                  BP65     PVCCIN_CPU0             
                                  BP67     PVCCIN_CPU0             
                                  BP69     PVCCIN_CPU0             
                                  BP71     PVCCIN_CPU0             
                                  BP73     PVCCIN_CPU0             
                                  BP75     PVCCIN_CPU0             
                                  BP77     PVCCIN_CPU0             
                                  BP79     PVCCIN_CPU0             
                                  BP81     PVCCIN_CPU0             
                                  BP83     PVCCIN_CPU0             
                                  BR4      P3E_CPU0_PE2_SS_TXP<12> 
                                  BR6      GND                     
                                  BR8      P3E_CPU0_PE2_SS_RXN<12> 
                                  BR10     GND                     
                                  BR12     PVCCIOMCP_CPU0          
                                  BR14     PVCCIOMCP_CPU0          
                                  BR16     GND                     
                                  BR18     GND                     
                                  BR20     FM_MODPRST_HFI0_CPU0_LVT2_N
                                  BR22     PVCCMCP_CPU0            
                                  BR24     PVCCMCP_CPU0            
                                  BR26     GND                     
                                  BR60     PVCCIN_CPU0             
                                  BR62     PVCCIN_CPU0             
                                  BR64     GND                     
                                  BR66     GND                     
                                  BR68     GND                     
                                  BR70     GND                     
                                  BR72     GND                     
                                  BR74     GND                     
                                  BR76     GND                     
                                  BR78     GND                     
                                  BR80     GND                     
                                  BR82     GND                     
                                  BR84     PVCCIN_CPU0             
                                  BT3      GND                     
                                  BT5      GND                     
                                  BT7      P3E_CPU0_PE2_SS_RXN<11> 
                                  BT9      GND                     
                                  BT11     PVCCIOMCP_CPU0          
                                  BT13     PVCCIOMCP_CPU0          
                                  BT15     PVCCIOMCP_CPU0          
                                  BT17     VSENSE_PVCCIOMCP_CPU0_SKT_VSEN
                                  BT19     FM_MODPRST_HFI1_CPU0_LVT2_N
                                  BT21     GND                     
                                  BT23     GND                     
                                  BT25     GND                     
                                  BT27     P1V8_MCP_CPU0           
                                  BT61     PVCCIN_CPU0             
                                  BT63     PVCCIN_CPU0             
                                  BT65     PVCCIN_CPU0             
                                  BT67     PVCCIN_CPU0             
                                  BT69     PVCCIN_CPU0             
                                  BT71     PVCCIN_CPU0             
                                  BT73     PVCCIN_CPU0             
                                  BT75     PVCCIN_CPU0             
                                  BT77     PVCCIN_CPU0             
                                  BT79     PVCCIN_CPU0             
                                  BT81     PVCCIN_CPU0             
                                  BT83     PVCCIN_CPU0             
                                  BU4      P3E_CPU0_PE2_SS_TXN<12> 
                                  BU6      P3E_CPU0_PE2_SS_RXP<10> 
                                  BU8      GND                     
                                  BU10     GND                     
                                  BU12     PVCCIOMCP_CPU0          
                                  BU14     PVCCIOMCP_CPU0          
                                  BU16     VSENSE_PVCCIOMCP_CPU0_SKT_VRTN
                                  BU18     PVCCMCP_CPU0            
                                  BU20     PVCCMCP_CPU0            
                                  BU22     PVCCMCP_CPU0            
                                  BU24     CLK_100M_CPU0_PE_REFCLK_DN
                                  BU26     P1V8_MCP_CPU0           
                                  BU60     PVCCIN_CPU0             
                                  BU62     PVCCIN_CPU0             
                                  BU64     PVCCIN_CPU0             
                                  BU66     PVCCIN_CPU0             
                                  BU68     PVCCIN_CPU0             
                                  BU70     PVCCIN_CPU0             
                                  BU72     PVCCIN_CPU0             
                                  BU74     PVCCIN_CPU0             
                                  BU76     PVCCIN_CPU0             
                                  BU78     PVCCIN_CPU0             
                                  BU80     PVCCIN_CPU0             
                                  BU82     PVCCIN_CPU0             
                                  BU84     PVCCIN_CPU0             
                                  BV3      P3E_CPU0_PE2_SS_TXP<11> 
                                  BV5      GND                     
                                  BV7      P3E_CPU0_PE2_SS_RXN<10> 
                                  BV9      P3E_CPU0_PE2_SS_RXP<8>  
                                  BV11     PVCCIOMCP_CPU0          
                                  BV13     PVCCIOMCP_CPU0          
                                  BV15     PVCCIOMCP_CPU0          
                                  BV17     GND                     
                                  BV19     PVCCMCP_CPU0            
                                  BV21     PVCCMCP_CPU0            
                                  BV23     TP_CPU0_RSVD_124        
                                  BV25     GND                     
                                  BV27     P1V8_MCP_CPU0           
                                  BV61     PVCCIN_CPU0             
                                  BV63     PVCCIN_CPU0             
                                  BV65     PVCCIN_CPU0             
                                  BV67     PVCCIN_CPU0             
                                  BV69     PVCCIN_CPU0             
                                  BV71     PVCCIN_CPU0             
                                  BV73     PVCCIN_CPU0             
                                  BV75     PVCCIN_CPU0             
                                  BV77     PVCCIN_CPU0             
                                  BV79     PVCCIN_CPU0             
                                  BV81     PVCCIN_CPU0             
                                  BV83     PVCCIN_CPU0             
                                  BW4      P3E_CPU0_PE2_SS_TXN<11> 
                                  BW6      GND                     
                                  BW8      P3E_CPU0_PE2_SS_RXP<9>  
                                  BW10     TP_CPU0_RSVD_123        
                                  BW12     GND                     
                                  BW14     GND                     
                                  BW16     GND                     
                                  BW18     GND                     
                                  BW20     PVCCMCP_CPU0            
                                  BW22     TP_CPU0_RSVD_121        
                                  BW24     CLK_100M_CPU0_PE_REFCLK_DP
                                  BW26     GND                     
                                  BW60     PVCCIN_CPU0             
                                  BW62     PVCCIN_CPU0             
                                  BW64     PVCCIN_CPU0             
                                  BW66     PVCCIN_CPU0             
                                  BW68     PVCCIN_CPU0             
                                  BW70     PVCCIN_CPU0             
                                  BW72     GND                     
                                  BW74     GND                     
                                  BW76     GND                     
                                  BW78     GND                     
                                  BW80     GND                     
                                  BW82     GND                     
                                  BW84     PVCCIN_CPU0             
                                  BY3      P3E_CPU0_PE2_SS_TXP<9>  
                                  BY5      P3E_CPU0_PE2_SS_TXP<10> 
                                  BY7      P3E_CPU0_PE2_SS_RXN<9>  
                                  BY9      P3E_CPU0_PE2_SS_RXN<8>  
                                  BY11     GND                     
                                  BY13     GND                     
                                  BY15     GND                     
                                  BY17     GND                     
                                  BY19     PVCCMCP_CPU0            
                                  BY21     JTAG_MCP_CPU0_TDI       
                                  BY23     GND                     
                                  BY25     TP_CPU0_RSVD_119        
                                  BY27     P1V8_MCP_CPU0           
                                  BY61     PVCCIN_CPU0             
                                  BY63     GND                     
                                  BY65     GND                     
                                  BY67     GND                     
                                  BY69     GND                     
                                  BY71     GND                     
                                  BY73     PVCCIN_CPU0             
                                  BY75     PVCCIN_CPU0             
                                  BY77     PVCCIN_CPU0             
                                  BY79     PVCCIN_CPU0             
                                  BY81     PVCCIN_CPU0             
                                  BY83     PVCCIN_CPU0             
                                  C4       GND                     
                                  C6       TP_CPU0_RSVD_291        
                                  C8       GND                     
                                  C10      GND                     
                                  C12      GND                     
                                  C14      GND                     
                                  C16      GND                     
                                  C18      TP_CPU0_RSVD_290        
                                  C24      TP_CPU0_RSVD_289        
                                  C26      M_B_DQ<50>              
                                  C28      M_B_DQS_DP<15>          
                                  C30      M_B_DQ<48>              
                                  C32      M_B_DQ<42>              
                                  C34      M_B_DQS_DP<14>          
                                  C36      M_B_DQ<40>              
                                  C38      M_A_DQ<34>              
                                  C40      M_A_DQS_DP<13>          
                                  C42      M_A_DQ<32>              
                                  C46      PVDDQ_ABC               
                                  C48      M_A_ODT<1>              
                                  C50      M_A_ODT<0>              
                                  C52      M_A_BA<0>               
                                  C54      M_A_CLK_DN<1>           
                                  C56      M_A_CLK_DN<3>           
                                  C58      M_A_MA<3>               
                                  C60      M_A_MA<8>               
                                  C62      M_A_CKE<0>              
                                  C64      M_A_CKE<1>              
                                  C72      M_B_DQ<30>              
                                  C74      M_B_DQ<25>              
                                  C76      GND                     
                                  C78      GND                     
                                  C80      GND                     
                                  C82      TP_CPU0_RSVD_288        
                                  CA2      GND                     
                                  CA4      P3E_CPU0_PE2_SS_TXN<10> 
                                  CA6      GND                     
                                  CA8      GND                     
                                  CA10     GND                     
                                  CA12     TP_CPU0_UPI2_RSVD_DP21  
                                  CA14     GND                     
                                  CA16     GND                     
                                  CA18     GND                     
                                  CA20     GND                     
                                  CA22     PVCCMCP_CPU0            
                                  CA24     TP_CPU0_RSVD_117        
                                  CA26     GND                     
                                  CA60     PVCCIN_CPU0             
                                  CA62     PVCCIN_CPU0             
                                  CA64     GND                     
                                  CA66     GND                     
                                  CA68     GND                     
                                  CA70     GND                     
                                  CA72     PVCCIN_CPU0             
                                  CA74     PVCCIN_CPU0             
                                  CA76     PVCCIN_CPU0             
                                  CA78     PVCCIN_CPU0             
                                  CA80     PVCCIN_CPU0             
                                  CA82     PVCCIN_CPU0             
                                  CA84     PVCCIN_CPU0             
                                  CB3      P3E_CPU0_PE2_SS_TXN<9>  
                                  CB5      TP_CPU0_RSVD_113        
                                  CB7      GND                     
                                  CB9      GND                     
                                  CB11     TP_CPU0_UPI2_RSVD_DN20  
                                  CB13     PVCCIO_CPU0             
                                  CB15     GND                     
                                  CB17     PVCCIO_CPU0             
                                  CB19     PVCCMCP_CPU0            
                                  CB21     PVCCMCP_CPU0            
                                  CB23     JTAG_MCP_TCK            
                                  CB25     TP_CPU0_RSVD_114        
                                  CB27     GND                     
                                  CB61     PVCCIN_CPU0             
                                  CB63     GND                     
                                  CB65     PVSA_CPU0               
                                  CB67     PVSA_CPU0               
                                  CB69     PVSA_CPU0               
                                  CB71     GND                     
                                  CB73     PVCCIN_CPU0             
                                  CB75     PVCCIN_CPU0             
                                  CB77     PVCCIN_CPU0             
                                  CB79     PVCCIN_CPU0             
                                  CB81     PVCCIN_CPU0             
                                  CB83     PVCCIN_CPU0             
                                  CC2      P3E_CPU0_PE2_SS_TXN<8>  
                                  CC4      GND                     
                                  CC6      TP_CPU0_RSVD_111        
                                  CC8      P3E_CPU0_PE2_SS_RXP<7>  
                                  CC10     TP_CPU0_UPI2_RSVD_DM21  
                                  CC12     TP_CPU0_UPI2_RSVD_DT21  
                                  CC14     GND                     
                                  CC16     GND                     
                                  CC18     GND                     
                                  CC20     PVCCMCP_CPU0            
                                  CC22     JTAG_MCP_CPU0_TDO       
                                  CC24     GND                     
                                  CC26     PVCCIO_CPU0             
                                  CC60     PVCCIN_CPU0             
                                  CC62     PVCCIN_CPU0             
                                  CC64     GND                     
                                  CC66     PVSA_CPU0               
                                  CC68     PVSA_CPU0               
                                  CC70     PVSA_CPU0               
                                  CC72     GND                     
                                  CC74     GND                     
                                  CC76     GND                     
                                  CC78     GND                     
                                  CC80     GND                     
                                  CC82     GND                     
                                  CC84     PVCCIN_CPU0             
                                  CD3      P3E_CPU0_PE2_SS_TXP<8>  
                                  CD5      GND                     
                                  CD7      P3E_CPU0_PE2_SS_RXP<6>  
                                  CD9      PVCCIO_CPU0             
                                  CD11     TP_CPU0_UPI2_RSVD_DK19  
                                  CD13     GND                     
                                  CD15     GND                     
                                  CD17     GND                     
                                  CD19     PVCCMCP_CPU0            
                                  CD21     PVCCMCP_CPU0            
                                  CD23     JTAG_MCP_TRST_N         
                                  CD25     TP_CPU0_RSVD_108        
                                  CD27     PVCCIO_CPU0             
                                  CD61     PVCCIN_CPU0             
                                  CD63     GND                     
                                  CD65     PVSA_CPU0               
                                  CD67     PVSA_CPU0               
                                  CD69     PVSA_CPU0               
                                  CD71     PVSA_CPU0               
                                  CD73     GND                     
                                  CD75     GND                     
                                  CD77     GND                     
                                  CD79     GND                     
                                  CD81     GND                     
                                  CD83     PVCCIN_CPU0             
                                  CD85     PVCCIN_CPU0             
                                  CE2      P3E_CPU0_PE2_SS_TXP<6>  
                                  CE4      P3E_CPU0_PE2_SS_TXP<7>  
                                  CE6      P3E_CPU0_PE2_SS_RXN<6>  
                                  CE8      P3E_CPU0_PE2_SS_RXN<7>  
                                  CE10     GND                     
                                  CE12     TP_CPU0_UPI2_RSVD_DL20  
                                  CE14     GND                     
                                  CE16     GND                     
                                  CE18     PVCCIO_CPU0             
                                  CE20     GND                     
                                  CE22     PVCCMCP_CPU0            
                                  CE24     JTAG_MCP_TMS            
                                  CE26     GND                     
                                  CE60     PVCCIN_CPU0             
                                  CE62     GND                     
                                  CE64     PVSA_CPU0               
                                  CE66     PVSA_CPU0               
                                  CE68     PVSA_CPU0               
                                  CE70     GND                     
                                  CE72     PVSA_CPU0               
                                  CE74     PVSA_CPU0               
                                  CE76     VSENSE_PVSA_CPU0_SKT_VSEN
                                  CE78     TP_CPU0_RSVD_106        
                                  CE80     TP_CPU0_RSVD_105        
                                  CE82     GND                     
                                  CE84     PVCCIN_CPU0             
                                  CF3      P3E_CPU0_PE2_SS_TXN<7>  
                                  CF5      PVCCIO_CPU0             
                                  CF7      P3E_CPU0_PE2_SS_RXP<5>  
                                  CF9      GND                     
                                  CF11     TP_CPU0_UPI2_RSVD_DJ20  
                                  CF13     TP_CPU0_UPI2_RSVD_DH19  
                                  CF15     GND                     
                                  CF17     GND                     
                                  CF19     PVCCMCP_CPU0            
                                  CF21     PVCCMCP_CPU0            
                                  CF23     PVCCMCP_CPU0            
                                  CF25     RST_CD_CPU0_POR_N       
                                  CF27     PVCCIO_CPU0             
                                  CF61     PVCCIN_CPU0             
                                  CF63     GND                     
                                  CF65     PVSA_CPU0               
                                  CF67     PVSA_CPU0               
                                  CF69     GND                     
                                  CF71     GND                     
                                  CF73     PVSA_CPU0               
                                  CF75     PVSA_CPU0               
                                  CF77     GND                     
                                  CF79     TP_CPU0_RSVD_101        
                                  CF81     TP_CPU0_RSVD_100        
                                  CF83     GND                     
                                  CF85     PVCCIN_CPU0             
                                  CG2      P3E_CPU0_PE2_SS_TXN<6>  
                                  CG4      DMI_CPU0_PCH_TX_DN<0>   
                                  CG6      GND                     
                                  CG8      P3E_CPU0_PE2_SS_RXN<5>  
                                  CG10     TP_CPU0_RSVD_99         
                                  CG12     TP_CPU0_UPI2_RSVD_DJ18  
                                  CG14     PVCCIO_CPU0             
                                  CG16     GND                     
                                  CG18     GND                     
                                  CG20     PVCCMCP_CPU0            
                                  CG22     GND                     
                                  CG24     TP_CPU0_RSVD_97         
                                  CG26     PVCCMCP_CPU0            
                                  CG60     PVCCIN_CPU0             
                                  CG62     GND                     
                                  CG64     PVSA_CPU0               
                                  CG66     PVSA_CPU0               
                                  CG68     GND                     
                                  CG70     M_F_DQS_DP<17>          
                                  CG72     GND                     
                                  CG74     PVSA_CPU0               
                                  CG76     VSENSE_PVSA_CPU0_SKT_VRTN
                                  CG78     TP_CPU0_RSVD_95         
                                  CG80     GND                     
                                  CG82     TP_CPU0_RSVD_94         
                                  CG84     PVCCIN_CPU0             
                                  CH1      GND                     
                                  CH3      GND                     
                                  CH5      DMI_CPU0_PCH_TX_DP<0>   
                                  CH7      P3E_CPU0_PE2_SS_RXP<4>  
                                  CH9      PVCCIO_CPU0             
                                  CH11     TP_CPU0_UPI2_RSVD_DG20  
                                  CH13     TP_CPU0_UPI2_RSVD_DH17  
                                  CH15     GND                     
                                  CH17     GND                     
                                  CH19     GND                     
                                  CH21     PVCCMCP_CPU0            
                                  CH23     PVCCMCP_CPU0            
                                  CH25     TP_CPU0_RSVD_91         
                                  CH27     PVCCIO_CPU0             
                                  CH61     PVCCIN_CPU0             
                                  CH63     GND                     
                                  CH65     PVSA_CPU0               
                                  CH67     GND                     
                                  CH69     M_F_ECC<6>              
                                  CH71     M_F_ECC<0>              
                                  CH73     GND                     
                                  CH75     PVSA_CPU0               
                                  CH77     TP_CPU0_RSVD_90         
                                  CH79     GND                     
                                  CH81     GND                     
                                  CH83     GND                     
                                  CH85     PVCCIN_CPU0             
                                  CJ2      GND                     
                                  CJ4      DMI_CPU0_PCH_TX_DN<1>   
                                  CJ6      GND                     
                                  CJ8      GND                     
                                  CJ10     GND                     
                                  CJ12     GND                     
                                  CJ14     TP_CPU0_UPI2_RSVD_DK17  
                                  CJ16     GND                     
                                  CJ18     GND                     
                                  CJ20     PVCCMCP_CPU0            
                                  CJ22     PVCCMCP_CPU0            
                                  CJ24     PVCCMCP_CPU0            
                                  CJ26     PVCCMCP_CPU0            
                                  CJ28     PVCCIO_CPU0             
                                  CJ60     PVCCIN_CPU0             
                                  CJ62     GND                     
                                  CJ64     PVSA_CPU0               
                                  CJ66     PVSA_CPU0               
                                  CJ68     M_F_ECC<2>              
                                  CJ70     M_F_DQS_DN<17>          
                                  CJ72     M_F_ECC<4>              
                                  CJ74     GND                     
                                  CJ76     GND                     
                                  CJ78     GND                     
                                  CJ80     M_E_DQ<5>               
                                  CJ82     GND                     
                                  CJ84     GND                     
                                  CJ86     GND                     
                                  CK1      P3E_CPU0_PE2_SS_TXP<4>  
                                  CK3      P3E_CPU0_PE2_SS_TXP<5>  
                                  CK5      PVCCIO_CPU0             
                                  CK7      P3E_CPU0_PE2_SS_RXN<4>  
                                  CK9      DMI_CPU0_PCH_RX_C_DN<0> 
                                  CK11     GND                     
                                  CK13     TP_CPU0_UPI2_RSVD_DF17  
                                  CK15     GND                     
                                  CK17     GND                     
                                  CK19     TP_CPU0_RSVD_85         
                                  CK21     GND                     
                                  CK23     PVCCMCP_CPU0            
                                  CK25     PVCCMCP_CPU0            
                                  CK27     GND                     
                                  CK29     A_CPU0_UPI2_RBIAS       
                                  CK59     PVCCIN_CPU0             
                                  CK61     PVCCIN_CPU0             
                                  CK63     GND                     
                                  CK65     GND                     
                                  CK67     GND                     
                                  CK69     GND                     
                                  CK71     GND                     
                                  CK73     GND                     
                                  CK75     GND                     
                                  CK77     TP_CPU0_RSVD_82         
                                  CK79     M_E_DQ<4>               
                                  CK81     M_E_DQ<1>               
                                  CK83     GND                     
                                  CK85     GND                     
                                  CL2      P3E_CPU0_PE2_SS_TXN<5>  
                                  CL4      DMI_CPU0_PCH_TX_DP<1>   
                                  CL6      P3E_CPU0_PE2_SS_RXP<3>  
                                  CL8      GND                     
                                  CL10     DMI_CPU0_PCH_RX_C_DP<0> 
                                  CL12     PVCCIO_CPU0             
                                  CL14     GND                     
                                  CL16     GND                     
                                  CL18     GND                     
                                  CL20     PVCCIO_CPU0             
                                  CL22     GND                     
                                  CL24     PVCCMCP_CPU0            
                                  CL26     PVCCMCP_CPU0            
                                  CL28     A_CPU0_UPI2_RBIAS       
                                  CL30     A_CPU0_PE012_RBIAS      
                                  CL58     PVCCIN_CPU0             
                                  CL60     PVCCIN_CPU0             
                                  CL62     GND                     
                                  CL64     GND                     
                                  CL66     GND                     
                                  CL68     M_F_ECC<3>              
                                  CL70     M_F_DQS_DP<8>           
                                  CL72     M_F_ECC<5>              
                                  CL74     GND                     
                                  CL76     GND                     
                                  CL78     GND                     
                                  CL80     GND                     
                                  CL82     M_E_DQS_DN<0>           
                                  CL84     M_D_DQ<4>               
                                  CL86     M_D_DQ<5>               
                                  CM1      P3E_CPU0_PE2_SS_TXN<4>  
                                  CM3      DMI_CPU0_PCH_TX_DP<2>   
                                  CM5      GND                     
                                  CM7      P3E_CPU0_PE2_SS_RXN<3>  
                                  CM9      P3E_CPU0_PE2_SS_RXP<1>  
                                  CM11     DMI_CPU0_PCH_RX_C_DN<1> 
                                  CM13     TP_CPU0_UPI2_RSVD_DG18  
                                  CM15     PVCCIO_CPU0             
                                  CM19     GND                     
                                  CM21     GND                     
                                  CM23     PVCCMCP_CPU0            
                                  CM25     PVCCMCP_CPU0            
                                  CM27     GND                     
                                  CM29     GND                     
                                  CM31     GND                     
                                  CM57     PVCCIN_CPU0             
                                  CM59     PVCCIN_CPU0             
                                  CM61     GND                     
                                  CM63     GND                     
                                  CM65     M_F_DQS_DP<12>          
                                  CM67     GND                     
                                  CM69     M_F_ECC<7>              
                                  CM71     M_F_ECC<1>              
                                  CM73     GND                     
                                  CM75     M_F_DQ<5>               
                                  CM77     GND                     
                                  CM79     M_E_DQ<0>               
                                  CM81     M_E_DQS_DP<0>           
                                  CM83     GND                     
                                  CM85     GND                     
                                  CN2      GND                     
                                  CN4      DMI_CPU0_PCH_TX_DN<2>   
                                  CN6      PVCCIO_CPU0             
                                  CN8      P3E_CPU0_PE2_SS_RXP<2>  
                                  CN10     DMI_CPU0_PCH_RX_C_DP<1> 
                                  CN12     GND                     
                                  CN14     GND                     
                                  CN18     GND                     
                                  CN20     GND                     
                                  CN22     TP_CPU0_KTI2_AMONV      
                                  CN24     PVCCMCP_CPU0            
                                  CN26     GND                     
                                  CN28     PD_CPU0_MCP01_DMON      
                                  CN30     A_CPU0_PE012_RBIAS      
                                  CN32     GND                     
                                  CN56     PVCCIN_CPU0             
                                  CN58     PVCCIN_CPU0             
                                  CN60     GND                     
                                  CN62     GND                     
                                  CN64     M_F_DQ<30>              
                                  CN66     M_F_DQ<24>              
                                  CN68     GND                     
                                  CN70     M_F_DQS_DN<8>           
                                  CN74     M_F_DQ<4>               
                                  CN76     M_F_DQ<1>               
                                  CN78     GND                     
                                  CN80     M_E_DQS_DN<9>           
                                  CN82     M_E_DQ<7>               
                                  CN84     M_D_DQ<0>               
                                  CN86     M_D_DQ<1>               
                                  CP1      GND                     
                                  CP3      P3E_CPU0_PE2_SS_TXP<3>  
                                  CP5      DMI_CPU0_PCH_TX_DN<3>   
                                  CP7      P3E_CPU0_PE2_SS_RXN<2>  
                                  CP9      P3E_CPU0_PE2_SS_RXN<1>  
                                  CP11     DMI_CPU0_PCH_RX_C_DP<2> 
                                  CP13     PVCCIO_CPU0             
                                  CP19     GND                     
                                  CP21     GND                     
                                  CP23     PVCCMCP_CPU0            
                                  CP25     GND                     
                                  CP27     CLK_100M_CPU0_BCLK1_DP  
                                  CP29     A_CPU0_PE3_RBIAS        
                                  CP31     TP_CPU0_RSVD_73         
                                  CP33     PVCCIN_CPU0             
                                  CP55     PVCCIN_CPU0             
                                  CP57     PVCCIN_CPU0             
                                  CP59     GND                     
                                  CP61     M_D_CPU_VREF            
                                  CP63     M_F_DQ<26>              
                                  CP65     M_F_DQS_DN<12>          
                                  CP67     M_F_DQ<28>              
                                  CP69     GND                     
                                  CP73     GND                     
                                  CP75     GND                     
                                  CP77     M_F_DQS_DN<0>           
                                  CP79     M_E_DQS_DP<9>           
                                  CP81     GND                     
                                  CP83     GND                     
                                  CP85     M_D_DQS_DP<9>           
                                  CR2      P3E_CPU0_PE2_SS_TXP<2>  
                                  CR4      DMI_CPU0_PCH_TX_DP<3>   
                                  CR6      GND                     
                                  CR8      P3E_CPU0_PE2_SS_RXP<0>  
                                  CR10     GND                     
                                  CR12     DMI_CPU0_PCH_RX_C_DN<2> 
                                  CR14     TP_CPU0_UPI2_RSVD_DE16  
                                  CR18     GND                     
                                  CR20     GND                     
                                  CR22     GND                     
                                  CR24     GND                     
                                  CR26     CLK_100M_CPU0_BCLK1_DN  
                                  CR28     PWRGD_CPU0_DRAMPWROK_DEF_G
                                  CR30     A_CPU0_PE3_RBIAS        
                                  CR32     GND                     
                                  CR34     PVCCIN_CPU0             
                                  CR54     PVCCIN_CPU0             
                                  CR56     PVCCIN_CPU0             
                                  CR58     GND                     
                                  CR60     TP_CPU0_RSVD_72         
                                  CR62     GND                     
                                  CR64     GND                     
                                  CR66     GND                     
                                  CR68     GND                     
                                  CR74     M_F_DQ<0>               
                                  CR76     M_F_DQS_DP<0>           
                                  CR78     GND                     
                                  CR80     M_E_DQ<6>               
                                  CR82     M_E_DQ<3>               
                                  CR84     M_D_DQS_DN<9>           
                                  CR86     GND                     
                                  CT1      P3E_CPU0_PE2_SS_TXN<2>  
                                  CT3      P3E_CPU0_PE2_SS_TXN<3>  
                                  CT5      TP_CPU0_RSVD_70         
                                  CT7      GND                     
                                  CT9      P3E_CPU0_PE2_SS_RXN<0>  
                                  CT11     DMI_CPU0_PCH_RX_C_DN<3> 
                                  CT13     GND                     
                                  CT19     GND                     
                                  CT21     GND                     
                                  CT23     PVCCMCP_CPU0            
                                  CT25     CLK_100M_CPU0_BCLK2_DN  
                                  CT27     GND                     
                                  CT29     GND                     
                                  CT31     A_CPU0_MCP01_RBIAS      
                                  CT33     GND                     
                                  CT35     GND                     
                                  CT37     PVCCIN_CPU0             
                                  CT39     PVCCIN_CPU0             
                                  CT41     PVCCIN_CPU0             
                                  CT53     PVCCIN_CPU0             
                                  CT55     PVCCIN_CPU0             
                                  CT57     GND                     
                                  CT59     SMB_PIROM_CPU0_SCL      
                                  CT61     M_E_CPU_VREF            
                                  CT63     M_F_DQ<27>              
                                  CT65     M_F_DQS_DP<3>           
                                  CT67     M_F_DQ<29>              
                                  CT69     TP_CPU0_RSVD_69         
                                  CT73     GND                     
                                  CT75     M_F_DQS_DN<9>           
                                  CT77     M_F_DQ<7>               
                                  CT79     GND                     
                                  CT81     M_E_DQ<2>               
                                  CT83     GND                     
                                  CT85     GND                     
                                  CU2      P3E_CPU0_PE2_SS_TXP<1>  
                                  CU4      GND                     
                                  CU6      TP_CPU0_RSVD_67         
                                  CU8      P3E_CPU0_PE1_SS_RXP<0>  
                                  CU10     P3E_CPU0_PE3_OCP_RXP<15>
                                  CU12     PVCCIO_CPU0             
                                  CU14     TP_CPU0_UPI2_RSVD_DD17  
                                  CU18     PVCCIO_CPU0             
                                  CU20     GND                     
                                  CU22     GND                     
                                  CU24     PVCCMCP_CPU0            
                                  CU26     CLK_100M_CPU0_BCLK2_DP  
                                  CU28     GND                     
                                  CU30     GND                     
                                  CU32     A_CPU0_MCP01_RBIAS      
                                  CU34     GND                     
                                  CU36     GND                     
                                  CU38     PVCCIN_CPU0             
                                  CU40     PVCCIN_CPU0             
                                  CU42     PVCCIN_CPU0             
                                  CU52     PVCCIN_CPU0             
                                  CU54     PVCCIN_CPU0             
                                  CU56     GND                     
                                  CU58     PD_PIROM_CPU0_ADDR0     
                                  CU60     TP_CPU0_RSVD_66         
                                  CU62     GND                     
                                  CU64     M_F_DQ<31>              
                                  CU66     M_F_DQ<25>              
                                  CU68     GND                     
                                  CU74     M_F_DQS_DP<9>           
                                  CU76     GND                     
                                  CU78     GND                     
                                  CU80     GND                     
                                  CU82     GND                     
                                  CU84     M_D_DQS_DN<0>           
                                  CU86     GND                     
                                  CV1      GND                     
                                  CV3      P3E_CPU0_PE2_SS_TXN<1>  
                                  CV5      P3E_CPU0_PE3_OCP_TXP<15>
                                  CV7      PVCCIO_CPU0             
                                  CV9      P3E_CPU0_PE3_OCP_RXN<15>
                                  CV11     DMI_CPU0_PCH_RX_C_DP<3> 
                                  CV13     TP_CPU0_UPI2_RSVD_DD15  
                                  CV17     GND                     
                                  CV19     GND                     
                                  CV21     PVCCIO_CPU0             
                                  CV23     PVCCMCP_CPU0            
                                  CV25     GND                     
                                  CV27     GND                     
                                  CV29     M_F_DQS_DP<16>          
                                  CV31     GND                     
                                  CV33     GND                     
                                  CV35     M_F_DQS_DP<15>          
                                  CV37     GND                     
                                  CV39     GND                     
                                  CV41     GND                     
                                  CV51     PVCCIN_CPU0             
                                  CV53     GND                     
                                  CV55     GND                     
                                  CV57     PD_PIROM_CPU0_ADDR1     
                                  CV59     FM_CPU0_SM_WP           
                                  CV61     M_F_CPU_VREF            
                                  CV63     GND                     
                                  CV65     M_F_DQS_DN<3>           
                                  CV67     GND                     
                                  CV69     TP_CPU0_RSVD_64         
                                  CV73     GND                     
                                  CV75     M_F_DQ<6>               
                                  CV77     M_F_DQ<3>               
                                  CV79     GND                     
                                  CV81     GND                     
                                  CV83     GND                     
                                  CV85     M_D_DQS_DP<0>           
                                  CW2      P3E_CPU0_PE1_SS_TXP<0>  
                                  CW4      P3E_CPU0_PE2_SS_TXP<0>  
                                  CW6      GND                     
                                  CW8      P3E_CPU0_PE1_SS_RXN<0>  
                                  CW10     P3E_CPU0_PE3_OCP_RXP<14>
                                  CW12     GND                     
                                  CW14     TP_CPU0_UPI2_RSVD_DF15  
                                  CW16     TP_CPU0_UPI2_RSVD_DB15  
                                  CW18     GND                     
                                  CW20     GND                     
                                  CW22     TP_CPU0_KTI2_DFX_DN     
                                  CW24     PVCCMCP_CPU0            
                                  CW26     GND                     
                                  CW28     M_F_DQ<62>              
                                  CW30     M_F_DQ<56>              
                                  CW32     GND                     
                                  CW34     M_F_DQ<54>              
                                  CW36     M_F_DQ<48>              
                                  CW38     GND                     
                                  CW40     GND                     
                                  CW42     GND                     
                                  CW46     PVCCIN_CPU0             
                                  CW48     PVCCIN_CPU0             
                                  CW50     PVCCIN_CPU0             
                                  CW52     GND                     
                                  CW54     GND                     
                                  CW56     PD_PIROM_CPU0_ADDR2     
                                  CW58     SMB_PIROM_CPU0_SDA      
                                  CW60     TP_CPU0_RSVD_61         
                                  CW62     TP_CPU0_RSVD_60         
                                  CW64     GND                     
                                  CW66     GND                     
                                  CW68     GND                     
                                  CW72     FM_CPU0_PKGID1          
                                  CW74     GND                     
                                  CW76     M_F_DQ<2>               
                                  CW78     GND                     
                                  CW80     M_E_DQ<13>              
                                  CW82     GND                     
                                  CW84     M_D_DQ<7>               
                                  CW86     M_D_DQ<6>               
                                  CY1      GND                     
                                  CY3      P3E_CPU0_PE2_SS_TXN<0>  
                                  CY5      P3E_CPU0_PE3_OCP_TXN<15>
                                  CY7      P3E_CPU0_PE1_SS_RXP<1>  
                                  CY9      GND                     
                                  CY11     P3E_CPU0_PE3_OCP_RXN<14>
                                  CY13     GND                     
                                  CY15     GND                     
                                  CY17     PVCCIO_CPU0             
                                  CY19     GND                     
                                  CY21     GND                     
                                  CY23     TP_CPU0_RSVD_59         
                                  CY25     PVCCMCP_CPU0            
                                  CY27     M_F_DQ<58>              
                                  CY29     M_F_DQS_DN<16>          
                                  CY31     M_F_DQ<60>              
                                  CY33     M_F_DQ<50>              
                                  CY35     M_F_DQS_DN<15>          
                                  CY37     M_F_DQ<52>              
                                  CY39     TP_CPU0_RSVD_57         
                                  CY41     GND                     
                                  CY45     GND                     
                                  CY47     PVCCIN_CPU0             
                                  CY49     PVCCIN_CPU0             
                                  CY51     GND                     
                                  CY53     TP_CPU0_RSVD_56         
                                  CY55     P3V3_STBY               
                                  CY57     TP_CPU0_RSVD_55         
                                  CY59     GND                     
                                  CY61     GND                     
                                  CY63     TP_CPU0_RSVD_54         
                                  CY65     GND                     
                                  CY67     M_D_DQS_DP<17>          
                                  CY69     GND                     
                                  CY71     FM_CPU0_PROC_ID0        
                                  CY73     TP_CPU0_RSVD_53         
                                  CY75     GND                     
                                  CY77     GND                     
                                  CY79     M_E_DQ<12>              
                                  CY81     M_E_DQ<9>               
                                  CY83     GND                     
                                  CY85     GND                     
                                  D3       GND                     
                                  D5       TP_CPU0_RSVD_287        
                                  D7       PVCCIO_CPU0             
                                  D9       UPI_CPU0_CPU1_P1P1_DN<12>
                                  D11      GND                     
                                  D13      GND                     
                                  D15      UPI_CPU0_CPU1_P1P1_DN<7>
                                  D17      TP_CPU0_RSVD_286        
                                  D25      GND                     
                                  D27      GND                     
                                  D29      GND                     
                                  D31      GND                     
                                  D33      GND                     
                                  D35      GND                     
                                  D37      GND                     
                                  D39      GND                     
                                  D41      GND                     
                                  D43      GND                     
                                  D45      PVDDQ_ABC               
                                  D47      M_A_CS_N<2>             
                                  D49      M_A_CS_N<5>             
                                  D51      M_A_MA<16>              
                                  D53      M_A_PAR                 
                                  D55      M_A_CLK_DP<0>           
                                  D57      M_A_MA<2>               
                                  D59      M_A_MA<6>               
                                  D61      M_A_BG<0>               
                                  D63      M_A_CKE<3>              
                                  D65      TP_CPU0_RSVD_285        
                                  D71      M_B_DQ<26>              
                                  D73      M_B_DQS_DP<12>          
                                  D75      M_B_DQ<24>              
                                  D77      GND                     
                                  D79      M_B_DQS_DN<11>          
                                  D81      GND                     
                                  D83      TP_CPU0_RSVD_284        
                                  DA2      P3E_CPU0_PE1_SS_TXN<0>  
                                  DA4      P3E_CPU0_PE3_OCP_TXP<14>
                                  DA6      GND                     
                                  DA8      P3E_CPU0_PE1_SS_RXN<1>  
                                  DA10     P3E_CPU0_PE1_SS_RXP<3>  
                                  DA12     P3E_CPU0_PE3_OCP_RXP<13>
                                  DA14     PVCCIO_CPU0             
                                  DA16     TP_CPU0_UPI2_RSVD_DC16  
                                  DA18     GND                     
                                  DA20     GND                     
                                  DA22     GND                     
                                  DA24     PVCCMCP_CPU0            
                                  DA26     GND                     
                                  DA28     GND                     
                                  DA30     GND                     
                                  DA32     GND                     
                                  DA34     GND                     
                                  DA36     GND                     
                                  DA38     GND                     
                                  DA40     TP_CPU0_RSVD_51         
                                  DA42     M_F_DQ<36>              
                                  DA44     GND                     
                                  DA46     GND                     
                                  DA48     GND                     
                                  DA50     GND                     
                                  DA52     TP_CPU0_RSVD_50         
                                  DA54     TP_CPU0_RSVD_49         
                                  DA56     TP_CPU0_RSVD_48         
                                  DA58     M_F_MA<9>               
                                  DA60     M_F_MA<11>              
                                  DA62     M_F_BG<0>               
                                  DA64     GND                     
                                  DA66     M_D_ECC<6>              
                                  DA68     M_D_ECC<0>              
                                  DA70     GND                     
                                  DA72     FM_CPU0_PKGID2          
                                  DA74     GND                     
                                  DA76     GND                     
                                  DA78     GND                     
                                  DA80     GND                     
                                  DA82     M_E_DQS_DN<1>           
                                  DA84     M_D_DQ<3>               
                                  DA86     M_D_DQ<2>               
                                  DB1      P3E_CPU0_PE1_SS_TXP<1>  
                                  DB3      GND                     
                                  DB5      P3E_CPU0_PE3_OCP_TXN<14>
                                  DB7      GND                     
                                  DB9      P3E_CPU0_PE1_SS_RXP<2>  
                                  DB11     P3E_CPU0_PE3_OCP_RXN<13>
                                  DB13     GND                     
                                  DB15     TP_CPU0_UPI2_RSVD_CW16  
                                  DB17     GND                     
                                  DB19     GND                     
                                  DB21     GND                     
                                  DB23     GND                     
                                  DB25     GND                     
                                  DB27     M_F_DQ<59>              
                                  DB29     M_F_DQS_DP<7>           
                                  DB31     M_F_DQ<61>              
                                  DB33     M_F_DQ<51>              
                                  DB35     M_F_DQS_DP<6>           
                                  DB37     M_F_DQ<53>              
                                  DB39     GND                     
                                  DB41     GND                     
                                  DB45     SVID_DIO0_CPU0          
                                  DB47     GND                     
                                  DB49     GND                     
                                  DB51     PD_CPU0_TEST13          
                                  DB53     PVDDQ_DEF               
                                  DB55     PVDDQ_DEF               
                                  DB57     PVDDQ_DEF               
                                  DB59     PVDDQ_DEF               
                                  DB61     PVDDQ_DEF               
                                  DB63     PVDDQ_DEF               
                                  DB65     M_D_ECC<2>              
                                  DB67     M_D_DQS_DN<17>          
                                  DB69     M_D_ECC<4>              
                                  DB71     FM_CPU0_PROC_ID1        
                                  DB73     GND                     
                                  DB75     M_F_DQ<13>              
                                  DB77     GND                     
                                  DB79     M_E_DQ<8>               
                                  DB81     M_E_DQS_DP<1>           
                                  DB83     GND                     
                                  DB85     GND                     
                                  DC2      P3E_CPU0_PE1_SS_TXN<1>  
                                  DC4      P3E_CPU0_PE1_SS_TXP<3>  
                                  DC6      P3E_CPU0_PE3_OCP_TXP<13>
                                  DC8      P3E_CPU0_PE1_SS_RXN<2>  
                                  DC10     P3E_CPU0_PE1_SS_RXN<3>  
                                  DC12     P3E_CPU0_PE3_OCP_RXP<12>
                                  DC14     GND                     
                                  DC16     TP_CPU0_UPI2_RSVD_DA16  
                                  DC18     PVCCIO_CPU0             
                                  DC20     GND                     
                                  DC22     GND                     
                                  DC24     GND                     
                                  DC26     GND                     
                                  DC28     M_F_DQ<63>              
                                  DC30     M_F_DQ<57>              
                                  DC32     GND                     
                                  DC34     M_F_DQ<55>              
                                  DC36     M_F_DQ<49>              
                                  DC38     GND                     
                                  DC40     M_F_DQS_DP<13>          
                                  DC42     GND                     
                                  DC44     SVID_CLK0_CPU0          
                                  DC46     TP_CPU0_RSVD_47         
                                  DC48     A_CPU0_DEF_RCOMP0       
                                  DC50     PD_CPU0_TEST14          
                                  DC52     TP_CPU0_RSVD_46         
                                  DC54     M_F_MA<15>              
                                  DC56     M_F_BA<1>               
                                  DC58     M_F_MA<1>               
                                  DC60     M_F_MA<7>               
                                  DC62     M_F_ACT_N               
                                  DC64     GND                     
                                  DC66     GND                     
                                  DC68     GND                     
                                  DC70     GND                     
                                  DC72     FM_CPU0_PKGID0          
                                  DC74     M_F_DQ<12>              
                                  DC76     M_F_DQ<9>               
                                  DC78     GND                     
                                  DC80     M_E_DQS_DN<10>          
                                  DC82     M_E_DQ<14>              
                                  DC84     GND                     
                                  DC86     GND                     
                                  DD3      P3E_CPU0_PE1_SS_TXP<2>  
                                  DD5      P3E_CPU0_PE3_OCP_TXN<13>
                                  DD7      PVCCIO_CPU0             
                                  DD9      P3E_CPU0_PE1_SS_RXP<4>  
                                  DD11     GND                     
                                  DD13     P3E_CPU0_PE3_OCP_RXN<12>
                                  DD15     TP_CPU0_UPI2_RSVD_CV13  
                                  DD17     TP_CPU0_UPI2_RSVD_CU14  
                                  DD19     GND                     
                                  DD21     GND                     
                                  DD23     GND                     
                                  DD25     M_E_DQ<58>              
                                  DD27     GND                     
                                  DD29     M_F_DQS_DN<7>           
                                  DD31     GND                     
                                  DD33     GND                     
                                  DD35     M_F_DQS_DN<6>           
                                  DD37     GND                     
                                  DD39     M_F_DQ<38>              
                                  DD41     M_F_DQ<32>              
                                  DD45     PVDDQ_DEF               
                                  DD47     A_CPU0_DEF_RCOMP1       
                                  DD49     A_CPU0_DEF_RCOMP2       
                                  DD51     TP_CPU0_RSVD_45         
                                  DD53     M_F_MA<13>              
                                  DD55     M_F_MA<10>              
                                  DD57     M_F_MA<2>               
                                  DD59     M_F_MA<8>               
                                  DD61     M_F_ALERT_N             
                                  DD63     M_F_CKE<1>              
                                  DD65     M_D_ECC<3>              
                                  DD67     M_D_DQS_DP<8>           
                                  DD69     M_D_ECC<5>              
                                  DD71     GND                     
                                  DD73     GND                     
                                  DD75     GND                     
                                  DD77     M_F_DQS_DN<1>           
                                  DD79     M_E_DQS_DP<10>          
                                  DD81     GND                     
                                  DD83     GND                     
                                  DD85     M_D_DQ<12>              
                                  DE2      P3E_CPU0_PE1_SS_TXN<2>  
                                  DE4      P3E_CPU0_PE1_SS_TXN<3>  
                                  DE6      GND                     
                                  DE8      GND                     
                                  DE10     P3E_CPU0_PE1_SS_RXN<4>  
                                  DE12     P3E_CPU0_PE3_OCP_RXP<10>
                                  DE14     PVCCIO_CPU0             
                                  DE16     TP_CPU0_UPI2_RSVD_CR14  
                                  DE18     GND                     
                                  DE20     GND                     
                                  DE22     GND                     
                                  DE24     GND                     
                                  DE26     M_E_DQS_DP<16>          
                                  DE28     GND                     
                                  DE30     GND                     
                                  DE32     M_F_DQS_DP<14>          
                                  DE34     GND                     
                                  DE36     GND                     
                                  DE38     M_F_DQ<34>              
                                  DE40     M_F_DQS_DN<13>          
                                  DE42     M_F_DQ<37>              
                                  DE44     SVID_ALERT0_CPU0_N      
                                  DE46     M_F_MA<17>              
                                  DE48     GND                     
                                  DE50     GND                     
                                  DE52     GND                     
                                  DE54     GND                     
                                  DE56     GND                     
                                  DE58     GND                     
                                  DE60     GND                     
                                  DE62     GND                     
                                  DE64     GND                     
                                  DE66     M_D_ECC<7>              
                                  DE68     M_D_ECC<1>              
                                  DE70     GND                     
                                  DE72     GND                     
                                  DE74     M_F_DQ<8>               
                                  DE76     M_F_DQS_DP<1>           
                                  DE78     GND                     
                                  DE80     M_E_DQ<10>              
                                  DE82     M_E_DQ<15>              
                                  DE84     M_D_DQ<13>              
                                  DF3      P3E_CPU0_PE1_SS_TXP<4>  
                                  DF5      GND                     
                                  DF7      GND                     
                                  DF9      P3E_CPU0_PE1_SS_RXP<5>  
                                  DF11     P3E_CPU0_PE3_OCP_RXP<11>
                                  DF13     PVCCIO_CPU0             
                                  DF15     TP_CPU0_UPI2_RSVD_CW14  
                                  DF17     TP_CPU0_UPI2_RSVD_CK13  
                                  DF19     GND                     
                                  DF21     PVCCIO_CPU0             
                                  DF23     GND                     
                                  DF25     M_E_DQ<62>              
                                  DF27     M_E_DQ<56>              
                                  DF29     GND                     
                                  DF31     M_F_DQ<46>              
                                  DF33     M_F_DQ<40>              
                                  DF35     GND                     
                                  DF37     GND                     
                                  DF39     GND                     
                                  DF41     GND                     
                                  DF45     M_F_C<2>                
                                  DF47     M_F_ODT<3>              
                                  DF49     M_F_CS_N<1>             
                                  DF51     M_F_CS_N<4>             
                                  DF53     M_F_MA<0>               
                                  DF55     M_F_CLK_DN<1>           
                                  DF57     M_F_CLK_DN<3>           
                                  DF59     M_F_MA<5>               
                                  DF61     M_F_BG<1>               
                                  DF63     M_F_CKE<3>              
                                  DF65     GND                     
                                  DF67     M_D_DQS_DN<8>           
                                  DF69     GND                     
                                  DF71     M_F_DQ<20>              
                                  DF73     GND                     
                                  DF75     M_F_DQS_DN<10>          
                                  DF77     M_F_DQ<14>              
                                  DF79     GND                     
                                  DF81     M_E_DQ<11>              
                                  DF83     GND                     
                                  DF85     GND                     
                                  DG2      GND                     
                                  DG4      P3E_CPU0_PE1_SS_TXN<4>  
                                  DG6      P3E_CPU0_PE3_OCP_TXP<12>
                                  DG8      PVCCIO_CPU0             
                                  DG10     P3E_CPU0_PE3_OCP_RXN<11>
                                  DG12     P3E_CPU0_PE3_OCP_RXN<10>
                                  DG14     GND                     
                                  DG16     GND                     
                                  DG18     TP_CPU0_UPI2_RSVD_CM13  
                                  DG20     TP_CPU0_UPI2_RSVD_CH11  
                                  DG22     GND                     
                                  DG24     GND                     
                                  DG26     M_E_DQS_DN<16>          
                                  DG28     M_E_DQ<60>              
                                  DG30     M_F_DQ<42>              
                                  DG32     M_F_DQS_DN<14>          
                                  DG34     M_F_DQ<44>              
                                  DG36     TP_CPU0_RSVD_44         
                                  DG38     M_F_DQ<35>              
                                  DG40     M_F_DQS_DN<4>           
                                  DG42     M_F_DQ<33>              
                                  DG44     SVID_CLK1_CPU0          
                                  DG46     M_F_CS_N<3>             
                                  DG48     M_F_ODT<1>              
                                  DG50     M_F_ODT<0>              
                                  DG52     M_F_MA<16>              
                                  DG54     M_F_CLK_DP<1>           
                                  DG56     M_F_CLK_DP<3>           
                                  DG58     M_F_MA<3>               
                                  DG60     M_F_MA<12>              
                                  DG62     M_F_CKE<0>              
                                  DG64     TP_CPU0_RSVD_43         
                                  DG66     GND                     
                                  DG68     GND                     
                                  DG70     M_F_DQ<16>              
                                  DG72     M_F_DQ<21>              
                                  DG74     M_F_DQS_DP<10>          
                                  DG76     GND                     
                                  DG78     GND                     
                                  DG80     GND                     
                                  DG82     GND                     
                                  DG84     M_D_DQ<8>               
                                  DH3      P3E_CPU0_PE1_SS_TXP<5>  
                                  DH5      P3E_CPU0_PE3_OCP_TXP<11>
                                  DH7      PVCCIO_CPU0             
                                  DH9      P3E_CPU0_PE1_SS_RXN<5>  
                                  DH11     P3E_CPU0_PE3_OCP_RXP<9> 
                                  DH13     GND                     
                                  DH15     GND                     
                                  DH17     TP_CPU0_UPI2_RSVD_CH13  
                                  DH19     TP_CPU0_UPI2_RSVD_CF13  
                                  DH21     GND                     
                                  DH23     GND                     
                                  DH25     GND                     
                                  DH27     GND                     
                                  DH29     GND                     
                                  DH31     GND                     
                                  DH33     GND                     
                                  DH35     GND                     
                                  DH37     GND                     
                                  DH39     M_F_DQ<39>              
                                  DH41     GND                     
                                  DH45     PVDDQ_DEF               
                                  DH47     PVDDQ_DEF               
                                  DH49     PVDDQ_DEF               
                                  DH51     PVDDQ_DEF               
                                  DH53     PVDDQ_DEF               
                                  DH55     PVDDQ_DEF               
                                  DH57     PVDDQ_DEF               
                                  DH59     PVDDQ_DEF               
                                  DH61     PVDDQ_DEF               
                                  DH63     PVDDQ_DEF               
                                  DH65     TP_CPU0_RSVD_42         
                                  DH67     GND                     
                                  DH69     M_F_DQS_DP<11>          
                                  DH71     GND                     
                                  DH73     GND                     
                                  DH75     M_F_DQ<10>              
                                  DH77     M_F_DQ<15>              
                                  DH79     GND                     
                                  DH81     GND                     
                                  DH83     GND                     
                                  DH85     M_D_DQ<9>               
                                  DJ2      GND                     
                                  DJ4      P3E_CPU0_PE3_OCP_TXN<11>
                                  DJ6      P3E_CPU0_PE3_OCP_TXN<12>
                                  DJ8      P3E_CPU0_PE1_SS_RXP<6>  
                                  DJ10     GND                     
                                  DJ12     P3E_CPU0_PE3_OCP_RXN<9> 
                                  DJ14     P3E_CPU0_PE3_OCP_RXP<7> 
                                  DJ16     PVCCIO_CPU0             
                                  DJ18     TP_CPU0_UPI2_RSVD_CG12  
                                  DJ20     TP_CPU0_UPI2_RSVD_CF11  
                                  DJ22     GND                     
                                  DJ24     M_E_DQ<59>              
                                  DJ26     M_E_DQS_DP<7>           
                                  DJ28     M_E_DQ<61>              
                                  DJ30     M_F_DQ<43>              
                                  DJ32     M_F_DQS_DP<5>           
                                  DJ34     M_F_DQ<45>              
                                  DJ36     TP_CPU0_RSVD_41         
                                  DJ38     GND                     
                                  DJ40     M_F_DQS_DP<4>           
                                  DJ42     GND                     
                                  DJ44     SVID_DIO1_CPU0          
                                  DJ46     M_F_CS_N<2>             
                                  DJ48     M_F_CS_N<5>             
                                  DJ50     M_F_MA<14>              
                                  DJ52     M_F_BA<0>               
                                  DJ54     M_F_CLK_DP<0>           
                                  DJ56     M_F_CLK_DP<2>           
                                  DJ58     M_F_MA<4>               
                                  DJ60     M_E_MA<8>               
                                  DJ62     M_E_BG<0>               
                                  DJ64     PVDDQ_DEF               
                                  DJ66     TP_CPU0_RSVD_40         
                                  DJ68     GND                     
                                  DJ70     M_F_DQS_DN<11>          
                                  DJ72     M_F_DQ<17>              
                                  DJ74     GND                     
                                  DJ76     M_F_DQ<11>              
                                  DJ78     GND                     
                                  DJ80     M_D_DQ<21>              
                                  DJ82     GND                     
                                  DJ84     GND                     
                                  DK3      P3E_CPU0_PE1_SS_TXN<5>  
                                  DK5      P3E_CPU0_PE3_OCP_TXP<10>
                                  DK7      GND                     
                                  DK9      P3E_CPU0_PE1_SS_RXN<6>  
                                  DK11     P3E_CPU0_PE1_PCH_RXP<8> 
                                  DK13     P3E_CPU0_PE3_OCP_RXP<8> 
                                  DK15     TP_CPU0_RSVD_39         
                                  DK17     TP_CPU0_UPI2_RSVD_CJ14  
                                  DK19     TP_CPU0_UPI2_RSVD_CD11  
                                  DK21     PVCCIO_CPU0             
                                  DK23     GND                     
                                  DK25     M_E_DQ<63>              
                                  DK27     M_E_DQ<57>              
                                  DK29     GND                     
                                  DK31     M_F_DQ<47>              
                                  DK33     M_F_DQ<41>              
                                  DK35     GND                     
                                  DK37     TP_CPU0_RSVD_38         
                                  DK39     GND                     
                                  DK41     GND                     
                                  DK45     M_F_CS_N<7>             
                                  DK47     M_E_CS_N<3>             
                                  DK49     M_F_ODT<2>              
                                  DK51     M_F_CS_N<0>             
                                  DK53     M_F_PAR                 
                                  DK55     M_F_CLK_DN<0>           
                                  DK57     M_F_CLK_DN<2>           
                                  DK59     M_F_MA<6>               
                                  DK61     M_E_MA<7>               
                                  DK63     M_F_CKE<2>              
                                  DK65     TP_CPU0_RSVD_37         
                                  DK67     TP_CPU0_RSVD_36         
                                  DK69     M_F_DQ<22>              
                                  DK71     M_F_DQS_DP<2>           
                                  DK73     GND                     
                                  DK75     GND                     
                                  DK77     GND                     
                                  DK79     M_D_DQ<20>              
                                  DK81     M_D_DQ<17>              
                                  DK83     GND                     
                                  DK85     GND                     
                                  DL2      P3E_CPU0_PE1_SS_TXP<6>  
                                  DL4      GND                     
                                  DL6      P3E_CPU0_PE3_OCP_TXN<10>
                                  DL8      GND                     
                                  DL10     P3E_CPU0_PE1_SS_RXP<7>  
                                  DL12     P3E_CPU0_PE3_OCP_RXN<8> 
                                  DL14     P3E_CPU0_PE3_OCP_RXN<7> 
                                  DL16     GND                     
                                  DL18     GND                     
                                  DL20     TP_CPU0_UPI2_RSVD_CE12  
                                  DL22     GND                     
                                  DL24     GND                     
                                  DL26     M_E_DQS_DN<7>           
                                  DL28     GND                     
                                  DL30     GND                     
                                  DL32     M_F_DQS_DN<5>           
                                  DL34     GND                     
                                  DL36     GND                     
                                  DL38     TP_CPU0_RSVD_35         
                                  DL40     GND                     
                                  DL42     M_E_DQ<36>              
                                  DL44     SVID_ALERT1_CPU0_N      
                                  DL46     PVDDQ_DEF               
                                  DL48     PVDDQ_DEF               
                                  DL50     PVDDQ_DEF               
                                  DL52     PVDDQ_DEF               
                                  DL54     PVDDQ_DEF               
                                  DL56     PVDDQ_DEF               
                                  DL58     PVDDQ_DEF               
                                  DL60     PVDDQ_DEF               
                                  DL62     PVDDQ_DEF               
                                  DL64     M_E_CKE<2>              
                                  DL66     TP_CPU0_RSVD_34         
                                  DL68     GND                     
                                  DL70     GND                     
                                  DL72     M_F_DQS_DN<2>           
                                  DL74     GND                     
                                  DL76     GND                     
                                  DL78     GND                     
                                  DL80     GND                     
                                  DL82     M_D_DQS_DN<2>           
                                  DL84     M_D_DQS_DP<10>          
                                  DM3      P3E_CPU0_PE1_SS_TXN<6>  
                                  DM5      P3E_CPU0_PE3_OCP_TXP<9> 
                                  DM7      P3E_CPU0_PE3_OCP_TXN<8> 
                                  DM9      P3E_CPU0_PE1_SS_RXN<7>  
                                  DM11     P3E_CPU0_PE1_PCH_RXN<8> 
                                  DM13     P3E_CPU0_PE3_OCP_RXP<6> 
                                  DM15     GND                     
                                  DM17     PVCCIO_CPU0             
                                  DM19     GND                     
                                  DM21     TP_CPU0_UPI2_RSVD_CC10  
                                  DM23     M_D_DQS_DN<16>          
                                  DM25     GND                     
                                  DM27     GND                     
                                  DM29     M_D_DQS_DN<15>          
                                  DM31     GND                     
                                  DM33     GND                     
                                  DM35     M_D_DQS_DP<14>          
                                  DM37     GND                     
                                  DM39     GND                     
                                  DM41     M_E_DQS_DP<13>          
                                  DM45     M_F_CS_N<6>             
                                  DM47     M_E_ODT<3>              
                                  DM49     M_E_CS_N<5>             
                                  DM51     M_E_MA<14>              
                                  DM53     M_E_BA<0>               
                                  DM55     M_E_CLK_DN<0>           
                                  DM57     M_E_CLK_DN<2>           
                                  DM59     M_E_MA<6>               
                                  DM61     M_E_BG<1>               
                                  DM63     M_E_CKE<0>              
                                  DM65     GND                     
                                  DM67     TP_CPU0_RSVD_33         
                                  DM69     M_F_DQ<18>              
                                  DM71     M_F_DQ<23>              
                                  DM73     GND                     
                                  DM75     M_D_DQS_DP<12>          
                                  DM77     GND                     
                                  DM79     M_D_DQ<16>              
                                  DM81     M_D_DQS_DP<2>           
                                  DM83     GND                     
                                  DM85     M_D_DQS_DN<10>          
                                  DN2      GND                     
                                  DN4      P3E_CPU0_PE1_SS_TXN<7>  
                                  DN6      P3E_CPU0_PE3_OCP_TXP<8> 
                                  DN8      PVCCIO_CPU0             
                                  DN10     P3E_CPU0_PE1_PCH_RXP<9> 
                                  DN12     GND                     
                                  DN14     P3E_CPU0_PE3_OCP_RXN<6> 
                                  DN16     P3E_CPU0_PE3_OCP_RXP<4> 
                                  DN18     GND                     
                                  DN20     TP_CPU0_UPI2_RSVD_CB11  
                                  DN22     GND                     
                                  DN24     M_D_DQ<56>              
                                  DN26     GND                     
                                  DN28     M_D_DQ<54>              
                                  DN30     M_D_DQ<48>              
                                  DN32     GND                     
                                  DN34     M_D_DQ<46>              
                                  DN36     M_D_DQ<40>              
                                  DN38     GND                     
                                  DN40     M_E_DQ<38>              
                                  DN42     M_E_DQ<37>              
                                  DN44     GND                     
                                  DN46     M_E_CS_N<7>             
                                  DN48     M_E_ODT<1>              
                                  DN50     M_E_CS_N<1>             
                                  DN52     M_E_MA<16>              
                                  DN54     M_E_CLK_DP<0>           
                                  DN56     M_E_CLK_DP<2>           
                                  DN58     M_E_MA<5>               
                                  DN60     M_E_MA<12>              
                                  DN62     TP_CPU0_RSVD_32         
                                  DN64     M_E_CKE<1>              
                                  DN66     TP_CPU0_RSVD_31         
                                  DN68     GND                     
                                  DN70     M_F_DQ<19>              
                                  DN72     GND                     
                                  DN74     M_D_DQ<30>              
                                  DN76     M_D_DQ<24>              
                                  DN78     GND                     
                                  DN80     M_D_DQS_DN<11>          
                                  DN82     M_D_DQ<23>              
                                  DN84     M_D_DQS_DN<1>           
                                  DP3      P3E_CPU0_PE1_SS_TXP<7>  
                                  DP5      P3E_CPU0_PE3_OCP_TXN<9> 
                                  DP7      P3E_CPU0_PE3_OCP_TXP<7> 
                                  DP9      GND                     
                                  DP11     P3E_CPU0_PE1_PCH_RXN<9> 
                                  DP13     P3E_CPU0_PE1_PCH_RXP<11>
                                  DP15     P3E_CPU0_PE3_OCP_RXP<5> 
                                  DP17     TP_CPU0_RSVD_30         
                                  DP19     PVCCIO_CPU0             
                                  DP21     TP_CPU0_UPI2_RSVD_CA12  
                                  DP23     M_D_DQS_DP<16>          
                                  DP25     M_D_DQ<60>              
                                  DP27     M_D_DQ<50>              
                                  DP29     M_D_DQS_DP<15>          
                                  DP31     M_D_DQ<52>              
                                  DP33     M_D_DQ<42>              
                                  DP35     M_D_DQS_DN<14>          
                                  DP37     M_D_DQ<44>              
                                  DP39     M_E_DQ<34>              
                                  DP41     M_E_DQS_DN<13>          
                                  DP45     GND                     
                                  DP47     GND                     
                                  DP49     GND                     
                                  DP51     GND                     
                                  DP53     GND                     
                                  DP55     GND                     
                                  DP57     GND                     
                                  DP59     GND                     
                                  DP61     GND                     
                                  DP63     GND                     
                                  DP65     TP_CPU0_RSVD_29         
                                  DP67     GND                     
                                  DP69     GND                     
                                  DP71     GND                     
                                  DP73     M_D_DQ<26>              
                                  DP75     M_D_DQS_DN<12>          
                                  DP77     M_D_DQ<28>              
                                  DP79     M_D_DQS_DP<11>          
                                  DP81     GND                     
                                  DP83     GND                     
                                  DP85     M_D_DQS_DP<1>           
                                  DR2      PVCCIO_CPU0             
                                  DR4      P3E_CPU0_PE1_PCH_TXP<8> 
                                  DR6      GND                     
                                  DR8      P3E_CPU0_PE3_OCP_TXN<7> 
                                  DR10     PVCCIO_CPU0             
                                  DR12     P3E_CPU0_PE1_PCH_RXP<10>
                                  DR14     P3E_CPU0_PE3_OCP_RXN<5> 
                                  DR16     P3E_CPU0_PE3_OCP_RXN<4> 
                                  DR18     P3E_CPU0_PE3_OCP_RXP<3> 
                                  DR20     GND                     
                                  DR22     GND                     
                                  DR24     GND                     
                                  DR26     GND                     
                                  DR28     GND                     
                                  DR30     GND                     
                                  DR32     GND                     
                                  DR34     GND                     
                                  DR36     GND                     
                                  DR38     GND                     
                                  DR40     GND                     
                                  DR42     GND                     
                                  DR44     TP_CPU0_RSVD_28         
                                  DR46     M_E_CS_N<2>             
                                  DR48     M_E_MA<17>              
                                  DR50     M_E_ODT<0>              
                                  DR52     M_E_MA<15>              
                                  DR54     M_E_CLK_DN<1>           
                                  DR56     M_E_CLK_DP<3>           
                                  DR58     M_E_MA<3>               
                                  DR60     M_E_MA<11>              
                                  DR62     M_E_ACT_N               
                                  DR64     M_E_CKE<3>              
                                  DR66     GND                     
                                  DR68     GND                     
                                  DR70     GND                     
                                  DR72     GND                     
                                  DR74     GND                     
                                  DR76     GND                     
                                  DR78     GND                     
                                  DR80     M_D_DQ<22>              
                                  DR82     M_D_DQ<19>              
                                  DR84     M_D_DQ<14>              
                                  DT3      GND                     
                                  DT5      P3E_CPU0_PE1_PCH_TXN<8> 
                                  DT7      P3E_CPU0_PE1_PCH_TXP<12>
                                  DT9      P3E_CPU0_PE3_OCP_TXP<6> 
                                  DT11     P3E_CPU0_PE1_PCH_RXN<10>
                                  DT13     P3E_CPU0_PE1_PCH_RXN<11>
                                  DT15     P3E_CPU0_PE1_PCH_RXP<15>
                                  DT17     GND                     
                                  DT19     P3E_CPU0_PE3_OCP_RXN<3> 
                                  DT21     TP_CPU0_UPI2_RSVD_CC12  
                                  DT23     M_D_DQS_DP<7>           
                                  DT25     M_D_DQ<61>              
                                  DT27     M_D_DQ<51>              
                                  DT29     M_D_DQS_DP<6>           
                                  DT31     M_D_DQ<53>              
                                  DT33     M_D_DQ<43>              
                                  DT35     M_D_DQS_DP<5>           
                                  DT37     M_D_DQ<45>              
                                  DT39     M_E_DQ<35>              
                                  DT41     M_E_DQS_DP<4>           
                                  DT45     M_E_CS_N<6>             
                                  DT47     M_E_C<2>                
                                  DT49     M_E_ODT<2>              
                                  DT51     M_E_MA<13>              
                                  DT53     M_E_CLK_DP<1>           
                                  DT55     M_E_MA<10>              
                                  DT57     M_E_CLK_DN<3>           
                                  DT59     M_E_MA<4>               
                                  DT61     M_E_ALERT_N             
                                  DT63     M_D_MA<12>              
                                  DT65     GND                     
                                  DT67     M_E_DQS_DP<17>          
                                  DT69     GND                     
                                  DT71     TP_CPU0_RSVD_27         
                                  DT73     M_D_DQ<27>              
                                  DT75     M_D_DQS_DP<3>           
                                  DT77     M_D_DQ<29>              
                                  DT79     GND                     
                                  DT81     M_D_DQ<18>              
                                  DT83     GND                     
                                  DT85     GND                     
                                  DU2      P3E_CPU0_PE1_PCH_TXP<9> 
                                  DU4      P3E_CPU0_PE1_PCH_TXP<10>
                                  DU6      P3E_CPU0_PE1_PCH_TXN<11>
                                  DU8      P3E_CPU0_PE3_OCP_TXN<6> 
                                  DU10     GND                     
                                  DU12     P3E_CPU0_PE1_PCH_RXP<12>
                                  DU14     GND                     
                                  DU16     P3E_CPU0_PE1_PCH_RXN<15>
                                  DU18     P3E_CPU0_PE3_OCP_RXP<1> 
                                  DU20     PVCCIO_CPU0             
                                  DU22     GND                     
                                  DU24     M_D_DQ<57>              
                                  DU26     GND                     
                                  DU28     M_D_DQ<55>              
                                  DU30     M_D_DQ<49>              
                                  DU32     GND                     
                                  DU34     M_D_DQ<47>              
                                  DU36     M_D_DQ<41>              
                                  DU38     GND                     
                                  DU40     M_E_DQ<39>              
                                  DU42     M_E_DQ<32>              
                                  DU44     TP_CPU0_RSVD_26         
                                  DU46     PVDDQ_DEF               
                                  DU48     PVDDQ_DEF               
                                  DU50     PVDDQ_DEF               
                                  DU52     PVDDQ_DEF               
                                  DU54     PVDDQ_DEF               
                                  DU56     PVDDQ_DEF               
                                  DU58     PVDDQ_DEF               
                                  DU60     PVDDQ_DEF               
                                  DU62     PVDDQ_DEF               
                                  DU64     PVDDQ_DEF               
                                  DU66     M_E_ECC<6>              
                                  DU68     M_E_ECC<4>              
                                  DU70     GND                     
                                  DU72     GND                     
                                  DU74     M_D_DQ<31>              
                                  DU76     M_D_DQ<25>              
                                  DU78     GND                     
                                  DU80     GND                     
                                  DU82     GND                     
                                  DU84     GND                     
                                  DV3      P3E_CPU0_PE1_PCH_TXN<9> 
                                  DV5      P3E_CPU0_PE1_PCH_TXP<11>
                                  DV7      P3E_CPU0_PE1_PCH_TXN<12>
                                  DV9      P3E_CPU0_PE3_OCP_TXP<5> 
                                  DV11     PVCCIO_CPU0             
                                  DV13     P3E_CPU0_PE1_PCH_RXN<12>
                                  DV15     P3E_CPU0_PE1_PCH_RXP<14>
                                  DV17     P3E_CPU0_PE3_OCP_RXP<2> 
                                  DV19     GND                     
                                  DV21     GND                     
                                  DV23     M_D_DQS_DN<7>           
                                  DV25     GND                     
                                  DV27     GND                     
                                  DV29     M_D_DQS_DN<6>           
                                  DV31     GND                     
                                  DV33     GND                     
                                  DV35     M_D_DQS_DN<5>           
                                  DV37     GND                     
                                  DV39     GND                     
                                  DV41     M_E_DQS_DN<4>           
                                  DV45     M_D_CS_N<6>             
                                  DV47     M_D_C<2>                
                                  DV49     M_D_MA<15>              
                                  DV51     M_E_CS_N<0>             
                                  DV53     M_E_PAR                 
                                  DV55     M_E_BA<1>               
                                  DV57     M_E_MA<2>               
                                  DV59     M_E_MA<9>               
                                  DV61     TP_CPU0_RSVD_25         
                                  DV63     M_DEF_RST_N             
                                  DV65     M_E_ECC<2>              
                                  DV67     M_E_DQS_DN<17>          
                                  DV69     M_E_ECC<5>              
                                  DV71     TP_CPU0_RSVD_24         
                                  DV73     GND                     
                                  DV75     M_D_DQS_DN<3>           
                                  DV77     GND                     
                                  DV79     M_E_DQS_DP<11>          
                                  DV81     GND                     
                                  DV83     M_D_DQ<10>              
                                  DV85     M_D_DQ<15>              
                                  DW2      GND                     
                                  DW4      P3E_CPU0_PE1_PCH_TXN<10>
                                  DW6      P3E_CPU0_PE1_PCH_TXP<13>
                                  DW8      GND                     
                                  DW10     P3E_CPU0_PE3_OCP_TXN<5> 
                                  DW12     GND                     
                                  DW14     P3E_CPU0_PE1_PCH_RXN<13>
                                  DW16     P3E_CPU0_PE3_OCP_RXN<2> 
                                  DW18     P3E_CPU0_PE3_OCP_RXN<1> 
                                  DW20     GND                     
                                  DW22     M_D_DQ<63>              
                                  DW24     GND                     
                                  DW26     M_E_DQS_DP<15>          
                                  DW28     GND                     
                                  DW30     GND                     
                                  DW32     M_E_DQS_DP<14>          
                                  DW34     GND                     
                                  DW36     GND                     
                                  DW38     M_D_DQS_DP<13>          
                                  DW40     GND                     
                                  DW42     M_E_DQ<33>              
                                  DW44     TP_CPU0_RSVD_23         
                                  DW46     TP_CPU0_RSVD_22         
                                  DW48     M_D_MA<13>              
                                  DW50     M_E_CS_N<4>             
                                  DW52     M_E_MA<0>               
                                  DW54     M_D_MA<10>              
                                  DW56     M_D_CLK_DN<2>           
                                  DW58     M_E_MA<1>               
                                  DW60     M_D_ACT_N               
                                  DW62     M_D_BG<1>               
                                  DW64     GND                     
                                  DW66     GND                     
                                  DW68     GND                     
                                  DW70     GND                     
                                  DW72     GND                     
                                  DW74     GND                     
                                  DW76     GND                     
                                  DW78     M_E_DQ<22>              
                                  DW80     M_E_DQ<16>              
                                  DW82     GND                     
                                  DW84     GND                     
                                  DY3      TP_CPU0_RSVD_21         
                                  DY5      GND                     
                                  DY7      P3E_CPU0_PE1_PCH_TXN<13>
                                  DY9      P3E_CPU0_PE3_OCP_TXP<4> 
                                  DY11     P3E_CPU0_PE3_OCP_TXN<3> 
                                  DY13     P3E_CPU0_PE1_PCH_RXP<13>
                                  DY15     P3E_CPU0_PE1_PCH_RXN<14>
                                  DY17     P3E_CPU0_PE3_OCP_RXP<0> 
                                  DY19     GND                     
                                  DY21     M_D_DQ<58>              
                                  DY23     GND                     
                                  DY25     M_E_DQ<54>              
                                  DY27     M_E_DQ<52>              
                                  DY29     GND                     
                                  DY31     M_E_DQ<46>              
                                  DY33     M_E_DQ<44>              
                                  DY35     GND                     
                                  DY37     M_D_DQ<38>              
                                  DY39     M_D_DQ<36>              
                                  DY41     GND                     
                                  DY45     GND                     
                                  DY47     GND                     
                                  DY49     GND                     
                                  DY51     GND                     
                                  DY53     GND                     
                                  DY55     GND                     
                                  DY57     GND                     
                                  DY59     GND                     
                                  DY61     GND                     
                                  DY63     GND                     
                                  DY65     M_E_ECC<3>              
                                  DY67     M_E_DQS_DP<8>           
                                  DY69     M_E_ECC<0>              
                                  DY71     GND                     
                                  DY73     M_E_DQS_DP<12>          
                                  DY75     GND                     
                                  DY77     M_E_DQ<18>              
                                  DY79     M_E_DQS_DN<11>          
                                  DY81     M_E_DQ<20>              
                                  DY83     M_D_DQ<11>              
                                  DY85     GND                     
                                  E2       TP_CPU0_RSVD_283        
                                  E4       TP_CPU0_RSVD_282        
                                  E6       GND                     
                                  E8       GND                     
                                  E10      UPI_CPU0_CPU1_P1P1_DP<11>
                                  E12      UPI_CPU0_CPU1_P1P1_DN<9>
                                  E14      UPI_CPU0_CPU1_P1P1_DP<7>
                                  E16      GND                     
                                  E18      GND                     
                                  E20      GND                     
                                  E22      GND                     
                                  E24      TP_CPU0_RSVD_281        
                                  E26      M_B_DQ<51>              
                                  E28      M_B_DQS_DP<6>           
                                  E30      M_B_DQ<52>              
                                  E32      M_B_DQ<43>              
                                  E34      M_B_DQS_DP<5>           
                                  E36      M_B_DQ<44>              
                                  E38      M_A_DQ<35>              
                                  E40      M_A_DQS_DP<4>           
                                  E42      M_A_DQ<36>              
                                  E46      PVDDQ_ABC               
                                  E48      PVDDQ_ABC               
                                  E50      PVDDQ_ABC               
                                  E52      PVDDQ_ABC               
                                  E54      PVDDQ_ABC               
                                  E56      PVDDQ_ABC               
                                  E58      PVDDQ_ABC               
                                  E60      PVDDQ_ABC               
                                  E62      PVDDQ_ABC               
                                  E64      PVDDQ_ABC               
                                  E66      GND                     
                                  E72      GND                     
                                  E74      GND                     
                                  E76      GND                     
                                  E78      M_B_DQ<22>              
                                  E80      M_B_DQ<16>              
                                  E82      GND                     
                                  E84      TP_CPU0_RSVD_280        
                                  EA4      TP_CPU0_RSVD_20         
                                  EA6      GND                     
                                  EA8      P3E_CPU0_PE1_PCH_TXN<14>
                                  EA10     P3E_CPU0_PE3_OCP_TXP<3> 
                                  EA12     PVCCIO_CPU0             
                                  EA14     GND                     
                                  EA16     GND                     
                                  EA18     P3E_CPU0_PE3_OCP_RXN<0> 
                                  EA20     GND                     
                                  EA22     GND                     
                                  EA24     M_E_DQ<50>              
                                  EA26     M_E_DQS_DN<15>          
                                  EA28     M_E_DQ<53>              
                                  EA30     M_E_DQ<42>              
                                  EA32     M_E_DQS_DN<14>          
                                  EA34     M_E_DQ<45>              
                                  EA36     M_D_DQ<34>              
                                  EA38     M_D_DQS_DN<13>          
                                  EA40     M_D_DQ<37>              
                                  EA42     GND                     
                                  EA44     TP_CPU0_RSVD_19         
                                  EA46     M_D_MA<17>              
                                  EA48     M_D_ODT<3>              
                                  EA50     M_D_ODT<2>              
                                  EA52     M_D_MA<16>              
                                  EA54     M_D_BA<1>               
                                  EA56     M_D_CLK_DP<2>           
                                  EA58     M_D_MA<5>               
                                  EA60     M_D_MA<7>               
                                  EA62     M_D_CKE<2>              
                                  EA64     GND                     
                                  EA66     M_E_ECC<7>              
                                  EA68     M_E_ECC<1>              
                                  EA70     GND                     
                                  EA72     M_E_DQ<30>              
                                  EA74     M_E_DQ<28>              
                                  EA76     GND                     
                                  EA78     GND                     
                                  EA80     GND                     
                                  EA82     GND                     
                                  EA84     GND                     
                                  EB3      TP_CPU0_RSVD_18         
                                  EB5      TP_CPU0_RSVD_17         
                                  EB7      P3E_CPU0_PE1_PCH_TXP<14>
                                  EB9      P3E_CPU0_PE3_OCP_TXN<4> 
                                  EB11     P3E_CPU0_PE3_OCP_TXP<2> 
                                  EB13     GND                     
                                  EB15     PVCCIO_CPU0             
                                  EB21     M_D_DQ<59>              
                                  EB23     GND                     
                                  EB25     GND                     
                                  EB27     GND                     
                                  EB29     GND                     
                                  EB31     GND                     
                                  EB33     GND                     
                                  EB35     GND                     
                                  EB37     GND                     
                                  EB39     GND                     
                                  EB41     GND                     
                                  EB45     M_D_CS_N<7>             
                                  EB47     M_D_CS_N<3>             
                                  EB49     M_D_CS_N<5>             
                                  EB51     M_D_CS_N<4>             
                                  EB53     M_D_MA<0>               
                                  EB55     M_D_CLK_DP<0>           
                                  EB57     M_D_MA<3>               
                                  EB59     M_D_MA<8>               
                                  EB61     M_D_MA<11>              
                                  EB63     M_D_CKE<3>              
                                  EB65     GND                     
                                  EB67     M_E_DQS_DN<8>           
                                  EB69     GND                     
                                  EB71     M_E_DQ<26>              
                                  EB73     M_E_DQS_DN<12>          
                                  EB75     M_E_DQ<29>              
                                  EB77     M_E_DQ<19>              
                                  EB79     M_E_DQS_DP<2>           
                                  EB81     M_E_DQ<21>              
                                  EB83     GND                     
                                  EB85     TP_CPU0_RSVD_16         
                                  EC4      TP_CPU0_RSVD_14         
                                  EC6      GND                     
                                  EC8      P3E_CPU0_PE1_PCH_TXP<15>
                                  EC10     GND                     
                                  EC12     P3E_CPU0_PE3_OCP_TXN<2> 
                                  EC14     P3E_CPU0_PE3_OCP_TXP<0> 
                                  EC16     TP_CPU0_RSVD_15         
                                  EC22     M_D_DQ<62>              
                                  EC24     M_E_DQ<51>              
                                  EC26     M_E_DQS_DP<6>           
                                  EC28     M_E_DQ<48>              
                                  EC30     M_E_DQ<43>              
                                  EC32     M_E_DQS_DP<5>           
                                  EC34     M_E_DQ<40>              
                                  EC36     M_D_DQ<35>              
                                  EC38     M_D_DQS_DP<4>           
                                  EC40     M_D_DQ<32>              
                                  EC42     GND                     
                                  EC44     TP_CPU0_RSVD_13         
                                  EC46     PVDDQ_DEF               
                                  EC48     PVDDQ_DEF               
                                  EC50     PVDDQ_DEF               
                                  EC52     PVDDQ_DEF               
                                  EC54     PVDDQ_DEF               
                                  EC56     PVDDQ_DEF               
                                  EC58     PVDDQ_DEF               
                                  EC60     PVDDQ_DEF               
                                  EC62     PVDDQ_DEF               
                                  EC70     GND                     
                                  EC72     GND                     
                                  EC74     GND                     
                                  EC76     GND                     
                                  EC78     M_E_DQ<23>              
                                  EC80     M_E_DQ<17>              
                                  EC82     GND                     
                                  EC84     TP_CPU0_RSVD_12         
                                  ED5      TP_CPU0_RSVD_10         
                                  ED7      GND                     
                                  ED9      P3E_CPU0_PE1_PCH_TXN<15>
                                  ED11     GND                     
                                  ED13     P3E_CPU0_PE3_OCP_TXP<1> 
                                  ED15     GND                     
                                  ED23     GND                     
                                  ED25     M_E_DQ<55>              
                                  ED27     M_E_DQ<49>              
                                  ED29     GND                     
                                  ED31     M_E_DQ<47>              
                                  ED33     M_E_DQ<41>              
                                  ED35     GND                     
                                  ED37     M_D_DQ<39>              
                                  ED39     M_D_DQ<33>              
                                  ED41     GND                     
                                  ED45     TP_CPU0_RSVD_11         
                                  ED47     M_D_CS_N<2>             
                                  ED49     M_D_CS_N<1>             
                                  ED51     M_D_MA<14>              
                                  ED53     M_D_PAR                 
                                  ED55     M_D_CLK_DN<0>           
                                  ED57     M_D_MA<1>               
                                  ED59     M_D_MA<4>               
                                  ED61     M_D_BG<0>               
                                  ED63     M_D_ALERT_N             
                                  ED69     GND                     
                                  ED71     M_E_DQ<27>              
                                  ED73     M_E_DQS_DP<3>           
                                  ED75     M_E_DQ<24>              
                                  ED77     GND                     
                                  ED79     M_E_DQS_DN<2>           
                                  ED81     GND                     
                                  ED83     TP_CPU0_RSVD_9          
                                  EE6      TP_CPU0_RSVD_6          
                                  EE8      GND                     
                                  EE10     PVCCIO_CPU0             
                                  EE12     P3E_CPU0_PE3_OCP_TXN<1> 
                                  EE14     P3E_CPU0_PE3_OCP_TXN<0> 
                                  EE16     TP_CPU0_RSVD_8          
                                  EE24     GND                     
                                  EE26     M_E_DQS_DN<6>           
                                  EE28     GND                     
                                  EE30     GND                     
                                  EE32     M_E_DQS_DN<5>           
                                  EE34     GND                     
                                  EE36     GND                     
                                  EE38     M_D_DQS_DN<4>           
                                  EE40     GND                     
                                  EE44     PVDDQ_DEF               
                                  EE46     TP_CPU0_RSVD_7          
                                  EE48     M_D_ODT<1>              
                                  EE50     M_D_ODT<0>              
                                  EE52     M_D_BA<0>               
                                  EE54     M_D_CLK_DP<1>           
                                  EE56     M_D_CLK_DP<3>           
                                  EE58     M_D_MA<2>               
                                  EE60     M_D_MA<6>               
                                  EE62     M_D_CKE<0>              
                                  EE70     GND                     
                                  EE72     M_E_DQ<31>              
                                  EE74     M_E_DQ<25>              
                                  EE76     GND                     
                                  EE78     GND                     
                                  EE80     GND                     
                                  EE82     TP_CPU0_RSVD_5          
                                  EE84     TP_CPU0_RSVD_4          
                                  EF45     PVDDQ_DEF               
                                  EF47     TP_CPU0_RSVD_3          
                                  EF49     PVDDQ_DEF               
                                  EF51     M_D_CS_N<0>             
                                  EF53     PVDDQ_DEF               
                                  EF55     M_D_CLK_DN<1>           
                                  EF57     M_D_CLK_DN<3>           
                                  EF59     PVDDQ_DEF               
                                  EF61     M_D_MA<9>               
                                  EF63     M_D_CKE<1>              
                                  EF71     GND                     
                                  EF73     M_E_DQS_DN<3>           
                                  EF75     GND                     
                                  EF77     TP_CPU0_RSVD_2          
                                  EF79     GND                     
                                  EF81     TP_CPU0_RSVD_1          
                                  EF83     TP_CPU0_RSVD_0          
                                  F3       TP_CPU0_RSVD_279        
                                  F5       GND                     
                                  F7       UPI_CPU0_CPU1_P1P1_DP<15>
                                  F9       UPI_CPU0_CPU1_P1P1_DP<12>
                                  F11      UPI_CPU0_CPU1_P1P1_DN<11>
                                  F13      UPI_CPU0_CPU1_P1P1_DP<8>
                                  F15      UPI_CPU0_CPU1_P1P1_DN<6>
                                  F17      GND                     
                                  F19      GND                     
                                  F21      UPI_CPU0_CPU1_P1P1_DN<1>
                                  F23      TP_CPU0_RSVD_278        
                                  F25      GND                     
                                  F27      M_B_DQ<55>              
                                  F29      M_B_DQ<53>              
                                  F31      GND                     
                                  F33      M_B_DQ<47>              
                                  F35      M_B_DQ<45>              
                                  F37      GND                     
                                  F39      M_A_DQ<39>              
                                  F41      M_A_DQ<37>              
                                  F43      GND                     
                                  F45      M_A_CS_N<6>             
                                  F47      M_A_CS_N<3>             
                                  F49      M_A_CS_N<1>             
                                  F51      M_A_MA<14>              
                                  F53      M_A_MA<0>               
                                  F55      M_A_CLK_DN<0>           
                                  F57      M_A_MA<1>               
                                  F59      M_A_MA<5>               
                                  F61      M_A_MA<9>               
                                  F63      M_A_BG<1>               
                                  F65      TP_CPU0_RSVD_277        
                                  F67      GND                     
                                  F69      GND                     
                                  F71      M_B_DQ<27>              
                                  F73      M_B_DQS_DP<3>           
                                  F75      M_B_DQ<28>              
                                  F77      M_B_DQ<18>              
                                  F79      M_B_DQS_DP<11>          
                                  F81      M_B_DQ<20>              
                                  F83      TP_CPU0_RSVD_276        
                                  G2       TP_CPU0_RSVD_275        
                                  G4       GND                     
                                  G6       UPI_CPU0_CPU1_P1P1_DN<15>
                                  G8       GND                     
                                  G10      UPI_CPU0_CPU1_P1P1_DN<10>
                                  G12      UPI_CPU0_CPU1_P1P1_DP<9>
                                  G14      UPI_CPU0_CPU1_P1P1_DN<8>
                                  G16      UPI_CPU0_CPU1_P1P1_DP<5>
                                  G18      UPI_CPU0_CPU1_P1P1_DN<3>
                                  G20      UPI_CPU0_CPU1_P1P1_DP<1>
                                  G22      GND                     
                                  G24      GND                     
                                  G26      GND                     
                                  G28      M_B_DQS_DN<6>           
                                  G30      GND                     
                                  G32      GND                     
                                  G34      M_B_DQS_DN<5>           
                                  G36      GND                     
                                  G38      GND                     
                                  G40      M_A_DQS_DN<4>           
                                  G42      GND                     
                                  G46      M_A_C<2>                
                                  G48      M_A_ODT<3>              
                                  G50      M_A_ODT<2>              
                                  G52      M_A_CS_N<0>             
                                  G54      M_A_BA<1>               
                                  G56      M_A_CLK_DP<2>           
                                  G58      M_A_MA<4>               
                                  G60      M_A_MA<7>               
                                  G62      M_A_MA<11>              
                                  G64      TP_CPU0_RSVD_274        
                                  G66      GND                     
                                  G68      M_B_DQS_DN<17>          
                                  G70      GND                     
                                  G72      M_B_DQ<31>              
                                  G74      M_B_DQ<29>              
                                  G76      GND                     
                                  G78      GND                     
                                  G80      GND                     
                                  G82      GND                     
                                  G84      TP_CPU0_RSVD_273        
                                  H1       TP_CPU0_RSVD_272        
                                  H3       GND                     
                                  H5       UPI_CPU0_CPU1_P1P1_DP<16>
                                  H7       UPI_CPU0_CPU1_P1P1_DN<14>
                                  H9       UPI_CPU0_CPU1_P1P1_DP<10>
                                  H11      GND                     
                                  H13      PVCCIO_CPU0             
                                  H15      UPI_CPU0_CPU1_P1P1_DP<6>
                                  H17      UPI_CPU0_CPU1_P1P1_DN<5>
                                  H19      UPI_CPU0_CPU1_P1P1_DP<2>
                                  H21      UPI_CPU0_CPU1_P1P1_DN<0>
                                  H23      M_A_DQ<62>              
                                  H25      GND                     
                                  H27      GND                     
                                  H29      GND                     
                                  H31      GND                     
                                  H33      GND                     
                                  H35      GND                     
                                  H37      GND                     
                                  H39      GND                     
                                  H41      GND                     
                                  H43      M_B_DQ<33>              
                                  H45      GND                     
                                  H47      GND                     
                                  H49      GND                     
                                  H51      GND                     
                                  H53      GND                     
                                  H55      GND                     
                                  H57      GND                     
                                  H59      GND                     
                                  H61      GND                     
                                  H63      GND                     
                                  H65      GND                     
                                  H67      M_B_ECC<6>              
                                  H69      M_B_ECC<1>              
                                  H71      GND                     
                                  H73      M_B_DQS_DN<3>           
                                  H75      GND                     
                                  H77      M_B_DQ<19>              
                                  H79      M_B_DQS_DP<2>           
                                  H81      M_B_DQ<21>              
                                  H83      TP_CPU0_RSVD_271        
                                  H85      TP_CPU0_RSVD_270        
                                  J2       PVCCIO_CPU0             
                                  J4       GND                     
                                  J6       UPI_CPU0_CPU1_P1P1_DN<16>
                                  J8       UPI_CPU0_CPU1_P1P1_DP<13>
                                  J10      PVCCIO_CPU0             
                                  J12      GND                     
                                  J14      GND                     
                                  J16      GND                     
                                  J18      UPI_CPU0_CPU1_P1P1_DP<3>
                                  J20      UPI_CPU0_CPU1_P1P1_DN<2>
                                  J22      GND                     
                                  J24      M_A_DQS_DN<16>          
                                  J26      GND                     
                                  J28      GND                     
                                  J30      M_A_DQS_DN<15>          
                                  J32      GND                     
                                  J34      GND                     
                                  J36      M_A_DQS_DN<14>          
                                  J38      GND                     
                                  J40      GND                     
                                  J42      M_B_DQS_DN<13>          
                                  J46      TP_CPU0_RSVD_269        
                                  J48      M_A_MA<13>              
                                  J50      M_B_CS_N<4>             
                                  J52      M_B_MA<0>               
                                  J54      M_A_MA<10>              
                                  J56      M_A_CLK_DN<2>           
                                  J58      M_B_MA<1>               
                                  J60      M_A_ACT_N               
                                  J62      TP_CPU0_RSVD_268        
                                  J64      M_A_MA<12>              
                                  J66      M_B_ECC<2>              
                                  J68      M_B_DQS_DP<17>          
                                  J70      M_B_ECC<0>              
                                  J72      GND                     
                                  J74      GND                     
                                  J76      GND                     
                                  J78      M_B_DQ<23>              
                                  J80      M_B_DQ<17>              
                                  J82      GND                     
                                  J84      GND                     
                                  J86      GND                     
                                  K1       GND                     
                                  K3       UPI_CPU0_CPU1_P1P1_DP<18>
                                  K5       UPI_CPU0_CPU1_P1P1_DN<17>
                                  K7       UPI_CPU0_CPU1_P1P1_DP<14>
                                  K9       UPI_CPU0_CPU1_P1P1_DN<13>
                                  K11      GND                     
                                  K13      GND                     
                                  K15      PVCCIO_CPU0             
                                  K17      GND                     
                                  K19      UPI_CPU0_CPU1_P1P1_DN<4>
                                  K21      UPI_CPU0_CPU1_P1P1_DP<0>
                                  K23      M_A_DQ<63>              
                                  K25      M_A_DQ<56>              
                                  K27      GND                     
                                  K29      M_A_DQ<54>              
                                  K31      M_A_DQ<48>              
                                  K33      GND                     
                                  K35      M_A_DQ<46>              
                                  K37      M_A_DQ<40>              
                                  K39      GND                     
                                  K41      M_B_DQ<38>              
                                  K43      M_B_DQ<32>              
                                  K45      M_A_CS_N<7>             
                                  K47      M_A_MA<17>              
                                  K49      M_A_MA<15>              
                                  K51      M_B_CS_N<0>             
                                  K53      M_B_PAR                 
                                  K55      M_B_BA<1>               
                                  K57      M_B_MA<2>               
                                  K59      M_B_MA<9>               
                                  K61      TP_CPU0_RSVD_267        
                                  K63      M_B_CKE<2>              
                                  K65      GND                     
                                  K67      GND                     
                                  K69      GND                     
                                  K71      GND                     
                                  K73      GND                     
                                  K75      M_A_DQS_DN<12>          
                                  K77      GND                     
                                  K79      M_B_DQS_DN<2>           
                                  K81      GND                     
                                  K83      GND                     
                                  K85      GND                     
                                  L2       GND                     
                                  L4       UPI_CPU0_CPU1_P1P1_DN<18>
                                  L6       GND                     
                                  L8       GND                     
                                  L10      GND                     
                                  L12      UPI_CPU1_CPU0_P1P1_DN<12>
                                  L14      PVCCIO_CPU0             
                                  L16      PVCCIO_CPU0             
                                  L18      UPI_CPU0_CPU1_P1P1_DP<4>
                                  L20      GND                     
                                  L22      GND                     
                                  L24      M_A_DQS_DP<16>          
                                  L26      M_A_DQ<60>              
                                  L28      M_A_DQ<50>              
                                  L30      M_A_DQS_DP<15>          
                                  L32      M_A_DQ<52>              
                                  L34      M_A_DQ<42>              
                                  L36      M_A_DQS_DP<14>          
                                  L38      M_A_DQ<44>              
                                  L40      M_B_DQ<34>              
                                  L42      M_B_DQS_DP<13>          
                                  L46      PVDDQ_ABC               
                                  L48      PVDDQ_ABC               
                                  L50      PVDDQ_ABC               
                                  L52      PVDDQ_ABC               
                                  L54      PVDDQ_ABC               
                                  L56      PVDDQ_ABC               
                                  L58      PVDDQ_ABC               
                                  L60      PVDDQ_ABC               
                                  L62      PVDDQ_ABC               
                                  L64      M_B_CKE<3>              
                                  L66      M_B_ECC<3>              
                                  L68      M_B_DQS_DP<8>           
                                  L70      M_B_ECC<4>              
                                  L72      GND                     
                                  L74      M_A_DQ<30>              
                                  L76      M_A_DQ<24>              
                                  L78      GND                     
                                  L80      GND                     
                                  L82      GND                     
                                  L84      M_A_DQ<11>              
                                  L86      M_A_DQ<10>              
                                  M1       UPI_CPU0_CPU1_P0P0_DP<19>
                                  M3       UPI_CPU0_CPU1_P1P1_DN<19>
                                  M5       UPI_CPU0_CPU1_P1P1_DP<17>
                                  M7       PVCCIO_CPU0             
                                  M9       PVCCIO_CPU0             
                                  M11      PVCCIO_CPU0             
                                  M13      UPI_CPU1_CPU0_P1P1_DP<11>
                                  M15      GND                     
                                  M17      GND                     
                                  M19      GND                     
                                  M21      PVCCIO_CPU0             
                                  M23      GND                     
                                  M25      GND                     
                                  M27      GND                     
                                  M29      GND                     
                                  M31      GND                     
                                  M33      GND                     
                                  M35      GND                     
                                  M37      GND                     
                                  M39      GND                     
                                  M41      GND                     
                                  M43      GND                     
                                  M45      M_B_CS_N<6>             
                                  M47      M_B_C<2>                
                                  M49      M_B_ODT<2>              
                                  M51      M_B_MA<13>              
                                  M53      M_B_CLK_DN<0>           
                                  M55      M_B_MA<10>              
                                  M57      M_B_CLK_DP<2>           
                                  M59      M_B_MA<4>               
                                  M61      M_B_BG<0>               
                                  M63      TP_CPU0_RSVD_266        
                                  M65      GND                     
                                  M67      M_B_ECC<7>              
                                  M69      M_B_ECC<5>              
                                  M71      GND                     
                                  M73      M_A_DQ<26>              
                                  M75      M_A_DQS_DP<12>          
                                  M77      M_A_DQ<28>              
                                  M79      GND                     
                                  M81      M_A_DQ<19>              
                                  M83      GND                     
                                  M85      GND                     
                                  N2       UPI_CPU0_CPU1_P0P0_DN<19>
                                  N4       GND                     
                                  N6       GND                     
                                  N8       GND                     
                                  N10      UPI_CPU1_CPU0_P1P1_DP<15>
                                  N12      UPI_CPU1_CPU0_P1P1_DP<12>
                                  N14      UPI_CPU1_CPU0_P1P1_DN<11>
                                  N16      UPI_CPU1_CPU0_P1P1_DP<8>
                                  N18      PVCCIO_CPU0             
                                  N20      GND                     
                                  N22      GND                     
                                  N24      M_A_DQS_DN<7>           
                                  N26      M_A_DQ<61>              
                                  N28      M_A_DQ<51>              
                                  N30      M_A_DQS_DP<6>           
                                  N32      M_A_DQ<53>              
                                  N34      M_A_DQ<43>              
                                  N36      M_A_DQS_DP<5>           
                                  N38      M_A_DQ<45>              
                                  N40      M_B_DQ<35>              
                                  N42      M_B_DQS_DN<4>           
                                  N46      M_B_CS_N<2>             
                                  N48      M_B_MA<17>              
                                  N50      M_B_ODT<0>              
                                  N52      M_B_MA<15>              
                                  N54      M_B_CLK_DP<0>           
                                  N56      M_B_CLK_DN<2>           
                                  N58      M_B_MA<3>               
                                  N60      M_B_BG<1>               
                                  N62      M_B_CKE<0>              
                                  N64      PVDDQ_ABC               
                                  N66      GND                     
                                  N68      M_B_DQS_DN<8>           
                                  N70      GND                     
                                  N72      GND                     
                                  N74      GND                     
                                  N76      GND                     
                                  N78      GND                     
                                  N80      M_A_DQ<23>              
                                  N82      M_A_DQ<18>              
                                  N84      M_A_DQ<15>              
                                  N86      M_A_DQ<14>              
                                  P1       UPI_CPU0_CPU1_P0P0_DN<18>
                                  P3       UPI_CPU0_CPU1_P1P1_DP<19>
                                  P5       PVCCIO_CPU0             
                                  P7       UPI_CPU1_CPU0_P1P1_DN<18>
                                  P9       UPI_CPU1_CPU0_P1P1_DN<15>
                                  P11      GND                     
                                  P13      UPI_CPU1_CPU0_P1P1_DP<10>
                                  P15      GND                     
                                  P17      UPI_CPU1_CPU0_P1P1_DN<8>
                                  P19      UPI_CPU1_CPU0_P1P1_DP<5>
                                  P21      UPI_CPU1_CPU0_P1P1_DN<3>
                                  P23      M_A_DQ<58>              
                                  P25      M_A_DQ<57>              
                                  P27      GND                     
                                  P29      M_A_DQ<55>              
                                  P31      M_A_DQ<49>              
                                  P33      GND                     
                                  P35      M_A_DQ<47>              
                                  P37      M_A_DQ<41>              
                                  P39      GND                     
                                  P41      M_B_DQ<39>              
                                  P43      M_B_DQ<36>              
                                  P45      GND                     
                                  P47      GND                     
                                  P49      GND                     
                                  P51      GND                     
                                  P53      GND                     
                                  P55      GND                     
                                  P57      GND                     
                                  P59      GND                     
                                  P61      GND                     
                                  P63      GND                     
                                  P65      TP_CPU0_RSVD_265        
                                  P67      GND                     
                                  P69      GND                     
                                  P71      GND                     
                                  P73      M_A_DQ<27>              
                                  P75      M_A_DQS_DP<3>           
                                  P77      M_A_DQ<29>              
                                  P79      M_A_DQS_DN<2>           
                                  P81      GND                     
                                  P83      GND                     
                                  P85      M_A_DQS_DP<1>           
                                  R2       GND                     
                                  R4       GND                     
                                  R6       UPI_CPU1_CPU0_P1P1_DP<19>
                                  R8       UPI_CPU1_CPU0_P1P1_DP<16>
                                  R10      UPI_CPU1_CPU0_P1P1_DN<14>
                                  R12      UPI_CPU1_CPU0_P1P1_DN<10>
                                  R14      GND                     
                                  R16      UPI_CPU1_CPU0_P1P1_DN<9>
                                  R18      GND                     
                                  R20      UPI_CPU1_CPU0_P1P1_DN<5>
                                  R22      GND                     
                                  R24      M_A_DQS_DP<7>           
                                  R26      GND                     
                                  R28      GND                     
                                  R30      M_A_DQS_DN<6>           
                                  R32      GND                     
                                  R34      GND                     
                                  R36      M_A_DQS_DN<5>           
                                  R38      GND                     
                                  R40      GND                     
                                  R42      M_B_DQS_DP<4>           
                                  R46      M_B_CS_N<7>             
                                  R48      M_B_ODT<1>              
                                  R50      M_B_CS_N<1>             
                                  R52      M_B_MA<16>              
                                  R54      M_B_CLK_DN<1>           
                                  R56      M_B_CLK_DN<3>           
                                  R58      M_B_MA<5>               
                                  R60      M_B_MA<11>              
                                  R62      TP_CPU0_RSVD_264        
                                  R64      M_B_CKE<1>              
                                  R66      TP_CPU0_RSVD_263        
                                  R68      GND                     
                                  R70      M_C_DQ<18>              
                                  R72      GND                     
                                  R74      M_A_DQ<31>              
                                  R76      M_A_DQ<25>              
                                  R78      GND                     
                                  R80      M_A_DQS_DP<2>           
                                  R82      M_A_DQ<22>              
                                  R84      M_A_DQS_DN<1>           
                                  R86      GND                     
                                  T1       UPI_CPU0_CPU1_P0P0_DP<18>
                                  T3       PVCCIO_CPU0             
                                  T5       UPI_CPU1_CPU0_P1P1_DN<19>
                                  T7       UPI_CPU1_CPU0_P1P1_DP<18>
                                  T9       UPI_CPU1_CPU0_P1P1_DN<16>
                                  T11      UPI_CPU1_CPU0_P1P1_DP<13>
                                  T13      GND                     
                                  T15      UPI_CPU1_CPU0_P1P1_DP<9>
                                  T17      GND                     
                                  T19      UPI_CPU1_CPU0_P1P1_DP<4>
                                  T21      UPI_CPU1_CPU0_P1P1_DP<3>
                                  T23      M_A_DQ<59>              
                                  T25      GND                     
                                  T27      M_B_DQS_DN<16>          
                                  T29      GND                     
                                  T31      GND                     
                                  T33      M_C_DQS_DN<14>          
                                  T35      GND                     
                                  T37      GND                     
                                  T39      M_C_DQS_DN<13>          
                                  T41      GND                     
                                  T43      M_B_DQ<37>              
                                  T45      M_C_CS_N<6>             
                                  T47      M_B_ODT<3>              
                                  T49      M_B_CS_N<5>             
                                  T51      M_B_MA<14>              
                                  T53      M_B_BA<0>               
                                  T55      M_B_CLK_DP<1>           
                                  T57      M_B_CLK_DP<3>           
                                  T59      M_B_MA<6>               
                                  T61      M_B_MA<12>              
                                  T63      M_B_ACT_N               
                                  T65      GND                     
                                  T67      TP_CPU0_RSVD_262        
                                  T69      M_C_DQ<19>              
                                  T71      M_C_DQ<22>              
                                  T73      GND                     
                                  T75      M_A_DQS_DN<3>           
                                  T77      GND                     
                                  T79      M_A_DQ<17>              
                                  T81      M_A_DQS_DP<11>          
                                  T83      GND                     
                                  T85      GND                     
                                  U2       GND                     
                                  U4       GND                     
                                  U6       GND                     
                                  U8       UPI_CPU1_CPU0_P1P1_DP<17>
                                  U10      UPI_CPU1_CPU0_P1P1_DP<14>
                                  U12      UPI_CPU1_CPU0_P1P1_DN<13>
                                  U14      PVCCIO_CPU0             
                                  U16      UPI_CPU1_CPU0_P1P1_DN<7>
                                  U18      UPI_CPU1_CPU0_P1P1_DN<4>
                                  U20      GND                     
                                  U22      GND                     
                                  U24      GND                     
                                  U26      M_B_DQ<62>              
                                  U28      M_B_DQ<56>              
                                  U30      GND                     
                                  U32      M_C_DQ<46>              
                                  U34      M_C_DQ<40>              
                                  U36      GND                     
                                  U38      M_C_DQ<38>              
                                  U40      M_C_DQ<32>              
                                  U42      GND                     
                                  U46      PVDDQ_ABC               
                                  U48      PVDDQ_ABC               
                                  U50      PVDDQ_ABC               
                                  U52      PVDDQ_ABC               
                                  U54      PVDDQ_ABC               
                                  U56      PVDDQ_ABC               
                                  U58      PVDDQ_ABC               
                                  U60      PVDDQ_ABC               
                                  U62      PVDDQ_ABC               
                                  U64      M_ABC_RST_N             
                                  U66      TP_CPU0_RSVD_261        
                                  U68      GND                     
                                  U70      GND                     
                                  U72      M_C_DQS_DN<11>          
                                  U74      GND                     
                                  U76      GND                     
                                  U78      GND                     
                                  U80      GND                     
                                  U82      M_A_DQS_DN<11>          
                                  U84      M_A_DQS_DN<10>          
                                  U86      GND                     
                                  V1       GND                     
                                  V3       UPI_CPU0_CPU1_P0P0_DN<17>
                                  V5       GND                     
                                  V7       UPI_CPU1_CPU0_P1P1_DN<17>
                                  V9       GND                     
                                  V11      GND                     
                                  V13      GND                     
                                  V15      GND                     
                                  V17      UPI_CPU1_CPU0_P1P1_DP<6>
                                  V19      UPI_CPU1_CPU0_P1P1_DN<2>
                                  V21      GND                     
                                  V23      GND                     
                                  V25      M_B_DQ<58>              
                                  V27      M_B_DQS_DP<16>          
                                  V29      M_B_DQ<60>              
                                  V31      M_C_DQ<42>              
                                  V33      M_C_DQS_DP<14>          
                                  V35      M_C_DQ<44>              
                                  V37      M_C_DQ<34>              
                                  V39      M_C_DQS_DP<13>          
                                  V41      M_C_DQ<36>              
                                  V43      GND                     
                                  V45      M_C_CS_N<7>             
                                  V47      M_B_CS_N<3>             
                                  V49      M_C_ODT<2>              
                                  V51      M_C_CS_N<0>             
                                  V53      M_C_PAR                 
                                  V55      M_C_CLK_DP<1>           
                                  V57      M_C_CLK_DP<3>           
                                  V59      M_C_MA<5>               
                                  V61      M_B_MA<7>               
                                  V63      M_C_CKE<2>              
                                  V65      TP_CPU0_RSVD_260        
                                  V67      TP_CPU0_RSVD_259        
                                  V69      M_C_DQ<23>              
                                  V71      M_C_DQS_DP<11>          
                                  V73      GND                     
                                  V75      GND                     
                                  V77      GND                     
                                  V79      M_A_DQ<21>              
                                  V81      M_A_DQ<16>              
                                  V83      GND                     
                                  V85      M_A_DQS_DP<10>          
                                  W2       UPI_CPU0_CPU1_P0P0_DP<16>
                                  W4       PVCCIO_CPU0             
                                  W6       PVCCIO_CPU0             
                                  W8       GND                     
                                  W10      PVCCIO_CPU0             
                                  W12      GND                     
                                  W14      XDP_CPU_TMS             
                                  W16      UPI_CPU1_CPU0_P1P1_DP<7>
                                  W18      UPI_CPU1_CPU0_P1P1_DN<6>
                                  W20      UPI_CPU1_CPU0_P1P1_DP<1>
                                  W22      GND                     
                                  W24      GND                     
                                  W26      GND                     
                                  W28      GND                     
                                  W30      GND                     
                                  W32      GND                     
                                  W34      GND                     
                                  W36      GND                     
                                  W38      GND                     
                                  W40      GND                     
                                  W42      GND                     
                                  W46      M_C_CS_N<2>             
                                  W48      M_C_CS_N<5>             
                                  W50      M_C_MA<14>              
                                  W52      M_C_BA<0>               
                                  W54      M_C_CLK_DN<1>           
                                  W56      M_C_CLK_DN<3>           
                                  W58      M_C_MA<3>               
                                  W60      M_B_MA<8>               
                                  W62      M_B_ALERT_N             
                                  W64      PVDDQ_ABC               
                                  W66      TP_CPU0_RSVD_258        
                                  W68      GND                     
                                  W70      M_C_DQS_DP<2>           
                                  W72      M_C_DQ<16>              
                                  W74      GND                     
                                  W76      M_C_DQ<11>              
                                  W78      GND                     
                                  W80      M_A_DQ<20>              
                                  W82      GND                     
                                  W84      M_A_DQ<9>               
                                  W86      M_A_DQ<8>               
                                  Y1       UPI_CPU0_CPU1_P0P0_DN<16>
                                  Y3       UPI_CPU0_CPU1_P0P0_DP<17>
                                  Y5       GND                     
                                  Y7       GND                     
                                  Y9       GND                     
                                  Y11      TP_XDP_CPU0_OBSDATA_A3_MBP5_N
                                  Y13      XDP_CPU_TRST_N          
                                  Y15      GND                     
                                  Y17      GND                     
                                  Y19      UPI_CPU1_CPU0_P1P1_DP<2>
                                  Y21      UPI_CPU1_CPU0_P1P1_DN<1>
                                  Y23      FM_CPU0_RC_ERROR_N      
                                  Y25      M_B_DQ<59>              
                                  Y27      M_B_DQS_DP<7>           
                                  Y29      M_B_DQ<61>              
                                  Y31      M_C_DQ<43>              
                                  Y33      M_C_DQS_DP<5>           
                                  Y35      M_C_DQ<45>              
                                  Y37      M_C_DQ<35>              
                                  Y39      M_C_DQS_DP<4>           
                                  Y41      M_C_DQ<37>              
                                  Y43      A_CPU0_ABC_RCOMP0       
                                  Y45      PVDDQ_ABC               
                                  Y47      PVDDQ_ABC               
                                  Y49      PVDDQ_ABC               
                                  Y51      PVDDQ_ABC               
                                  Y53      PVDDQ_ABC               
                                  Y55      PVDDQ_ABC               
                                  Y57      PVDDQ_ABC               
                                  Y59      PVDDQ_ABC               
                                  Y61      PVDDQ_ABC               
                                  Y63      PVDDQ_ABC               
                                  Y65      TP_CPU0_RSVD_256        
                                  Y67      GND                     
                                  Y69      M_C_DQS_DN<2>           
                                  Y71      GND                     
                                  Y73      GND                     
                                  Y75      M_C_DQ<15>              
                                  Y77      M_C_DQ<10>              
                                  Y79      GND                     
                                  Y81      GND                     
                                  Y83      GND                     
                                  Y85      GND                     
U6F1             PCA9617_SSOP-IC,G81764-001-GNDA 1        PVCCIO_CPU0             
                                  2        SMB_DDR_ABC_SCL_G       
                                  3        SMB_DDR_ABC_SDA_G       
                                  5        TP_SMB_DDR_ABC_EN       
                                  6        SMB_DDR_ABC_VPP_SDA_R   
                                  7        SMB_DDR_ABC_VPP_SCL_R   
                                  8        PVPP_ABC                
U6M1             74CBTLV1G125_SMLF-IC,C88177-00A 1        FM_CPU1_PKGID1          
                                  2        P1V8_MCP_CPU1           
                                  4        JTAG_MCP_CPU1_TDI_R     
U7C1             LBG_CORE_QAT_EXT_D_BGA1-IC,H91A A5       GND                     
                                  A7       GND                     
                                  A9       GND                     
                                  A11      TP_PCH_RSVD21           
                                  A13      FM_GBE_LOM_DISABLE_N    
                                  A15      FM_BMC_CPLD_MP_RST_N    
                                  A18      GND                     
                                  A20      CLK_100M_SPRV_DP        
                                  A22      GND                     
                                  A24      TP_CLK_100M_SRC13_DP    
                                  A26      TP_PCH_RSVD65           
                                  A28      CLK_100M_PCH_SLOTX24_S2_DN
                                  A30      GND                     
                                  A32      TP_CLK_100M_NSSCC0_DN   
                                  A34      GND                     
                                  A37      GND                     
                                  A39      CLK_100M_PCH_XDP_DN     
                                  A41      GND                     
                                  A43      DMI_CPU0_PCH_TX_C_DP<1> 
                                  A45      DMI_CPU0_PCH_TX_C_DP<3> 
                                  A48      P3E_CPU0_PE1_PCH_TXP<0> 
                                  A50      P3E_CPU0_PE1_PCH_TXP<2> 
                                  A52      P3E_CPU0_PE1_PCH_TXP<4> 
                                  A54      P3E_CPU0_PE1_PCH_TXP<6> 
                                  A57      P3E_CPU0_PE1_PCH_C_TXN<8>
                                  A59      P3E_CPU0_PE1_PCH_C_TXN<10>
                                  A61      P3E_CPU0_PE1_PCH_C_TXN<12>
                                  A63      P3E_CPU0_PE1_PCH_C_TXN<14>
                                  A65      GND                     
                                  A66      GND                     
                                  A68      GND                     
                                  A70      GND                     
                                  AA2      IRQ_PIRQA_SPI_TPM_N     
                                  AA4      IRQ_VM_INT_N            
                                  AA9      FM_CPU1_PROCHOT_PCH_N   
                                  AA13     H_CPU1_MEMGHJ_MEMHOT_PCH_N
                                  AA17     FM_PRSNT_2_6_N          
                                  AA20     FM_PRSNT_2_5_N          
                                  AA24     P1V05_PCH_STBY          
                                  AA26     GND                     
                                  AA27     GND                     
                                  AA29     PVNN_PCH_STBY           
                                  AA30     PVNN_PCH_STBY           
                                  AA32     PVNN_PCH_STBY           
                                  AA34     PVNN_PCH_STBY           
                                  AA36     PVNN_PCH_STBY           
                                  AA37     PVNN_PCH_STBY           
                                  AA39     PVNN_PCH_STBY           
                                  AA41     PVNN_PCH_STBY           
                                  AA43     GND                     
                                  AA45     P1V05_PCH_STBY          
                                  AA46     P1V05_PCH_STBY          
                                  AA48     GND                     
                                  AA50     GND                     
                                  AA54     TP_PCH_RSVD32           
                                  AA58     TP_PCH_RSVD2            
                                  AA61     SATA6G_PCH_PCIE_UP_SATA_RXN<7>
                                  AA65     P3E_CPU0_PE1_PCH_R_RXP<15>
                                  AA69     TP_PCH_RSVD51           
                                  AA71     TP_PCH_RSVD52           
                                  AB1      PU_LPC_CLKRUN_N         
                                  AB3      FM_MB_SLOT_ID1          
                                  AB5      GND                     
                                  AB68     GND                     
                                  AB70     GND                     
                                  AB72     GND                     
                                  AC2      PU_LPC_PME_N            
                                  AC4      FM_MB_SLOT_ID2          
                                  AC7      GND                     
                                  AC11     GND                     
                                  AC15     GND                     
                                  AC18     GND                     
                                  AC22     GND                     
                                  AC26     P1V05_PCH_STBY          
                                  AC27     GND                     
                                  AC29     PVNN_PCH_STBY           
                                  AC30     PVNN_PCH_STBY           
                                  AC32     PVNN_PCH_STBY           
                                  AC34     PVNN_PCH_STBY           
                                  AC36     PVNN_PCH_STBY           
                                  AC37     PVNN_PCH_STBY           
                                  AC39     PVNN_PCH_STBY           
                                  AC41     PVNN_PCH_STBY           
                                  AC43     GND                     
                                  AC45     GND                     
                                  AC46     GND                     
                                  AC48     GND                     
                                  AC52     GND                     
                                  AC56     TP_PCH_RSVD1            
                                  AC59     GND                     
                                  AC63     GND                     
                                  AC66     GND                     
                                  AC69     SATA6G_TX_DN<3>         
                                  AC71     SATA6G_TX_DP<3>         
                                  AD1      FM_CPU_BMC_INIT         
                                  AD3      RST_PCH_SYSRST_BTN_OUT_N
                                  AD5      GND                     
                                  AD9      FM_OCP_MEZZB_PRES_N     
                                  AD13     H_CPU0_MEMDEF_MEMHOT_PCH_N
                                  AD17     FM_OCP_MEZZC_PRES_N     
                                  AD20     TP_PCH_GPP_L11          
                                  AD24     P3V3_STBY               
                                  AD50     P1V05_PCH_STBY_VCCA_XTAL
                                  AD54     XDP_PRDY_N              
                                  AD58     GND                     
                                  AD61     SATA6G_PCH_PCIE_UP_SATA_RXP<7>
                                  AD65     GND                     
                                  AD68     GND                     
                                  AD70     SATA6G_TX_DN<2>         
                                  AD72     SATA6G_TX_DP<2>         
                                  AE2      FM_OCP_MEZZA_PRES_N     
                                  AE4      FM_TPM_PRES_N           
                                  AE7      FM_CPU_ERR0_PCH_N       
                                  AE11     FM_PRSNT_2_3_N          
                                  AE15     FM_PRSNT_2_2_N          
                                  AE18     FM_PRSNT_2_1_N          
                                  AE22     GND                     
                                  AE26     P1V8_PCH_STBY           
                                  AE27     P1V05_PCH_STBY          
                                  AE29     GND                     
                                  AE30     PVNN_PCH_STBY           
                                  AE32     PVNN_PCH_STBY           
                                  AE34     PVNN_PCH_STBY           
                                  AE36     PVNN_PCH_STBY           
                                  AE37     PVNN_PCH_STBY           
                                  AE39     PVNN_PCH_STBY           
                                  AE41     PVNN_PCH_STBY           
                                  AE43     GND                     
                                  AE45     P1V05_PCH_STBY_VCCA_PLL1
                                  AE46     P1V05_PCH_STBY_ISCLK_PLL
                                  AE48     GND                     
                                  AE52     GND                     
                                  AE56     GND                     
                                  AE59     GND                     
                                  AE63     GND                     
                                  AE66     GND                     
                                  AE69     SATA6G_TX_DN<1>         
                                  AE71     SATA6G_TX_DP<1>         
                                  AF1      GND                     
                                  AF3      GND                     
                                  AF5      GND                     
                                  AF9      GND                     
                                  AF13     GND                     
                                  AF17     GND                     
                                  AF20     TP_PCH_GPP_L10          
                                  AF24     GND                     
                                  AF50     GND                     
                                  AF54     XDP_PCH_CPU_TCK0        
                                  AF58     A_PCIEUP_RCOMP_N        
                                  AF61     TP_PCH_RSVD0            
                                  AF65     SATA6G_PCH_PCIE_UP_SATA_RXN<4>
                                  AF68     GND                     
                                  AF70     SATA6G_TX_DN<0>         
                                  AF72     SATA6G_TX_DP<0>         
                                  AG7      IRQ_OC_DETECT_N         
                                  AG11     FM_CPU_ERR1_PCH_N       
                                  AG15     TP_PCH_RSVD5            
                                  AG18     FM_INTRUDER_HDR_PCH_N   
                                  AG22     A_PVCCRTC_EXT_CAP       
                                  AG26     GND                     
                                  AG27     P1V8_PCH_STBY           
                                  AG29     P3V3_STBY               
                                  AG30     GND                     
                                  AG32     PVNN_PCH_STBY           
                                  AG34     PVNN_PCH_STBY           
                                  AG36     PVNN_PCH_STBY           
                                  AG37     PVNN_PCH_STBY           
                                  AG39     PVNN_PCH_STBY           
                                  AG41     GND                     
                                  AG43     GND                     
                                  AG45     P1V05_PCH_STBY_ISCLK_PLL
                                  AG46     GND                     
                                  AG48     P1V05_PCH_STBY_VCCA_PLL0
                                  AG52     GND                     
                                  AG56     GND                     
                                  AG59     GND                     
                                  AG63     SATA6G_PCH_PCIE_UP_SATA_RXP<5>
                                  AG66     GND                     
                                  AH2      RMII_BMC_PCH_SPRNGVLLE_RXER_R
                                  AH4      RST_PCIE_PCH_PERST_N    
                                  AH9      JTAG_PCH_PLD_TMS        
                                  AH13     FM_BMC_READY_N          
                                  AH17     FM_BIOS_USB_RECOVERY    
                                  AH20     GND                     
                                  AH24     P3V3_STBY               
                                  AH50     P1V05_PCH_STBY          
                                  AH54     XDP_TMS                 
                                  AH58     A_PCIEUP_RCOMP_P        
                                  AH61     SATA6G_PCH_PCIE_UP_SATA_RXN<5>
                                  AH65     SATA6G_PCH_PCIE_UP_SATA_RXP<4>
                                  AH69     SATA6G_S1_TX_DN         
                                  AH71     SATA6G_S1_TX_DP         
                                  AJ1      CLK_50M_CKMNG_PCH_10GBE 
                                  AJ3      RMII_PCH_SPRNGVLLE_ARB_IN
                                  AJ5      GND                     
                                  AJ7      GND                     
                                  AJ11     GND                     
                                  AJ15     GND                     
                                  AJ18     GND                     
                                  AJ22     GND                     
                                  AJ26     GND                     
                                  AJ27     P3V3_RTC_STBY           
                                  AJ29     P1V05_PCH_STBY          
                                  AJ30     GND                     
                                  AJ32     GND                     
                                  AJ34     GND                     
                                  AJ36     GND                     
                                  AJ37     GND                     
                                  AJ39     GND                     
                                  AJ41     GND                     
                                  AJ43     P1V05_PCH_STBY          
                                  AJ45     GND                     
                                  AJ46     P1V05_PCH_STBY_ISCLK_PLL
                                  AJ48     P1V05_PCH_STBY_ISCLK_PLL
                                  AJ52     GND                     
                                  AJ56     GND                     
                                  AJ59     GND                     
                                  AJ63     SATA6G_PCH_PCIE_UP_SATA_RXP<2>
                                  AJ66     GND                     
                                  AJ68     GND                     
                                  AJ70     SATA6G_S0_TX_DN         
                                  AJ72     SATA6G_S0_TX_DP         
                                  AK2      RMII_BMC_PCH_SPRNGVLLE_TXD1
                                  AK4      RMII_PCH_SPRNGVLLE_ARB_OUT_R
                                  AK9      FM_HSC_TIMER_EXP_N      
                                  AK13     FM_MP_PS_REDUNDANT_LOST_N
                                  AK17     JTAG_PCH_PLD_TDI        
                                  AK20     FM_MP_PS_FAIL_N         
                                  AK24     P1V8_PCH_STBY           
                                  AK26     GND                     
                                  AK27     P1V05_PCH_STBY          
                                  AK29     P1V8_PCH_STBY           
                                  AK30     GND                     
                                  AK32     PVNN_PCH_STBY           
                                  AK34     PVNN_PCH_STBY           
                                  AK36     VSENSE_PVNN_PCH_STBY_FPK
                                  AK37     PVNN_PCH_STBY           
                                  AK39     PVNN_PCH_STBY           
                                  AK41     GND                     
                                  AK43     P1V05_PCH_STBY          
                                  AK45     P1V05_PCH_STBY          
                                  AK46     GND                     
                                  AK48     GND                     
                                  AK50     P1V05_PCH_STBY_WM20_PLL 
                                  AK54     TP_PCH_RSVD36           
                                  AK58     GND                     
                                  AK61     GND                     
                                  AK65     SATA6G_PCH_PCIE_UP_SATA_RXN<2>
                                  AK69     GND                     
                                  AK71     GND                     
                                  AL1      RMII_SPRNGVLLE_BMC_PCH_RXD0_R1
                                  AL3      RMII_BMC_PCH_SPRNGVLLE_TXEN
                                  AL5      GND                     
                                  AL7      SGPIO_PCH_SATA_CLOCK    
                                  AL11     LED_PCH_SSATA_HDD_N     
                                  AL15     FM_MEM_THERM_EVENT_PCH_N
                                  AL18     JTAG_PCH_PLD_TCK        
                                  AL22     GND                     
                                  AL52     GND                     
                                  AL56     XDP_PCH_TCK1            
                                  AL59     GND                     
                                  AL63     SATA6G_PCH_PCIE_UP_SATA_RXP<3>
                                  AL66     SATA6G_PCH_PCIE_UP_SATA_RXN<1>
                                  AL68     GND                     
                                  AL70     GND                     
                                  AL72     GND                     
                                  AM2      RMII_BMC_PCH_SPRNGVLLE_TXD0
                                  AM4      A_1P8_3P3_RCOMP         
                                  AM26     GND                     
                                  AM27     P1V05_PCH_STBY          
                                  AM29     P1V8_PCH_STBY           
                                  AM30     GND                     
                                  AM32     PVNN_PCH_STBY           
                                  AM34     PVNN_PCH_STBY           
                                  AM36     PVNN_PCH_STBY           
                                  AM37     PVNN_PCH_STBY           
                                  AM39     PVNN_PCH_STBY           
                                  AM41     GND                     
                                  AM43     P1V05_PCH_STBY          
                                  AM45     P1V05_PCH_STBY          
                                  AM46     GND                     
                                  AM48     P1V05_PCH_STBY          
                                  AM69     PE_PCH_SPRV_RX_C_DN     
                                  AM71     PE_PCH_SPRV_RX_C_DP     
                                  AN1      RMII_SPRNGVLLE_BMC_PCH_RXD1_R1
                                  AN3      RMII_BMC_PCH_SPRNGVLLE_CRSDV_R1
                                  AN5      GND                     
                                  AN9      GND                     
                                  AN13     GND                     
                                  AN17     GND                     
                                  AN20     GND                     
                                  AN24     P3V3_STBY               
                                  AN50     P1V05_PCH_STBY_WM20_PLL 
                                  AN54     XDP_TDI                 
                                  AN58     GND                     
                                  AN61     SATA6G_PCH_PCIE_UP_SATA_RXP<6>
                                  AN65     SATA6G_PCH_PCIE_UP_SATA_RXP<1>
                                  AN68     GND                     
                                  AN70     P2E_SSB_BMC_RX_C_DN     
                                  AN72     P2E_SSB_BMC_RX_C_DP     
                                  AP2      GND                     
                                  AP4      GND                     
                                  AP7      TP_PCH_GPP_F12          
                                  AP11     SGPIO_PCH_SATA_DOUT0    
                                  AP15     FM_BIOS_TOP_SWAP        
                                  AP18     SGPIO_PCH_SSATA_CLOCK   
                                  AP22     GND                     
                                  AP26     GND                     
                                  AP27     TP_PCH_RSVD58           
                                  AP29     P1V8_PCH_STBY           
                                  AP30     GND                     
                                  AP32     PVNN_PCH_STBY           
                                  AP34     PVNN_PCH_STBY           
                                  AP36     PVNN_PCH_STBY           
                                  AP37     PVNN_PCH_STBY           
                                  AP39     PVNN_PCH_STBY           
                                  AP41     GND                     
                                  AP43     P1V05_PCH_STBY          
                                  AP45     P1V05_PCH_STBY          
                                  AP46     GND                     
                                  AP48     P1V05_PCH_STBY_WM26_PLL 
                                  AP52     GND                     
                                  AP56     XDP_TDO                 
                                  AP59     SATA6G_PCH_PCIE_UP_SATA_RXN<6>
                                  AP63     SATA6G_PCH_PCIE_UP_SATA_RXN<3>
                                  AP66     GND                     
                                  AP69     TP_PCH_RSVD47           
                                  AP71     TP_PCH_RSVD48           
                                  AR1      LED_POSTCODE_1          
                                  AR3      LED_POSTCODE_6          
                                  AR5      GND                     
                                  AR9      SGPIO_PCH_SATA_LOAD     
                                  AR13     FM_FORCE_ADR_N          
                                  AR17     IRQ_PCH_NIC_ALERT_N     
                                  AR20     JTAG_PCH_PLD_TDO        
                                  AR24     P3V3_STBY               
                                  AR50     GND                     
                                  AR54     XDP_ITP_PMODE           
                                  AR58     GND                     
                                  AR61     SATA6G_PCH_PCIE_UP_SATA_RXN<0>
                                  AR65     GND                     
                                  AR68     GND                     
                                  AR70     GND                     
                                  AR72     GND                     
                                  AT2      LED_POSTCODE_2          
                                  AT4      FM_UARTSW_LSB_N         
                                  AT7      GND                     
                                  AT11     GND                     
                                  AT15     GND                     
                                  AT18     GND                     
                                  AT22     GND                     
                                  AT26     GND                     
                                  AT27     TP_PCH_RSVD59           
                                  AT29     P1V8_PCH_STBY           
                                  AT30     GND                     
                                  AT32     PVNN_PCH_STBY           
                                  AT34     PVNN_PCH_STBY           
                                  AT36     PVNN_PCH_STBY           
                                  AT37     GND                     
                                  AT39     P1V05_PCH_STBY          
                                  AT41     GND                     
                                  AT43     P1V05_PCH_STBY          
                                  AT45     P1V05_PCH_STBY          
                                  AT46     GND                     
                                  AT48     P1V05_PCH_STBY          
                                  AT52     FM_CPU_MSMI_LVT3_N      
                                  AT56     XDP_TRST_N              
                                  AT59     GND                     
                                  AT63     SATA6G_PCH_PCIE_UP_SATA_RXP<0>
                                  AT66     SATA6G_RX_DN<3>         
                                  AT69     TP_PCH_RSVD6            
                                  AT71     TP_PCH_RSVD22           
                                  AU9      SMB_LAN_STBY_LVC3_SCL_R2
                                  AU13     FM_IE_DISABLE_N         
                                  AU17     SGPIO_PCH_SSATA_LOAD    
                                  AU20     SMB_LAN_STBY_LVC3_SDA_R2
                                  AU24     P3V3_STBY               
                                  AU26     GND                     
                                  AU27     P3V3_STBY               
                                  AU29     P1V8_PCH_STBY           
                                  AU30     GND                     
                                  AU32     PVNN_PCH_STBY           
                                  AU34     PVNN_PCH_STBY           
                                  AU36     PVNN_PCH_STBY           
                                  AU37     P1V05_PCH_STBY          
                                  AU39     P1V05_PCH_STBY          
                                  AU41     GND                     
                                  AU43     P1V05_PCH_STBY          
                                  AU45     P1V05_PCH_STBY          
                                  AU46     GND                     
                                  AU48     P1V05_PCH_STBY_WM26_PLL 
                                  AU50     GND                     
                                  AU54     GND                     
                                  AU58     IRQ_UV_DETECT_N         
                                  AU61     GND                     
                                  AU65     SATA6G_RX_DP<2>         
                                  AV1      LED_POSTCODE_5          
                                  AV3      LED_POSTCODE_0          
                                  AV5      GND                     
                                  AV7      FM_BOARD_SKU_ID2        
                                  AV11     FAN_PWM_OUT_SYS1        
                                  AV15     FAN_TACH1               
                                  AV18     FM_CPU1_THERMTRIP_LATCH_LVT3_N
                                  AV22     GND                     
                                  AV52     FM_CPU_ERR2_LVT3_N      
                                  AV56     LED_PCH_SATA_HDD_N      
                                  AV59     GND                     
                                  AV63     SATA6G_RX_DN<2>         
                                  AV66     SATA6G_RX_DP<3>         
                                  AV68     GND                     
                                  AV70     P3E_PCH_M2_RX_DP<3>     
                                  AV72     P3E_PCH_M2_RX_DN<3>     
                                  AW2      LED_POSTCODE_4          
                                  AW4      FM_BACKUP_BIOS_SEL_N    
                                  AW9      GND                     
                                  AW13     GND                     
                                  AW17     GND                     
                                  AW20     IRQ_PVCCIN_CPU1_VRHOT_LVC3_N
                                  AW24     P3V3_STBY               
                                  AW26     GND                     
                                  AW27     P1V8_PCH_STBY           
                                  AW29     P1V8_PCH_STBY           
                                  AW30     GND                     
                                  AW32     GND                     
                                  AW34     GND                     
                                  AW36     GND                     
                                  AW37     GND                     
                                  AW39     GND                     
                                  AW41     GND                     
                                  AW43     P1V05_PCH_STBY          
                                  AW45     P1V05_PCH_STBY          
                                  AW46     GND                     
                                  AW48     P1V05_PCH_STBY_WM26_PLL 
                                  AW50     GND                     
                                  AW54     IRQ_BMC_PCH_SMI_LPC_N   
                                  AW58     GND                     
                                  AW61     GND                     
                                  AW65     SATA6G_RX_DN<1>         
                                  AW69     P3E_PCH_M2_RX_DP<2>     
                                  AW71     P3E_PCH_M2_RX_DN<2>     
                                  AY1      SMB_SENSOR_STBY_LVC3_SCL_R1
                                  AY3      LED_POSTCODE_3          
                                  AY5      GND                     
                                  AY7      FAN_TACH3               
                                  AY11     FAN_TACH0               
                                  AY15     FM_THROTTLE_N           
                                  AY18     FM_BOARD_SKU_ID1        
                                  AY22     GND                     
                                  AY52     FM_CPU1_RC_ERROR_N      
                                  AY56     GND                     
                                  AY59     SATA6G_S1_RX_DN         
                                  AY63     GND                     
                                  AY66     SATA6G_RX_DP<1>         
                                  AY68     GND                     
                                  AY70     P3E_PCH_M2_RX_DP<1>     
                                  AY72     P3E_PCH_M2_RX_DN<1>     
                                  B10      TP_PCH_RSVD17           
                                  B12      GND                     
                                  B14      FM_CPU0_RC_ERROR_N      
                                  B16      FM_SLPS4_N              
                                  B19      GND                     
                                  B21      CLK_100M_MEZZ4_DN       
                                  B23      CLK_100M_MEZZ3_DN       
                                  B25      GND                     
                                  B27      GND                     
                                  B29      CLK_100M_BMC_PE_DN      
                                  B31      CLK_100M_MEZZ1_DP       
                                  B33      CLK_100M_PCH_SLOTX24_S4_DP
                                  B35      XTAL_PCH_48M_IN         
                                  B38      TP_CLK_100M_NSSCC1_DN   
                                  B40      TP_CLK_100M_PLAT1_DN    
                                  B42      DMI_CPU0_PCH_TX_C_DP<0> 
                                  B44      DMI_CPU0_PCH_TX_C_DP<2> 
                                  B47      GND                     
                                  B49      P3E_CPU0_PE1_PCH_TXP<1> 
                                  B51      P3E_CPU0_PE1_PCH_TXP<3> 
                                  B53      P3E_CPU0_PE1_PCH_TXP<5> 
                                  B55      P3E_CPU0_PE1_PCH_TXP<7> 
                                  B58      P3E_CPU0_PE1_PCH_C_TXN<9>
                                  B60      P3E_CPU0_PE1_PCH_C_TXP<11>
                                  B62      P3E_CPU0_PE1_PCH_C_TXN<13>
                                  B64      P3E_CPU0_PE1_PCH_C_TXN<15>
                                  BA2      FM_BIOS_SMI_ACTIVE_N    
                                  BA4      SMB_VR_STBY_LVC3_SCL_R1 
                                  BA9      IRQ_PVCCIN_CPU0_VRHOT_LVC3_N
                                  BA13     FM_UARTSW_MSB_N         
                                  BA17     IRQ_FORCE_NM_THROTTLE_N 
                                  BA20     FM_CPU1_FIVR_FAULT_LVT3_N
                                  BA24     P3V3_STBY               
                                  BA26     P3V3_STBY               
                                  BA27     P1V8_PCH_STBY           
                                  BA29     P1V8_PCH_STBY           
                                  BA30     P1V05_PCH_STBY          
                                  BA32     P1V05_PCH_STBY          
                                  BA34     P1V05_PCH_STBY          
                                  BA36     P1V05_PCH_STBY          
                                  BA37     P1V05_PCH_STBY          
                                  BA39     P1V05_PCH_STBY_KR_PLL   
                                  BA41     P1V05_PCH_STBY_KR_PLL   
                                  BA43     P3V3_STBY               
                                  BA45     P3V3_STBY               
                                  BA46     P3V3_STBY               
                                  BA48     P3V3_STBY               
                                  BA50     GND                     
                                  BA54     GND                     
                                  BA58     GND                     
                                  BA61     SATA6G_S1_RX_DP         
                                  BA65     SATA6G_RX_DN<0>         
                                  BA69     P3E_PCH_RX_0_DP         
                                  BA71     P3E_PCH_RX_0_DN         
                                  BB1      FM_FLASH_ATTACH_CFG_STRAP
                                  BB3      PU_ADR_TIMER_HOLD_OFF_N 
                                  BB5      GND                     
                                  BB7      GND                     
                                  BB11     GND                     
                                  BB15     GND                     
                                  BB18     GND                     
                                  BB22     GND                     
                                  BB26     P3V3_STBY               
                                  BB29     A_KR0_RBIAS             
                                  BB33     P1V05_PCH_STBY          
                                  BB37     P1V05_PCH_STBY          
                                  BB40     P1V05_PCH_STBY_KR_PLL   
                                  BB44     GND                     
                                  BB48     GND                     
                                  BB52     IRQ_BMC_PCH_NMI_STBY_N  
                                  BB56     A_PCIE_RCOMP_P          
                                  BB59     GND                     
                                  BB63     SATA6G_S0_RX_DN         
                                  BB66     GND                     
                                  BB68     GND                     
                                  BB70     GND                     
                                  BB72     GND                     
                                  BC2      SMB_SENSOR_STBY_LVC3_SDA_R1
                                  BC4      FM_OC_DETECT_EN_N       
                                  BC69     GND                     
                                  BC71     GND                     
                                  BD1      SMB_VR_STBY_LVC3_SDA_R1 
                                  BD3      FP_PWR_ID_LED_N         
                                  BD5      GND                     
                                  BD9      FM_ADR_COMPLETE_R1      
                                  BD13     FM_BOARD_SKU_ID0        
                                  BD17     FM_BOARD_SKU_ID4        
                                  BD20     FM_CPU0_RC_EN           
                                  BD24     GND                     
                                  BD27     GND                     
                                  BD31     GND                     
                                  BD35     GND                     
                                  BD38     P1V05_PCH_STBY_KR_PLL   
                                  BD42     A_KR1_RBIAS             
                                  BD46     P1V8_PCH_STBY           
                                  BD50     GND                     
                                  BD54     GND                     
                                  BD58     A_PCIE_RCOMP_N          
                                  BD61     SATA6G_S0_RX_DP         
                                  BD65     SATA6G_RX_DP<0>         
                                  BD68     GND                     
                                  BD70     TP_USB3_P06_RXP         
                                  BD72     TP_USB3_P06_RXN         
                                  BE2      LED_POSTCODE_7          
                                  BE4      SMB_LAN_STBY_LVC3_SDA_R1
                                  BE7      FM_NMI_EVENT_N          
                                  BE11     FM_CPU0_FIVR_FAULT_LVT3_N
                                  BE15     FM_BIOS_SMI_ACTIVE_N    
                                  BE18     FM_BOARD_SKU_ID3        
                                  BE22     FAN_TACH2               
                                  BE26     P3V3_STBY               
                                  BE29     GND                     
                                  BE33     GND                     
                                  BE37     GND                     
                                  BE40     P3V3_STBY               
                                  BE44     P3V3_STBY               
                                  BE48     P1V05_PCH_STBY          
                                  BE52     FM_CPLD_ADR_TRIGGER_R_N 
                                  BE56     GND                     
                                  BE59     GND                     
                                  BE63     GND                     
                                  BE66     GND                     
                                  BE69     TP_USB3_P05_RXP         
                                  BE71     TP_USB3_P05_RXN         
                                  BF1      SMB_LAN_STBY_LVC3_SCL_R1
                                  BF3      FM_BMC_NMI_N            
                                  BF5      GND                     
                                  BF9      GND                     
                                  BF13     GND                     
                                  BF17     GND                     
                                  BF20     GND                     
                                  BF24     GND                     
                                  BF27     GND                     
                                  BF31     KR_P0_OCP_RX_C_DP       
                                  BF35     KR_P3_OCP_RX_C_DN       
                                  BF38     GND                     
                                  BF42     GND                     
                                  BF46     P1V05_PCH_STBY          
                                  BF50     GND                     
                                  BF54     GND                     
                                  BF58     GND                     
                                  BF61     GND                     
                                  BF65     GND                     
                                  BF68     GND                     
                                  BF70     TP_USB3_P04_RXP         
                                  BF72     TP_USB3_P04_RXN         
                                  BG7      FM_SOL_UART_CH_SEL      
                                  BG11     FAN_PWM_OUT_SYS0        
                                  BG15     FM_PCH_PWRBTN_OUT_N     
                                  BG18     IRQ_PVDDQ_GHJ_VRHOT_LVT3_N
                                  BG22     IRQ_PCH_NIC_ALERT_N     
                                  BG26     TP_PCH_RSVD27           
                                  BG29     KR_P1_OCP_RX_C_DN       
                                  BG33     GND                     
                                  BG37     KR_P2_OCP_RX_C_DP       
                                  BG40     TP_PCH_RSVD42           
                                  BG44     GND                     
                                  BG48     GND                     
                                  BG52     FM_POST_CARD_PRES_BMC_N 
                                  BG56     TP_USB3_P04_TXP         
                                  BG59     GND                     
                                  BG63     GND                     
                                  BG66     P2E_SSB_BMC_TX_DN       
                                  BH2      FM_PCH_BMC_THERMTRIP_N  
                                  BH4      FM_SSATA_PCIE_M2_SEL    
                                  BH9      VID_PCH_CORE_PVNN_AUX_VID_1
                                  BH13     FM_BIOS_TOP_SWAP_SPKR   
                                  BH17     FM_FAST_PROCHOT_EN_N    
                                  BH20     FM_PWR_BTN_N            
                                  BH24     TP_PCH_RSVD26           
                                  BH27     GND                     
                                  BH31     KR_P0_OCP_RX_C_DN       
                                  BH35     KR_P3_OCP_RX_C_DP       
                                  BH38     GND                     
                                  BH42     GND                     
                                  BH46     GND                     
                                  BH50     FM_CPU0_RC_ERROR_N      
                                  BH54     GND                     
                                  BH58     TP_USB3_P04_TXN         
                                  BH61     P3E_PCH_M2_TX_DN<3>     
                                  BH65     PE_PCH_SPRV_TX_DN       
                                  BH69     TP_USB3_P03_RXP         
                                  BH71     TP_USB3_P03_RXN         
                                  BJ1      GND                     
                                  BJ3      GND                     
                                  BJ5      GND                     
                                  BJ7      GND                     
                                  BJ11     GND                     
                                  BJ15     GND                     
                                  BJ18     GND                     
                                  BJ22     FM_BIOS_POST_CMPLT_N    
                                  BJ26     GND                     
                                  BJ29     KR_P1_OCP_RX_C_DP       
                                  BJ33     GND                     
                                  BJ37     KR_P2_OCP_RX_C_DN       
                                  BJ40     TP_PCH_RSVD41           
                                  BJ44     IRQ_HSC_FAULT_N         
                                  BJ48     FM_ADR_SMI_GPIO_N       
                                  BJ52     GND                     
                                  BJ56     TP_USB3_P02_TXP         
                                  BJ59     TP_USB3_P05_TXP         
                                  BJ63     PE_PCH_SPRV_TX_DP       
                                  BJ66     P2E_SSB_BMC_TX_DP       
                                  BJ68     GND                     
                                  BJ70     TP_USB3_P02_RXP         
                                  BJ72     TP_USB3_P02_RXN         
                                  BK2      LED_GBE_P1_1            
                                  BK4      LED_GBE_P0_1            
                                  BK9      FM_PMBUS_ALERT_BUF_EN_N 
                                  BK13     FM_UART_ALERT_N         
                                  BK17     IRQ_PVDDQ_DEF_VRHOT_LVT3_N
                                  BK20     FM_BIOS_PREFRB2_GOOD    
                                  BK24     GND                     
                                  BK27     GND                     
                                  BK31     GND                     
                                  BK35     GND                     
                                  BK38     GND                     
                                  BK42     GND                     
                                  BK46     FM_PWR_LED_N            
                                  BK50     GND                     
                                  BK54     USB3_P01_TXP            
                                  BK58     TP_USB3_P05_TXN         
                                  BK61     P3E_PCH_M2_TX_DP<3>     
                                  BK65     P3E_PCH_M2_TX_DN<2>     
                                  BK69     USB3_P01_RXP            
                                  BK71     USB3_P01_RXN            
                                  BL1      LED_GBE_P0_0            
                                  BL3      LED_GBE_P2_0            
                                  BL5      GND                     
                                  BL7      VID_PCH_CORE_PVNN_AUX_VID_0
                                  BL11     RST_SYSTEM_BTN_N        
                                  BL15     FM_UV_ADR_TRIGGER_EN    
                                  BL18     FM_GLOBAL_RST_WARN_N    
                                  BL22     GND                     
                                  BL26     TP_10GBE_KR0_MON_DN     
                                  BL29     TP_PCH_RSVD38           
                                  BL33     TP_10GBE_KR1_MON_DN     
                                  BL37     GND                     
                                  BL40     GND                     
                                  BL44     SMB_SLOTX24_STBY_LVC3_SDA_R1
                                  BL48     FM_OC0_USB_N            
                                  BL52     USB3_P01_TXN            
                                  BL56     TP_USB3_P02_TXN         
                                  BL59     TP_USB3_P06_TXN         
                                  BL63     GND                     
                                  BL66     P3E_PCH_M2_TX_DP<2>     
                                  BL68     GND                     
                                  BL70     GND                     
                                  BL72     GND                     
                                  BM2      LED_GBE_P3_1            
                                  BM4      SMB_PCH_MEZZ_LOM0_SCL   
                                  BM9      GND                     
                                  BM13     GND                     
                                  BM17     GND                     
                                  BM20     FM_PCH_BMC_THERMTRIP_EXI_STRAP_
                                  BM24     KR_P1_OCP_TX_DN         
                                  BM27     KR_P0_OCP_TX_DN         
                                  BM31     KR_P3_OCP_TX_DP         
                                  BM35     KR_P2_OCP_TX_DN         
                                  BM38     FM_BMC_ENABLE_N         
                                  BM42     FM_PCH_PLD_DATA_R       
                                  BM46     GND                     
                                  BM50     GND                     
                                  BM54     TP_USB3_P03_TXN         
                                  BM58     GND                     
                                  BM61     TP_USB3_P06_TXP         
                                  BM65     P3E_PCH_M2_TX_DN<1>     
                                  BM69     GND                     
                                  BM71     GND                     
                                  BN1      GND                     
                                  BN3      SMB_PCH_MEZZ_LOM0_SDA   
                                  BN5      GND                     
                                  BN7      IRQ_PVDDQ_ABC_VRHOT_LVT3_N
                                  BN11     FP_NMI_BTN_N            
                                  BN15     PU_IRQ_VRALERT_N        
                                  BN18     RST_PLTRST_N            
                                  BN22     GND                     
                                  BN26     TP_10GBE_KR0_MON_DP     
                                  BN29     TP_PCH_RSVD37           
                                  BN33     TP_10GBE_KR1_MON_DP     
                                  BN37     GND                     
                                  BN40     TP_PCH_GPP_D12          
                                  BN44     FM_CPU0_THERMTRIP_LATCH_LVT3_N
                                  BN48     IRQ_BMC_PCH_SCI_LPC_N   
                                  BN52     GND                     
                                  BN56     TP_USB3_P03_TXP         
                                  BN59     GND                     
                                  BN63     P3E_PCH_TX_0_DP         
                                  BN66     GND                     
                                  BN68     TP_PCH_RSVD55           
                                  BN70     A_USB2_COMP             
                                  BN72     GND                     
                                  BP4      LED_GBE_P1_0            
                                  BP69     GND                     
                                  BR1      GND                     
                                  BR3      GND                     
                                  BR6      GND                     
                                  BR9      FM_QAT_EN_N             
                                  BR13     IRQ_PVDDQ_KLM_VRHOT_LVT3_N
                                  BR17     FM_USB_P0_EN_BOOT_BIOS_STRAP_N
                                  BR20     GND                     
                                  BR24     KR_P1_OCP_TX_DP         
                                  BR27     KR_P0_OCP_TX_DP         
                                  BR31     KR_P3_OCP_TX_DN         
                                  BR35     KR_P2_OCP_TX_DP         
                                  BR38     FM_BMC_FAULT_LED_N      
                                  BR42     IRQ_BMC_PCH_NMI_STBY_R_N
                                  BR46     SP2_BMC_CM_UART_TX      
                                  BR50     GND                     
                                  BR54     GND                     
                                  BR58     GND                     
                                  BR61     P3E_PCH_TX_0_DN         
                                  BR65     P3E_PCH_M2_TX_DP<1>     
                                  BR67     A_USB2_VBUS             
                                  BR70     GND                     
                                  BR72     GND                     
                                  BT5      SMB_PCH_MEZZ_LOM2_SCL   
                                  BT8      GND                     
                                  BT66     GND                     
                                  BT69     GND                     
                                  BU1      GND                     
                                  BU3      GND                     
                                  BU6      LED_GBE_P2_1            
                                  BU9      GND                     
                                  BU11     GND                     
                                  BU13     GND                     
                                  BU15     GND                     
                                  BU18     GND                     
                                  BU20     GND                     
                                  BU22     GND                     
                                  BU24     GND                     
                                  BU26     GND                     
                                  BU28     GND                     
                                  BU30     GND                     
                                  BU32     GND                     
                                  BU34     GND                     
                                  BU37     GND                     
                                  BU39     GND                     
                                  BU41     GND                     
                                  BU43     GND                     
                                  BU45     GND                     
                                  BU48     GND                     
                                  BU50     GND                     
                                  BU52     GND                     
                                  BU54     GND                     
                                  BU57     GND                     
                                  BU59     GND                     
                                  BU61     GND                     
                                  BU63     GND                     
                                  BU65     TP_USB2_P10_DP          
                                  BU67     TP_USB2_P14_DP          
                                  BU70     GND                     
                                  BU72     GND                     
                                  BV8      SMB_PCH_MEZZ_LOM1_SDA   
                                  BV10     FM_GBE0_LVC3_MOD_ABS    
                                  BV12     TP_PCH_GPP_J21          
                                  BV14     TP_PCH_GPP_J23          
                                  BV16     XTAL_KR_25M_IN          
                                  BV19     RST_BMC_SYSRST_BTN_OUT_B_N
                                  BV21     JTAG_PCH_GBE_CLK        
                                  BV23     FM_CPU1_RC_ERROR_N      
                                  BV25     FM_BIOS_MRC_DEBUG_MSG_DIS_N
                                  BV27     SMB_HOST_STBY_LVC3_SDA_R1
                                  BV29     SMB_SMLINK0_STBY_LVC3_SCL_R1
                                  BV31     FM_PCH_SATA_RAID_KEY    
                                  BV33     FM_BOARD_REV_ID2        
                                  BV35     SMB_PMBUS_BMC_STBY_LVC3_SDA_R1
                                  BV38     FM_BOARD_REV_ID1        
                                  BV40     GND                     
                                  BV42     IRQ_OOB_MGMT_RISER_ALERT_N
                                  BV44     SP2_BMC_CM_UART_RX      
                                  BV47     H_CPU0_FAST_WAKE_LVT3_N 
                                  BV49     GND                     
                                  BV51     TP_CLK_24M_PMSYNC2      
                                  BV53     TP_USB2_P13_DP          
                                  BV55     TP_USB2_P9_DP           
                                  BV58     USB2_PCH_BMC_P5_DP      
                                  BV60     USB2_P01_DP             
                                  BV62     USB_PCH_BMC_P4_DP       
                                  BV64     TP_USB2_P8_DP           
                                  BV66     TP_USB2_P12_DP          
                                  BW1      GND                     
                                  BW3      TP_PCH_RSVD46           
                                  BW5      SMB_PCH_MEZZ_LOM1_SCL   
                                  BW6      SMB_PCH_MEZZ_LOM3_SCL   
                                  BW9      SMB_PCH_MEZZ_LOM3_SDA   
                                  BW11     SMB_PCH_MEZZ_LOM2_SDA   
                                  BW13     FM_GBE2_LVC3_MOD_ABS    
                                  BW15     GND                     
                                  BW18     GND                     
                                  BW20     IRQ_DIMM_SAVE_LVT3_N    
                                  BW22     PU_10GBE_LOM_PCI_DISABLE_N
                                  BW24     IRQ_BOARD_BMC_ALERT_N   
                                  BW26     GND                     
                                  BW28     SMB_HOST_STBY_LVC3_SCL_R1
                                  BW30     SMB_SMLINK0_STBY_LVC3_SDA_R1
                                  BW32     FM_PASSWORD_CLEAR_N     
                                  BW34     IRQ_SML0_ALERT_N        
                                  BW37     FM_SLT_CFG1             
                                  BW39     FM_BB_BMC_MP_GPIO       
                                  BW41     FM_CPLD_BMC_PWRDN_N     
                                  BW43     SGPIO_PCH_SSATA_DOUT0   
                                  BW45     IRQ_MEZZ_LAN_ALERT_N    
                                  BW48     FM_XRC_PRESENT_N        
                                  BW50     CLK_48M_USB_BMC         
                                  BW52     GND                     
                                  BW54     TP_USB2_P11_DP          
                                  BW57     TP_USB2_P07_DP          
                                  BW59     TP_USB2_P03_DP          
                                  BW61     TP_USB2_P02_DP          
                                  BW63     TP_USB2_P06_DP          
                                  BW65     TP_USB2_P10_DN          
                                  BW67     TP_USB2_P12_DN          
                                  BW68     TP_USB2_P14_DN          
                                  BW70     GND                     
                                  BW72     GND                     
                                  BY10     FM_GBE1_LVC3_MOD_ABS    
                                  BY12     FM_GBE3_LVC3_MOD_ABS    
                                  BY14     TP_PCH_GPP_J19          
                                  BY16     XTAL_KR_25M_OUT         
                                  BY19     PWRGD_SYS_PWROK         
                                  BY21     FM_10GBE_LOM_DISABLE_N  
                                  BY23     JTAG_PCH_GBE_TDI        
                                  BY25     A_RCOMP_3P3             
                                  BY27     PU_PCH_TLS_ENABLE_STRAP 
                                  BY29     FM_CPU1_RC_EN           
                                  BY31     FM_SLT_CFG2_R           
                                  BY33     FM_BIOS_POST_CMPLT_N    
                                  BY35     FM_PMBUS_ALERT_BUF_EN_N 
                                  BY38     IRQ_BMC_PCH_SCI_LPC_N   
                                  BY40     GND                     
                                  BY42     IRQ_FORCE_NM_THROTTLE_N 
                                  BY44     SMB_SLOTX24_STBY_LVC3_SCL_R1
                                  BY47     IRQ_LOM_ALERT_N         
                                  BY49     GND                     
                                  BY51     H_PMSYNC_CLK_24M_R      
                                  BY53     TP_USB2_P13_DN          
                                  BY55     TP_USB2_P9_DN           
                                  BY58     USB2_PCH_BMC_P5_DN      
                                  BY60     USB2_P01_DN             
                                  BY62     USB_PCH_BMC_P4_DN       
                                  BY64     TP_USB2_P8_DN           
                                  C3       GND                     
                                  C5       TP_PCH_RSVD16           
                                  C6       TP_PCH_RSVD15           
                                  C9       TP_PCH_RSVD19           
                                  C11      TP_PCH_RSVD18           
                                  C13      IRQ_SML1_PMBUS_ALERT_N  
                                  C15      FM_PCH_PWRBTN_N         
                                  C18      FM_SINT_PRSNT_N         
                                  C20      CLK_100M_SPRV_DN        
                                  C22      GND                     
                                  C24      TP_CLK_100M_SRC13_DN    
                                  C26      TP_PCH_RSVD64           
                                  C28      CLK_100M_PCH_SLOTX24_S2_DP
                                  C30      GND                     
                                  C32      TP_CLK_100M_NSSCC0_DP   
                                  C34      GND                     
                                  C37      GND                     
                                  C39      CLK_100M_PCH_XDP_DP     
                                  C41      GND                     
                                  C43      DMI_CPU0_PCH_TX_C_DN<1> 
                                  C45      DMI_CPU0_PCH_TX_C_DN<3> 
                                  C48      P3E_CPU0_PE1_PCH_TXN<0> 
                                  C50      P3E_CPU0_PE1_PCH_TXN<2> 
                                  C52      P3E_CPU0_PE1_PCH_TXN<4> 
                                  C54      P3E_CPU0_PE1_PCH_TXN<6> 
                                  C57      P3E_CPU0_PE1_PCH_C_TXP<8>
                                  C59      P3E_CPU0_PE1_PCH_C_TXP<10>
                                  C61      P3E_CPU0_PE1_PCH_C_TXP<12>
                                  C63      P3E_CPU0_PE1_PCH_C_TXP<14>
                                  C65      GND                     
                                  C67      TP_PCH_RSVD13           
                                  C68      TP_PCH_RSVD12           
                                  C70      FM_PCH_PRSNT_N          
                                  C72      GND                     
                                  CA3      GND                     
                                  CA5      GND                     
                                  CA7      GND                     
                                  CA9      GND                     
                                  CA11     TP_PCH_GPP_J17          
                                  CA13     LED_GBE_P3_0            
                                  CA15     GND                     
                                  CA18     GND                     
                                  CA20     JTAG_PCH_GBE_TDO        
                                  CA22     JTAG_PCH_GBE_TMS        
                                  CA24     JTAG_PCH_GBE_TRST_N     
                                  CA26     GND                     
                                  CA28     SMB_PMBUS_BMC_STBY_LVC3_SCL_R1
                                  CA30     FM_BOARD_REV_ID0        
                                  CA32     FM_SLT_CFG0             
                                  CA34     IRQ_BMC_PCH_SMI_LPC_N   
                                  CA37     FM_CPU_CATERR_DLY_LVT3_R_N
                                  CA39     FM_THROTTLE_N           
                                  CA41     FM_XRC_READY_N          
                                  CA43     FM_ADR_MODE_SEL_R       
                                  CA45     FM_BMC_CPLD_GPO         
                                  CA48     FM_BMC_HEARTBEAT_N      
                                  CA50     GND                     
                                  CA52     GND                     
                                  CA54     TP_USB2_P11_DN          
                                  CA57     TP_USB2_P07_DN          
                                  CA59     TP_USB2_P03_DN          
                                  CA61     TP_USB2_P02_DN          
                                  CA63     TP_USB2_P06_DN          
                                  CA65     GND                     
                                  CA66     GND                     
                                  CA68     GND                     
                                  CA70     GND                     
                                  D8       FM_WBG_PRSNT_N          
                                  D10      TP_PCH_RSVD20           
                                  D12      GND                     
                                  D14      FM_SLPS3_N              
                                  D16      GND                     
                                  D19      GND                     
                                  D21      CLK_100M_MEZZ4_DP       
                                  D23      CLK_100M_MEZZ3_DP       
                                  D25      GND                     
                                  D27      GND                     
                                  D29      CLK_100M_BMC_PE_DP      
                                  D31      CLK_100M_MEZZ1_DN       
                                  D33      CLK_100M_PCH_SLOTX24_S4_DN
                                  D35      XTAL_PCH_48M_OUT        
                                  D38      TP_CLK_100M_NSSCC1_DP   
                                  D40      TP_CLK_100M_PLAT1_DP    
                                  D42      DMI_CPU0_PCH_TX_C_DN<0> 
                                  D44      DMI_CPU0_PCH_TX_C_DN<2> 
                                  D47      GND                     
                                  D49      P3E_CPU0_PE1_PCH_TXN<1> 
                                  D51      P3E_CPU0_PE1_PCH_TXN<3> 
                                  D53      P3E_CPU0_PE1_PCH_TXN<5> 
                                  D55      P3E_CPU0_PE1_PCH_TXN<7> 
                                  D58      P3E_CPU0_PE1_PCH_C_TXP<9>
                                  D60      P3E_CPU0_PE1_PCH_C_TXN<11>
                                  D62      P3E_CPU0_PE1_PCH_C_TXP<13>
                                  D64      P3E_CPU0_PE1_PCH_C_TXP<15>
                                  D66      A_EXTCLKN               
                                  E1       GND                     
                                  E3       GND                     
                                  E6       GND                     
                                  E9       GND                     
                                  E11      GND                     
                                  E13      GND                     
                                  E15      GND                     
                                  E18      TP_PCH_RSVD14           
                                  E20      GND                     
                                  E22      GND                     
                                  E24      GND                     
                                  E26      GND                     
                                  E28      GND                     
                                  E30      GND                     
                                  E32      GND                     
                                  E34      GND                     
                                  E37      GND                     
                                  E39      GND                     
                                  E41      GND                     
                                  E43      GND                     
                                  E45      GND                     
                                  E48      GND                     
                                  E50      GND                     
                                  E52      GND                     
                                  E54      GND                     
                                  E57      GND                     
                                  E59      GND                     
                                  E61      GND                     
                                  E63      GND                     
                                  E65      GND                     
                                  E67      A_EXTCLKP               
                                  E70      GND                     
                                  E72      GND                     
                                  F3       GND                     
                                  F5       SPI_PCH_IO2             
                                  F8       TP_PCH_RSVD7            
                                  F66      TP_PCH_RSVD9            
                                  F69      TP_PCH_RSVD8            
                                  F70      GND                     
                                  G1       GND                     
                                  G6       GND                     
                                  G7       TP_SPI_PCH_CS1_R1_N     
                                  G11      FM_CPU0_SKTOCC_LVT3_N   
                                  G15      XDP_PCH_PWR_DEBUG_N     
                                  G18      RST_SRTCRST_N           
                                  G22      GND                     
                                  G26      CLK_100M_MEZZ2_DP       
                                  G29      GND                     
                                  G33      CLK_100M_PCH_SLOTX24_S0_DP
                                  G37      GND                     
                                  G40      CLK_100M_PCH_SLOTX24_S3_DP
                                  G44      A_PCH_XCLK_BIASREF      
                                  G48      GND                     
                                  G52      P3E_CPU0_PE1_PCH_RXP<0> 
                                  G56      P3E_CPU0_PE1_PCH_RXP<2> 
                                  G59      GND                     
                                  G63      GND                     
                                  G66      GND                     
                                  G67      TP_PCH_RSVD49           
                                  G72      GND                     
                                  H4       SPI_PCH_MOSI_R          
                                  H9       FM_BATTERY_SENSE_EN_N   
                                  H13      FM_CPU1_SKTOCC_LVT3_N   
                                  H17      XTAL_33K_RTC2           
                                  H20      TP_PCH_HDA_SYNC         
                                  H24      TP_CLK_100M_SRC12_DP    
                                  H27      CLK_100M_M2_DP          
                                  H31      CLK_100M_PCH_SLOTX24_S5_DN
                                  H35      CLK_100M_DB1200_DP      
                                  H38      CLK_100M_AIRMAX8_PE1_DP 
                                  H42      CLK_100M_PCH_SLOTX24_S1_DP
                                  H46      DMI_CPU0_PCH_RX_DN<0>   
                                  H50      DMI_CPU0_PCH_RX_DP<1>   
                                  H54      P3E_CPU0_PE1_PCH_RXN<2> 
                                  H58      GND                     
                                  H61      P3E_CPU0_PE1_PCH_RXN<6> 
                                  H65      GND                     
                                  H69      TP_PCH_RSVD50           
                                  J1       GND                     
                                  J3       SPI_PCH_CS0_R_N         
                                  J5       GND                     
                                  J7       GND                     
                                  J11      GND                     
                                  J15      GND                     
                                  J18      GND                     
                                  J22      GND                     
                                  J26      CLK_100M_MEZZ2_DN       
                                  J29      GND                     
                                  J33      CLK_100M_PCH_SLOTX24_S0_DN
                                  J37      GND                     
                                  J40      CLK_100M_PCH_SLOTX24_S3_DN
                                  J44      GND                     
                                  J48      DMI_CPU0_PCH_RX_DN<1>   
                                  J52      P3E_CPU0_PE1_PCH_RXN<0> 
                                  J56      P3E_CPU0_PE1_PCH_RXN<3> 
                                  J59      GND                     
                                  J63      P3E_CPU0_PE1_PCH_RXP<6> 
                                  J66      P3E_CPU0_PE1_PCH_R_RXN<9>
                                  J68      GND                     
                                  J70      GND                     
                                  J72      GND                     
                                  K2       SPI_PCH_CLK             
                                  K4       SPI_PCH_TPM_CS_N        
                                  K9       IRQ_LVC3_WAKE_N         
                                  K13      PWRGD_DSW_PWROK         
                                  K17      XTAL_33K_RTC1           
                                  K20      TP_PCH_HDA_SDI_0        
                                  K24      TP_CLK_100M_SRC12_DN    
                                  K27      CLK_100M_M2_DN          
                                  K31      CLK_100M_PCH_SLOTX24_S5_DP
                                  K35      CLK_100M_DB1200_DN      
                                  K38      CLK_100M_AIRMAX8_PE1_DN 
                                  K42      CLK_100M_PCH_SLOTX24_S1_DN
                                  K46      DMI_CPU0_PCH_RX_DP<0>   
                                  K50      DMI_CPU0_PCH_RX_DN<2>   
                                  K54      GND                     
                                  K58      P3E_CPU0_PE1_PCH_RXP<3> 
                                  K61      P3E_CPU0_PE1_PCH_RXP<5> 
                                  K65      P3E_CPU0_PE1_PCH_R_RXN<8>
                                  K69      GND                     
                                  K71      GND                     
                                  L1       SPI_PCH_IO3             
                                  L3       SPI_PCH_MISO            
                                  L5       GND                     
                                  L68      GND                     
                                  L70      SATA6G_PCH_PCIE_UP_SATA_TXN<7>
                                  L72      SATA6G_PCH_PCIE_UP_SATA_TXP<7>
                                  M2       GND                     
                                  M4       GND                     
                                  M7       TP_CPU_PCH_TRIGGER_IN   
                                  M11      RST_BMC_SRST_R_N        
                                  M15      TP_SLP_LAN_N            
                                  M18      TP_PCH_HSA_RST_N        
                                  M22      GND                     
                                  M26      GND                     
                                  M29      GND                     
                                  M33      GND                     
                                  M37      GND                     
                                  M40      GND                     
                                  M44      GND                     
                                  M48      GND                     
                                  M52      DMI_CPU0_PCH_RX_DP<2>   
                                  M56      P3E_CPU0_PE1_PCH_RXP<1> 
                                  M59      P3E_CPU0_PE1_PCH_RXP<4> 
                                  M63      P3E_CPU0_PE1_PCH_R_RXP<8>
                                  M66      P3E_CPU0_PE1_PCH_R_RXP<9>
                                  M69      SATA6G_PCH_PCIE_UP_SATA_TXN<6>
                                  M71      SATA6G_PCH_PCIE_UP_SATA_TXP<6>
                                  N1       LPC_LAD1_IO1            
                                  N3       PU_FM_RCIN_N            
                                  N5       GND                     
                                  N9       GND                     
                                  N13      GND                     
                                  N17      GND                     
                                  N20      GND                     
                                  N24      GND                     
                                  N27      GND                     
                                  N31      GND                     
                                  N35      GND                     
                                  N38      GND                     
                                  N42      GND                     
                                  N46      GND                     
                                  N50      GND                     
                                  N54      DMI_CPU0_PCH_RX_DP<3>   
                                  N58      P3E_CPU0_PE1_PCH_RXN<4> 
                                  N61      P3E_CPU0_PE1_PCH_RXN<5> 
                                  N65      P3E_CPU0_PE1_PCH_R_RXN<10>
                                  N68      GND                     
                                  N70      SATA6G_PCH_PCIE_UP_SATA_TXN<5>
                                  N72      SATA6G_PCH_PCIE_UP_SATA_TXP<5>
                                  P2       IRQ_LPC_SERIRQ_N        
                                  P4       LPC_LFRAME_N_CS0_N      
                                  P7       FM_SLP_SUS_N            
                                  P11      RST_RTCRST_N            
                                  P15      RST_RSMRST_N            
                                  P18      TP_PCH_HDA_BCLK         
                                  P22      TP_PCH_RSVD45           
                                  P26      TP_PCH_RSVD53           
                                  P29      TP_PCH_RSVD31           
                                  P33      TP_PCH_RSVD29           
                                  P37      TP_PCH_RSVD4            
                                  P40      TP_PCH_RSVD23           
                                  P44      TP_PCH_RSVD24           
                                  P48      TP_PCH_RSVD25           
                                  P52      DMI_CPU0_PCH_RX_DN<3>   
                                  P56      P3E_CPU0_PE1_PCH_RXN<1> 
                                  P59      P3E_CPU0_PE1_PCH_RXN<7> 
                                  P63      GND                     
                                  P66      P3E_CPU0_PE1_PCH_R_RXP<10>
                                  P69      SATA6G_PCH_PCIE_UP_SATA_TXN<4>
                                  P71      SATA6G_PCH_PCIE_UP_SATA_TXP<4>
                                  R1       PU_IRQ_PCH_SCI_WHEA_N   
                                  R3       CLK_24M_BMC_LPC_R       
                                  R5       GND                     
                                  R9       PWRGD_CPUPWRGD_GTL      
                                  R13      TP_CPU_PCH_TRIGGER_OUT  
                                  R17      PWRGD_PCH_PWROK         
                                  R20      TP_PCH_DISPA_SDI        
                                  R24      TP_PCH_RSVD54           
                                  R27      GND                     
                                  R31      TP_PCH_RSVD30           
                                  R35      TP_PCH_RSVD28           
                                  R38      GND                     
                                  R42      P1V05_PCH_STBY          
                                  R46      P1V05_PCH_STBY          
                                  R50      GND                     
                                  R54      GND                     
                                  R58      GND                     
                                  R61      P3E_CPU0_PE1_PCH_RXP<7> 
                                  R65      P3E_CPU0_PE1_PCH_R_RXN<12>
                                  R68      GND                     
                                  R70      SATA6G_PCH_PCIE_UP_SATA_TXN<3>
                                  R72      SATA6G_PCH_PCIE_UP_SATA_TXP<3>
                                  T2       FM_UART_PRES_N          
                                  T4       FM_MB_SLOT_ID0          
                                  T7       GND                     
                                  T11      GND                     
                                  T15      GND                     
                                  T18      GND                     
                                  T22      GND                     
                                  T26      GND                     
                                  T29      GND                     
                                  T33      GND                     
                                  T37      GND                     
                                  T40      GND                     
                                  T44      P1V05_PCH_STBY          
                                  T48      GND                     
                                  T52      GND                     
                                  T56      GND                     
                                  T59      P3E_CPU0_PE1_PCH_R_RXN<11>
                                  T63      P3E_CPU0_PE1_PCH_R_RXN<13>
                                  T66      GND                     
                                  T69      SATA6G_PCH_PCIE_UP_SATA_TXN<2>
                                  T71      SATA6G_PCH_PCIE_UP_SATA_TXP<2>
                                  U9       PECI_PCH                
                                  U13      H_PM_SYNC1_GTL_R        
                                  U17      TP_PLTRST_CPU_N         
                                  U20      TP_PCH_DISPA_BCLK       
                                  U24      FM_FLASH_DESC_OVERRIDE  
                                  U27      PVNN_PCH_STBY           
                                  U31      PVNN_PCH_STBY           
                                  U35      PVNN_PCH_STBY           
                                  U38      PVNN_PCH_STBY           
                                  U42      GND                     
                                  U46      P1V05_PCH_STBY          
                                  U50      P1V05_PCH_STBY          
                                  U54      XDP_PREQ_N              
                                  U58      GND                     
                                  U61      P3E_CPU0_PE1_PCH_R_RXP<13>
                                  U65      P3E_CPU0_PE1_PCH_R_RXP<12>
                                  V1       FM_BMC_READY_N          
                                  V3       FM_ME_RECOVER_N         
                                  V5       GND                     
                                  V7       TP_PM_SYNC_GTL          
                                  V11      TP_PCH_RSVD3            
                                  V15      FM_PCH_LVC1_THERMTRIP_N 
                                  V18      TP_PCH_HDA_SDI_1        
                                  V22      TP_PCH_DISPA_SDO        
                                  V26      GND                     
                                  V29      PVNN_PCH_STBY           
                                  V33      PVNN_PCH_STBY           
                                  V37      VSENSE_PVNN_PCH_STBY_QAT
                                  V40      PVNN_PCH_STBY           
                                  V44      P1V05_PCH_STBY          
                                  V48      GND                     
                                  V52      GND                     
                                  V56      TP_PCH_RSVD33           
                                  V59      P3E_CPU0_PE1_PCH_R_RXP<11>
                                  V63      P3E_CPU0_PE1_PCH_R_RXP<14>
                                  V66      GND                     
                                  V68      GND                     
                                  V70      SATA6G_PCH_PCIE_UP_SATA_TXN<1>
                                  V72      SATA6G_PCH_PCIE_UP_SATA_TXP<1>
                                  W2       LPC_LAD2_IO2            
                                  W4       FM_POST_CARD_PRES_BMC_N 
                                  W9       GND                     
                                  W13      GND                     
                                  W17      GND                     
                                  W20      GND                     
                                  W24      GND                     
                                  W50      P1V05_PCH_STBY_ISCLK_PLL
                                  W54      TP_PCH_RSVD35           
                                  W58      GND                     
                                  W61      GND                     
                                  W65      P3E_CPU0_PE1_PCH_R_RXN<14>
                                  W69      SATA6G_PCH_PCIE_UP_SATA_TXN<0>
                                  W71      SATA6G_PCH_PCIE_UP_SATA_TXP<0>
                                  Y1       LPC_LAD3_IO3            
                                  Y3       LPC_LAD0_IO0            
                                  Y5       GND                     
                                  Y7       FM_CPU0_PROCHOT_PCH_N   
                                  Y11      H_CPU1_MEMKLM_MEMHOT_PCH_N
                                  Y15      H_CPU0_MEMABC_MEMHOT_PCH_N
                                  Y18      FM_PRSNT_2_4_N          
                                  Y22      GND                     
                                  Y26      P1V05_PCH_STBY          
                                  Y27      GND                     
                                  Y29      PVNN_PCH_STBY           
                                  Y30      PVNN_PCH_STBY           
                                  Y32      PVNN_PCH_STBY           
                                  Y34      PVNN_PCH_STBY           
                                  Y36      PVNN_PCH_STBY           
                                  Y37      PVNN_PCH_STBY           
                                  Y39      PVNN_PCH_STBY           
                                  Y41      PVNN_PCH_STBY           
                                  Y43      GND                     
                                  Y45      P1V05_PCH_STBY          
                                  Y46      P1V05_PCH_STBY          
                                  Y48      GND                     
                                  Y52      GND                     
                                  Y56      TP_PCH_RSVD34           
                                  Y59      GND                     
                                  Y63      GND                     
                                  Y66      P3E_CPU0_PE1_PCH_R_RXN<15>
                                  Y68      GND                     
                                  Y70      GND                     
                                  Y72      GND                     
U7D1             74CBTLV1G125_SMLF-IC,C88177-00A 1        PWRGD_PVCCIO_CPU0       
                                  2        XDP_PCH_PWR_DEBUG_N     
                                  4        XDP_CPU_PWR_DEBUG_N     
U7D2             GTL2014_SM-IC,D66151-001 1        PD_GTL2104_DIR_0        
                                  2        H_CPU_MSMI_G_N          
                                  3        H_CPU0_FIVR_FAULT_G     
                                  4        P0V7_GTL2104_VREF_0     
                                  5        H_CPU_ERR2_GTL_N        
                                  6        H_CPU0_THERMTRIP_G_N    
                                  7        GND                     
                                  8        GND                     
                                  9        FM_CPU0_THERMTRIP_LVT3_R_N
                                  10       FM_CPU_ERR2_LVT3_R_N    
                                  11       GND                     
                                  12       FM_CPU0_FIVR_FAULT_R_LVT3
                                  13       FM_CPU_MSMI_LVT3_R_N    
                                  14       P3V3                    
U7D3             ADM1085_SMT-IC,H46130-001 1        PWRGD_P3V3_STBY         
                                  2        GND                     
                                  3        VSENSE_P12V_ADM1085     
                                  4        PWRGD_DSW_PWROK         
                                  5        A_ADM1085_CEXT          
                                  6        P3V3_STBY               
U7E1             PCA9617_SSOP-IC,G81764-001-GNDA 1        PVCCIO_CPU0             
                                  2        SMB_DDR_DEF_SCL_G       
                                  3        SMB_DDR_DEF_SDA_G       
                                  5        TP_SMB_DDR_DEF_EN       
                                  6        SMB_DDR_DEF_VPP_SDA_R   
                                  7        SMB_DDR_DEF_VPP_SCL_R   
                                  8        PVPP_DEF                
U7E2             TTL1G08_SOTLF-NC7SZ08,IC,D1032B 1        FM_PVCCIN_CPU0_PWR_IN_ALERT_N
                                  2        IRQ_PVCCIN_CPU0_VRHOT_LVC3_N
                                  4        IRQ_CPU0_PROCHOT_G_N    
U7E3             TTL1G08_SOTLF-NC7SZ08,IC,D1032B 1        FM_PVCCIN_CPU1_PWR_IN_ALERT_N
                                  2        IRQ_PVCCIN_CPU1_VRHOT_LVC3_N
                                  4        IRQ_CPU1_PROCHOT_G_N    
U7F1             W25Q256_XSOI-IC,H25002-001 1        PU_BIOS_SPI_HOLD0_N     
                                  2        P3V3_STBY               
                                  3        PU_SPI0_RST             
                                  4        TP_SPI_0_6              
                                  5        TP_SPI_0_5              
                                  6        TP_SPI_0_4              
                                  7        SPI_CS0_PRIMARY_R_N     
                                  8        SPI_MISO_R0             
                                  9        PU_BIOS_SPI_WP0_N       
                                  10       GND                     
                                  11       TP_SPI_0_3              
                                  12       TP_SPI_0_2              
                                  13       TP_SPI_0_1              
                                  14       TP_SPI_0_0              
                                  15       SPI_SWITCH_MOSI_R0      
                                  16       SPI_CLK_R0              
U8D2             TTL1G07_A_SOP-74LVC1G07,IC,C88B 2        PWRGD_DSW_PWROK         
                                  4        RST_BMC_SRST_R2_N       
U8D3             TTL1G07_A_SOP-74LVC1G07,IC,C88B 2        IRQ_SML1_PMBUS_ALERT_BUF_N
                                  4        IRQ_FORCE_NM_THROTTLE_R_N
U8D4             AT24C64_SOICLF-IC,C47049-001-GA 1        GND                     
                                  2        GND                     
                                  3        PU_AT24C64_A2           
                                  5        SMB_SENSOR_STBY_LVC3_SDA_R2
                                  6        SMB_SENSOR_STBY_LVC3_SCL_R2
                                  7        PD_FRU_WP               
U8D5             TTL1G126_A_SOT-74HC1G126,IC,A7B 1        FM_PMBUS_ALERT_BUF_EN   
                                  2        IRQ_SML1_PMBUS_ALERT_N  
                                  4        IRQ_SML1_PMBUS_ALERT_BUF_N
U8D7             LCMXO2_A_256BGA-IC,H63395-001 A1       P3V3_STBY               
                                  A2       NC_CPLD1                
                                  A3       FM_PCH_PRSNT_N          
                                  A4       FM_P3V3_CPLD_EN         
                                  A5       TP_CPLD1_PT11A          
                                  A6       JTAG_PLD_TDI            
                                  A7       JTAG_PLD_TCK            
                                  A8       TP_CPLD1_PT17B_PCLKC0_1 
                                  A9       SMB_SENSOR_STBY_LVC3_SCL
                                  A10      FM_PVCCIN_PVCCSA_CPU0_EN_LVC1
                                  A11      FM_CPU0_OR_CPU1_MCP_PRES
                                  A12      PU_THERMTRIP_FORCE_N    
                                  A13      TP_CPLD1_PT24C_INITN    
                                  A14      TP_CPLD1_PT22D          
                                  A15      TP_CPLD1_PT24B          
                                  A16      P3V3_STBY               
                                  B1       RST_PCIE_PCH_PERST_N    
                                  B2       GND                     
                                  B3       FM_CTNR_PS_ON           
                                  B4       PWRGD_PVTT_CPU0         
                                  B5       PWRGD_P12V_MAIN         
                                  B6       TP_CPLD1_PT11B          
                                  B7       TP_CPLD1_PT13A          
                                  B8       JTAG_PLD_TMS            
                                  B9       PU_RST_PERST_BIT1       
                                  B10      TP_CPLD1_PT20D_PROGRAMN 
                                  B11      PWRGD_DSW_PWROK         
                                  B12      FM_PCH_PWRBTN_N         
                                  B13      TP_CPLD1_PT22C          
                                  B14      FM_SINT_PRSNT_N         
                                  B15      GND                     
                                  B16      FM_ADR_COMPLETE_DLY     
                                  C1       RST_PCIE_CPU_DEV1_N     
                                  C2       FM_PCH_PLD_DATA         
                                  C3       GND                     
                                  C4       FM_ADR_SMI_GPIO_R_N     
                                  C5       FM_CPU1_THERMTRIP_LATCH_LVT3_N
                                  C6       JTAG_PLD_TDO            
                                  C7       FM_BMC_ONCTL_N          
                                  C8       FM_ADR_COMPLETE         
                                  C9       SMB_SENSOR_STBY_LVC3_SDA
                                  C10      FM_JTAG_PLD_EN_DEBUG    
                                  C11      FM_CPU0_CD_PRES         
                                  C12      FM_SLPS4_N              
                                  C13      TP_CPLD1_PT24D_DONE     
                                  C14      GND                     
                                  C15      FM_DB1200_PWRGD         
                                  C16      PWRGD_PCH_PWROK         
                                  D1       TP_CPLD1_PL1B_L_GPLLC_FB
                                  D2       FM_MEM_EVENT_FUNC       
                                  D3       TP_CPLD1_PL1A_L_GPLLT_FB
                                  D4       GND                     
                                  D5       P3V3_STBY               
                                  D6       RST_PCIE_CPU_DEV0_N     
                                  D7       FM_FORCE_ADR_N          
                                  D8       TP_CPLD1_PT17C          
                                  D9       RST_PCIE_MIDPLANE_N     
                                  D10      TP_CPLD1_PT20A          
                                  D11      FM_CPU0_AND_CPU1_MCP_PRES
                                  D12      P3V3_STBY               
                                  D13      GND                     
                                  D14      PWRGD_SYS_PWROK         
                                  D15      PWRGD_P1V8MCP_CPU0      
                                  D16      PWRGD_P1V8MCP_CPU1      
                                  E1       CLK_32K_SUSCLK_PLD      
                                  E2       FM_CPU_CATERR_DLY_LVT3_N
                                  E3       TP_CPLD1_PL2B_L_GPLLC_IN
                                  E4       P3V3_STBY               
                                  E5       GND                     
                                  E6       FM_CPU1_FIVR_FAULT_LVT3_N
                                  E7       PWRGD_P1V26_BMC_STBY    
                                  E8       TP_CPLD1_PT16B          
                                  E9       FM_SLP_SUS_N            
                                  E10      TP_CPLD1_PT20B          
                                  E11      TP_CPLD1_PT19D          
                                  E12      GND                     
                                  E13      P3V3_STBY               
                                  E14      FM_CPLD_ADR_TRIGGER_N   
                                  E15      RST_PLTRST_N            
                                  E16      FM_P1V8MCP_CPU0_EN      
                                  F1       FM_CPU0_PROC_ID0        
                                  F2       FM_CPU0_PKGID0          
                                  F3       FM_CPU0_PROC_ID1        
                                  F4       PU_RST_PERST_BIT0       
                                  F5       FM_CPU0_FIVR_FAULT_LVT3_N
                                  F6       GND                     
                                  F7       FM_PLD_DEBUG_MODE_N     
                                  F8       SGPIO_BMC_DIN_R         
                                  F9       FM_PS_EN                
                                  F10      FM_CPU1_CD_PRES         
                                  F11      GND                     
                                  F12      FM_P1V8MCP_CPU1_EN      
                                  F13      PWRGD_CPUPWRGD          
                                  F14      RST_BMC_SYSRST_BTN_OUT_B_N
                                  F15      FM_CPU0_MCP_CLK_EN_N    
                                  F16      FM_CPU1_MCP_CLK_EN_N    
                                  G1       FM_SLPS3_N              
                                  G2       FM_CPU0_PKGID2          
                                  G3       FM_CPU0_PKGID1          
                                  G4       RST_RSMRST_R_N          
                                  G5       FM_DEBUG_RST_BTN_N      
                                  G6       FM_PWR_BTN_N            
                                  G7       P3V3_STBY               
                                  G8       P3V3_STBY               
                                  G9       P3V3_STBY               
                                  G10      P3V3_STBY               
                                  G11      FM_WBG_PRSNT_N          
                                  G12      FM_CPU0_THERMTRIP_LATCH_LVT3_N
                                  G13      FM_CPU1_FIVR_FAULT_LVT3 
                                  G14      FM_CPU1_THERMTRIP_LVT3_N
                                  G15      FM_UV_ADR_TRIGGER_N     
                                  G16      FM_FAST_PROCHOT_THROTTLE_IN_N
                                  H1       RST_PCIE_CPU_DEV3_N     
                                  H2       FM_PVCCMCP_CPU0_EN      
                                  H3       RST_PCIE_CPU_DEV2_N     
                                  H4       FM_MP_PS_FAIL_N         
                                  H5       SMB_SLOTX24_PCH_STBY_LVC3_SCL
                                  H6       PWRGD_P3V3              
                                  H7       P3V3_STBY               
                                  H8       GND                     
                                  H9       GND                     
                                  H10      P3V3_STBY               
                                  H11      TP_CPLD1_PR9C           
                                  H12      FM_UV_ADR_TRIGGER_EN    
                                  H13      FM_PVDDQ_GHJ_EN         
                                  H14      TP_CPLD1_PR7A_PCLKT1_0  
                                  H15      FM_PVDDQ_KLM_EN         
                                  H16      TP_CPLD1_PR7B_PCLKC1_0  
                                  J1       SGPIO_BMC_CLK           
                                  J2       SGPIO_BMC_DOUT          
                                  J3       TP_CPLD1_PL7D_PCLKT4_0  
                                  J4       SMB_SLOTX24_PCH_STBY_LVC3_SDA
                                  J5       UART_BMC_RXD5           
                                  J6       PWRGD_P5V               
                                  J7       P3V3_STBY               
                                  J8       GND                     
                                  J9       GND                     
                                  J10      P3V3_STBY               
                                  J11      TP_CPLD1_PR10C          
                                  J12      FM_FAST_PROCHOT_THROTTLE_DLY_N
                                  J13      TP_CPLD1_PR9D           
                                  J14      TP_CPLD1_PR7D           
                                  J15      TP_CPLD1_PR9A           
                                  J16      TP_CPLD1_PR7C           
                                  K1       FM_PVCCIOMCP_CPU0_EN    
                                  K2       SP1_BMC_HOST_UART_TX    
                                  K3       SP1_BMC_HOST_UART_RX    
                                  K4       SGPIO_BMC_LD_N          
                                  K5       PWRGD_PVCCIN_CPU0       
                                  K6       UART_BMC_TXD5           
                                  K7       P3V3_STBY               
                                  K8       P3V3_STBY               
                                  K9       P3V3_STBY               
                                  K10      P3V3_STBY               
                                  K11      RST_PLTRST_BUF_N        
                                  K12      FM_MEM_THERM_EVENT_PCH_N
                                  K13      FM_MEM_THERM_EVENT_LVT3_N
                                  K14      FM_PVDDQ_ABC_EN         
                                  K15      FM_PVDDQ_DEF_EN         
                                  K16      PU_FAB2_MARKER_CPLD     
                                  L1       PWRGD_PVSA_CPU0         
                                  L2       CLK_25M_CPLD            
                                  L3       TP_CPLD1_PL11A          
                                  L4       PWRGD_PVCCMCP_CPU1      
                                  L5       PWRGD_CPU0_LVC3         
                                  L6       GND                     
                                  L7       TP_CPLD1_PB8D           
                                  L8       PWRGD_PVCCIO_CPU0       
                                  L9       FM_IE_DISABLE_N         
                                  L10      FM_SOL_UART_CH_SEL      
                                  L11      GND                     
                                  L12      PWRGD_P3V3_STBY         
                                  L13      TP_CPLD1_PR12D          
                                  L14      TP_CPLD1_PR11B          
                                  L15      FM_THERMTRIP_DLY        
                                  L16      PWRGD_PVCCIO_CPU1       
                                  M1       RST_RSMRST_DLY          
                                  M2       PWRGD_PVPP_GHJ          
                                  M3       RST_PCIE_RISER1_PERST_N 
                                  M4       P3V3_STBY               
                                  M5       GND                     
                                  M6       PWRGD_PVPP_DEF          
                                  M7       FM_PVCCIO_CPU0_EN       
                                  M8       FM_PVCCMCP_CPU1_EN      
                                  M9       FM_CPLD_UART_CH_LOCK_N  
                                  M10      PWRGD_CPU1_LVC3         
                                  M11      XDP_PWRGD_RST_N         
                                  M12      GND                     
                                  M13      P3V3_STBY               
                                  M14      FM_CPU1_PROC_ID1        
                                  M15      FM_CPU1_PROC_ID0        
                                  M16      FM_CPU0_FIVR_FAULT_LVT3 
                                  N1       PWRGD_PVCCIN_CPU1       
                                  N2       PWRGD_PVPP_KLM          
                                  N3       RST_CD_CPU0_POR_N       
                                  N4       GND                     
                                  N5       P3V3_STBY               
                                  N6       PWRGD_PVCCIOMCP_CPU0    
                                  N7       PWRGD_PVPP_ABC          
                                  N8       FM_156M_CPU1_BRD_OSC_EN 
                                  N9       FM_CPLD_BMC_PWRDN_N     
                                  N10      RST_CPU1_LVC3_R1_N      
                                  N11      XDP_SYSPWROK            
                                  N12      P3V3_STBY               
                                  N13      GND                     
                                  N14      FM_CPU1_VRM_OSC_EN      
                                  N15      FM_CPU0_THERMTRIP_LVT3_N
                                  N16      FM_PVCCIN_PVCCSA_CPU1_EN_LVC1
                                  P1       FM_GLOBAL_RST_WARN_N    
                                  P2       FM_UART_ALERT_N         
                                  P3       GND                     
                                  P4       FM_CPU1_RC_EN           
                                  P5       PWRGD_PVCCMCP_CPU0      
                                  P6       TP_CPLD1_PB8A_MCLK_CCLK 
                                  P7       FM_PVCCIOMCP_CPU1_EN    
                                  P8       PWRGD_PVNN_P1V05_PCH    
                                  P9       TP_CPLD1_PB16B_PCLKC2_1 
                                  P10      RST_CD_CPU1_POR_N       
                                  P11      FM_UARTSW_MSB_N         
                                  P12      FM_CPU1_PKGID1          
                                  P13      TP_CPLD1_PB25B_SI_SISPI 
                                  P14      GND                     
                                  P15      FM_PVPP_CPU0_EN         
                                  P16      FM_PVPP_CPU1_EN         
                                  R1       FM_BMC_CPLD_GPO         
                                  R2       GND                     
                                  R3       FM_CPU0_RC_EN           
                                  R4       FM_BMC_CPLD_MP_RST_N    
                                  R5       TP_CPLD1_PB5A_CSSPIN    
                                  R6       RST_PCIE_M2_DEV_N       
                                  R7       PWRGD_PVTT_CPU1         
                                  R8       TP_CPLD1_PB11B_PCLKC2_0 
                                  R9       FM_UARTSW_LSB_N         
                                  R10      RST_CPU0_LVC3_R1_N      
                                  R11      FM_DB1200ZL_BCLKS_EN_N  
                                  R12      FM_CPU1_PKGID0          
                                  R13      FM_CPU0_VRM_OSC_EN      
                                  R14      FM_CPU_CATERR_LVT3_N    
                                  R15      GND                     
                                  R16      FM_P12V_MAIN_SW_EN      
                                  T1       P3V3_STBY               
                                  T2       FM_ADR_MODE_SEL         
                                  T3       FM_DIS_ADR_DLY          
                                  T4       PWRGD_PVSA_CPU1         
                                  T5       PWRGD_PVCCIOMCP_CPU1    
                                  T6       TP_CPLD1_PB8B_SO_SPISO  
                                  T7       FM_PVCCIO_CPU1_EN       
                                  T8       FM_CPLD_DBG_PWR_EN_N    
                                  T9       TP_CPLD1_PB16A_PCLKT2_1 
                                  T10      FM_156M_CPU0_BRD_OSC_EN 
                                  T11      FM_CPU1_PKGID2          
                                  T12      FM_CPU1_SKTOCC_LVT3_N   
                                  T13      FM_CPU_MSMI_LVT3_N      
                                  T14      FM_CPU0_SKTOCC_LVT3_N   
                                  T15      PWRGD_DRAMPWRGD         
                                  T16      P3V3_STBY               
U8D8             TPS3700_SM-IC,H69492-001 1        PWRGD_P5V_N             
                                  2        P3V3_STBY               
                                  3        A_PG_P5V                
                                  4        A_PG_P12V_MAIN          
                                  5        GND                     
                                  6        PWRGD_P12V_MAIN_R       
U8E1             TTL08_QFN15-74LVC08A,IC,D90404B 1        IRQ_FORCE_NM_THROTTLE_N 
                                  2        FM_OC_DETECT_N          
                                  3        FM_FAST_PROCHOT_AND_OUT_0_N
                                  4        IRQ_UV_DETECT_N         
                                  5        FM_HSC_TIMER_EXP_N      
                                  6        FM_FAST_PROCHOT_AND_OUT_1_N
                                  8        FM_CTNR_PS_ON_R         
                                  9        FM_PS_EN                
                                  10       PWRGD_P12V_HSC_DLY      
                                  11       FM_FAST_PROCHOT_THROTTLE_IN_N
                                  12       FM_FAST_PROCHOT_AND_OUT_0_N
                                  13       FM_FAST_PROCHOT_AND_OUT_1_N
U8E2             ADM809_SMLF-IC,D23047-001-GND=A 2        PWRGD_P12V_HSC_DLY_R    
                                  3        PWRGD_P12V_HSC          
U8E3             TTL1G126_A_SOT-74HC1G126,IC,A7B 1        RST_PLTRST_TOP_SWAP     
                                  2        FM_BIOS_TOP_SWAP        
                                  4        FM_BIOS_TOP_SWAP_SPKR_R 
U8E4             TTL1G126_A_SOT-74HC1G126,IC,A7B 1        PU_TRI_STATE_EN         
                                  2        FM_ALL_WAKE_N           
                                  4        IRQ_LVC3_WAKE_R_N       
U8F1             PI3B3257A_TSSOPLF-IC,E16801-001 1        FM_BIOS_SPI_BMC_CTRL    
                                  2        SPI_PCH_CLK             
                                  3        SPI_BMC_CLK             
                                  4        SPI_SWITCH_CLK          
                                  5        SPI_PCH_MOSI            
                                  6        SPI_BMC_DO              
                                  7        SPI_SWITCH_MOSI         
                                  8        GND                     
                                  9        SPI_SWITCH_CS0_N        
                                  10       SPI_BMC_CS0_N           
                                  11       SPI_PCH_CS0_N           
                                  12       SPI_SWITCH_MISO         
                                  13       SPI_BMC_DI              
                                  14       SPI_PCH_MISO_R          
                                  15       GND                     
                                  16       P3V3_STBY               
U8F2             W25Q128_SKT16-IC,H12709-001 1        PU_SPI_BMC_BT_HOLD_N    
                                  2        P3V3_STBY               
                                  3        PU_SPI_FLASH_RESET_2_N  
                                  4        TP_SPI_2_0              
                                  5        TP_SPI_2_1              
                                  6        TP_SPI_2_2              
                                  7        SPI_BMC_BT_CS_N         
                                  8        SPI_BMC_BT_DI_R         
                                  9        PU_SPI_BMC_BT_WP_N      
                                  10       GND                     
                                  11       TP_SPI_2_3              
                                  12       TP_SPI_2_4              
                                  13       TP_SPI_2_5              
                                  14       TP_SPI_2_6              
                                  15       SPI_BMC_BT_DO           
                                  16       SPI_BMC_BT_CLK          
U8F3             TTL2G07_SOT23LF-74LVC2G07,IC,DB 1        RST_BMC_SYSRST_BTN_OUT_N
                                  3        FM_BMC_PWRBTN_OUT_N     
                                  4        FM_PCH_PWRBTN_R_N       
                                  6        RST_BMC_SYSRST_BTN_OUT_B_R_N
U8G1             TTL2G07_SOT23LF-74LVC2G07,IC,DB 1        RST_PCH_SYSRST_BTN_OUT_N
                                  3        FM_PCH_PWRBTN_OUT_N     
                                  4        FM_PCH_PWRBTN_R_N       
                                  6        RST_BMC_SYSRST_BTN_OUT_B_R_N
U8G2             TTL1G07_A_SOP-74LVC1G07,IC,C88B 2        FAN_PWM_OUT_SYS0        
                                  4        FAN_PWM_OUT_SYS0_BUF    
U8G3             TTL1G07_A_SOP-74LVC1G07,IC,C88B 2        FAN_PWM_OUT_SYS1        
                                  4        FAN_PWM_OUT_SYS1_BUF    
U9A1             TTL1G07_A_SOP-74LVC1G07,IC,C88B 2        SPA_5V_SIN_SW           
                                  4        SPA_SIN_SW_R            
U9A3             TTL2G14_SMLF-74LVC2G14,IC,D184B 1        FP_RST_BTN_R_N          
                                  3        FP_RST_BTN_BUF1_N       
                                  4        RST_SYSTEM_BTN_BUF_N    
                                  6        FP_RST_BTN_BUF1_N       
U9A4             TTL2G14_SMLF-74LVC2G14,IC,D184B 1        FP_PWR_BTN_R1_N         
                                  3        FP_PWR_BTN_BUF1_N       
                                  4        FM_PWR_BTN_R_N          
                                  6        FP_PWR_BTN_BUF1_N       
U9A5             74CBTLV1G125_SMLF-IC,C88177-00A 1        FM_CPU0_OR_CPU1_MCP_PRES
                                  2        JTAG_MCP_TCK_R          
                                  4        GND                     
U9B4             TMP421_TSSOP-IC,G62962-001 1        ISENSE_TMP421_1_DXP     
                                  2        ISENSE_TMP421_1_DXN     
                                  3        PU_TMP421_1_A1          
                                  4        PD_TMP421_1_A0          
                                  5        GND                     
                                  6        SMB_SENSOR_TMP421_1_SDA 
                                  7        SMB_SENSOR_TMP421_1_SCL 
                                  8        P3V3_STBY               
U9E1             M25PE16_SM-IC,H77797-001 1        SPI_NIC_CS_N            
                                  2        SPI_NIC_MISO_R          
                                  3        PU_NV_WP_N              
                                  4        GND                     
                                  5        SPI_NIC_MOSI            
                                  6        SPI_NIC_SCLK            
                                  7        PU_NV_HOLD_N            
                                  8        P3V3_STBY               
U9F1             FSA3357_SM-IC,C63273-001 1        SP2_BMC_CM_UART_RX_R    
                                  2        UART_BMC_RXD5           
                                  3        SP1_BMC_HOST_UART_RX    
                                  4        GND                     
                                  5        FM_UARTSW_MSB_N         
                                  6        FM_UARTSW_LSB_N         
                                  7        UART_MUX_IN_R           
                                  8        P3V3_STBY               
U9F2             FSA3357_SM-IC,C63273-001 1        SP2_BMC_CM_UART_TX_R    
                                  2        UART_BMC_TXD5           
                                  3        SP1_BMC_HOST_UART_TX    
                                  4        GND                     
                                  5        FM_UARTSW_MSB_N         
                                  6        FM_UARTSW_LSB_N         
                                  7        UART_MUX_OUT_R          
                                  8        P3V3_STBY               
U9F3             TTL1G07_A_SOP-74LVC1G07,IC,C88B 2        RST_BMC_DDR3_BUF_IN_N   
                                  4        RST_BMC_DDR3_R_N        
U9F4             AST1250_BGA-IC,G85138-002 A1       H_CPU1_MEMKLM_MEMHOT_LVT3_BMC_N
                                  A2       H_CPU0_MEMABC_MEMHOT_LVT3_BMC_N
                                  A3       FM_FORCE_ADR_N          
                                  A4       FM_BIOS_POST_CMPLT_N    
                                  A5       FM_CPU1_SKTOCC_LVT3_N   
                                  A6       LED_POSTCODE_6          
                                  A7       LED_POSTCODE_3          
                                  A8       LED_POSTCODE_0          
                                  A9       RMII_SPRNGVLLE_BMC_PCH_RXD0
                                  A10      RMII_BMC_PCH_SPRNGVLLE_TXD0_R
                                  A11      RMII_BMC_OCP_CRSDV      
                                  A12      RMII_BMC_OCP_TXEN_R     
                                  A13      TP_RGMII2TXD3_GPIOT5    
                                  A14      FM_CPU_BMC_INIT         
                                  A15      FM_BB_BMC_MP_GPIO       
                                  A16      FM_CPU_ERR0_LVT3_BMC_N  
                                  A17      FM_BMC_PWRBTN_OUT_N     
                                  A18      FP_NMI_BTN_N            
                                  A19      IRQ_MEZZ_LAN_ALERT_N    
                                  A20      IRQ_HSC_FAULT_N         
                                  A21      LPC_LFRAME_N_CS0_R_N    
                                  A22      LPC_LAD1_IO1_R          
                                  AA1      SP2_BMC_CM_UART_TX      
                                  AA2      FM_BIOS_PREFRB2_GOOD    
                                  AA3      FM_UARTSW_LSB_N         
                                  AA4      FAN_TACH2               
                                  AA5      FM_MP_PS_REDUNDANT_LOST_N
                                  AA6      FM_BOARD_SKU_ID3        
                                  AA7      FM_CPU0_PROCHOT_LVT3_BMC_N
                                  AA8      M_BMC_DDR3_MDQS_1_DP    
                                  AA9      M_BMC_DDR3_DQ<10>       
                                  AA10     M_BMC_DDR3_MDQS_0_DN    
                                  AA11     M_BMC_DDR3_DQ<3>        
                                  AA12     M_BMC_DDR3_MCK_N        
                                  AA13     M_BMC_DDR3_MCS_N        
                                  AA14     M_BMC_DDR3_MBA_1        
                                  AA15     M_BMC_DDR3_MA<6>        
                                  AA16     M_BMC_DDR3_MA<11>       
                                  AA17     M_BMC_DDR3_MA<9>        
                                  AA18     GND                     
                                  AA19     GND                     
                                  AA20     A_USB2VRES              
                                  AA21     PECI_BMC_R              
                                  AA22     FM_BMC_NMI_N            
                                  AB1      FM_CPU_MSMI_LVT3_N      
                                  AB2      FM_UARTSW_MSB_N         
                                  AB3      FAN_TACH3               
                                  AB4      FM_XRC_PRESENT_N        
                                  AB5      FM_BOARD_SKU_ID1        
                                  AB6      IRQ_PVCCIN_CPU0_VRHOT_LVC3_N
                                  AB7      FM_CPU1_PROCHOT_LVT3_BMC_N
                                  AB8      M_BMC_DDR3_MDQS_1_DN    
                                  AB9      M_BMC_DDR3_DQ<9>        
                                  AB10     M_BMC_DDR3_MDQS_0_DP    
                                  AB11     M_BMC_DDR3_DQ<2>        
                                  AB12     M_BMC_DDR3_MCK_P        
                                  AB13     M_BMC_DDR3_MCAS_N       
                                  AB14     M_BMC_DDR3_MA<0>        
                                  AB15     M_BMC_DDR3_MA<4>        
                                  AB16     M_BMC_DDR3_MA<8>        
                                  AB17     M_BMC_DDR3_MA<14>       
                                  AB18     M_BMC_DDR3_MA<7>        
                                  AB19     P3V3_STBY_BMC_HPLLAV33  
                                  AB20     USB2_PCH_BMC_P5_DN      
                                  AB21     USB2_PCH_BMC_P5_DP      
                                  AB22     CLK_24M_25M_BMC_CLKIN   
                                  B1       SMB_HOST_STBY_LVC3_SCL_R
                                  B2       H_CPU1_MEMGHJ_MEMHOT_LVT3_BMC_N
                                  B3       IRQ_PVDDQ_DEF_VRHOT_LVT3_N
                                  B4       SMB_OCP_FRU_STBY_LVC3_SDA_R
                                  B5       FM_BMC_FAULT_LED_N      
                                  B6       LED_POSTCODE_5          
                                  B7       LED_POSTCODE_2          
                                  B8       GND                     
                                  B9       GND                     
                                  B10      RMII_BMC_PCH_SPRNGVLLE_TXD1_R
                                  B11      RMII_BMC_OCP_RXD1       
                                  B12      TP_RGMII2TXCTL_GPIOT7   
                                  B13      FM_BATTERY_SENSE_EN_N   
                                  B14      TP_GPIOE7_RXD3          
                                  B15      PWRGD_SYS_PWROK         
                                  B16      RST_BMC_SYSRST_BTN_OUT_N
                                  B17      FM_PWR_BTN_N            
                                  B18      IRQ_SML1_PMBUS_ALERT_N  
                                  B19      FM_CPU_CATERR_LVT3_N    
                                  B20      CLK_24M_BMC_LPC         
                                  B21      LPC_LAD0_IO0_R          
                                  B22      SPI_BMC_CS0_N           
                                  C1       SMB_VR_STBY_LVC3_SCL_R  
                                  C2       SMB_OCP_LAN_STBY_LVC3_SDA_R
                                  C3       IRQ_PVDDQ_KLM_VRHOT_LVT3_N
                                  C4       IRQ_PVDDQ_ABC_VRHOT_LVT3_N
                                  C5       SMB_OCP_FRU_STBY_LVC3_SCL_R
                                  C6       FM_CPU0_SKTOCC_LVT3_N   
                                  C7       LED_POSTCODE_1          
                                  C8       RMII_BMC_PCH_SPRNGVLLE_RXER
                                  C9       CLK_50M_CKMNG_BMC_2     
                                  C10      TP_RGMII1TXD2_GPIOT4    
                                  C11      RMII_BMC_OCP_RXD0       
                                  C12      RMII_BMC_OCP_TXD0_R     
                                  C13      FM_SLPS4_N              
                                  C14      FM_BMC_CPLD_MP_RST_N    
                                  C15      PWRGD_PCH_PWROK         
                                  C16      RST_SYSTEM_BTN_N        
                                  C17      H_CPU0_FAST_WAKE_LVT3_N 
                                  C18      SPI_BMC_DO              
                                  C19      LPC_LAD3_IO3_R          
                                  C20      TP_SPI_PCH_BIOS_MISO_R  
                                  C21      P1V8_BMC_STBY_PCIEA     
                                  C22      TP_SPI_PCH_BIOS_CS0_R_N 
                                  D1       SMB_SENSOR_BMC_STBY_LVC3_SDA
                                  D2       SMB_SMLINK0_STBY_LVC3_SDA_R
                                  D3       SMB_OCP_LAN_STBY_LVC3_SCL_R
                                  D4       IRQ_PVDDQ_GHJ_VRHOT_LVT3_N
                                  D5       FM_UV_ADR_TRIGGER_EN    
                                  D6       FM_CPLD_BMC_PWRDN_N     
                                  D7       LED_POSTCODE_4          
                                  D8       RMII_BMC_PCH_SPRNGVLLE_CRSDV
                                  D9       RMII_BMC_SPRNGVLLE_TXEN_R
                                  D10      TP_RGMII1TXD3_GPIOT5    
                                  D11      GND                     
                                  D12      RMII_BMC_OCP_TXD1_R     
                                  D13      FM_SLPS3_N              
                                  D14      IRQ_BMC_PCH_SMI_LPC_N   
                                  D15      IRQ_SML0_ALERT_N        
                                  D16      IRQ_BMC_PCH_NMI_STBY_N  
                                  D17      IRQ_OOB_MGMT_RISER_ALERT_N
                                  D18      FM_PCH_BMC_THERMTRIP_N  
                                  D19      TP_SPI_PCH_BIOS_MOSI_R  
                                  D20      PD_PEREXT               
                                  D21      GND                     
                                  D22      GND                     
                                  E1       JTAG_BMC_TRST_N         
                                  E2       SMB_SENSOR_BMC_STBY_LVC3_SCL
                                  E3       SMB_SMLINK0_STBY_LVC3_SCL_R
                                  E4       PD_SP_ENTEST            
                                  E5       H_CPU0_MEMDEF_MEMHOT_LVT3_BMC_N
                                  E6       FM_BMC_SYS_THROTTLE_R_N 
                                  E7       LED_POSTCODE_7          
                                  E8       RMII_SPRNGVLLE_BMC_PCH_RXD1
                                  E9       TP_RGMII1TXCTL_GPIOT1   
                                  E10      RMII_BMC_OCP_RXER       
                                  E11      CLK_50M_CKMNG_BMC_1     
                                  E12      TP_RGMII2TXD2_GPIOT4    
                                  E13      IRQ_PCH_NIC_ALERT_N     
                                  E14      IRQ_BMC_PCH_SCI_LPC_N   
                                  E15      FM_CPU_ERR1_LVT3_BMC_N  
                                  E16      IRQ_LOM_ALERT_N         
                                  E17      IRQ_LPC_SERIRQ_R        
                                  E18      FM_BMC_CPLD_GPO         
                                  E19      RST_BMC_LVC3_N          
                                  E20      SPI_BMC_DI              
                                  E21      P2E_SSB_BMC_RX_DN       
                                  E22      P2E_SSB_BMC_RX_DP       
                                  F1       JTAG_BMC_TDI            
                                  F2       JTAG_BMC_TCK            
                                  F3       SMB_BMC_PMBUS_STBY_LVC3_SDA_R
                                  F4       SMB_VR_STBY_LVC3_SDA_R  
                                  F5       SMB_HOST_STBY_LVC3_SDA_R
                                  F8       P3V3_STBY               
                                  F9       P3V3_STBY               
                                  F10      P3V3_STBY               
                                  F11      P3V3_STBY               
                                  F12      P3V3_STBY               
                                  F13      P3V3_STBY               
                                  F14      P1V26_BMC_STBY          
                                  F15      P1V26_BMC_STBY          
                                  F18      FM_FAST_PROCHOT_EN_N    
                                  F19      LPC_LAD2_IO2_R          
                                  F20      P1V8_BMC_STBY_PCIEA     
                                  F21      P2E_SSB_BMC_TX_C_DP     
                                  F22      P2E_SSB_BMC_TX_C_DN     
                                  G1       UART_BMC_RXD5           
                                  G2       JTAG_BMC_TMS            
                                  G3       JTAG_BMC_TDO            
                                  G4       TP_JTAG_BMC_RTCK        
                                  G5       SMB_BMC_PMBUS_STBY_LVC3_SCL_R
                                  G18      TP_SPI_PCH_BIOS_CLK_R   
                                  G19      SPI_BMC_CLK             
                                  G20      P1V8_BMC_STBY_PCIE      
                                  G21      CLK_100M_BMC_PE_R_DN    
                                  G22      CLK_100M_BMC_PE_R_DP    
                                  H1       FM_CPU1_FIVR_FAULT_LVT3_R_N
                                  H2       FM_CPU0_FIVR_FAULT_LVT3_R_N
                                  H3       FP_PWR_ID_LED_N         
                                  H4       FM_BMC_READY_N          
                                  H5       UART_BMC_TXD5           
                                  H6       P3V3_STBY               
                                  H17      P3V3_STBY               
                                  H18      FM_POST_CARD_PRES_BMC_N 
                                  H19      FM_CPU0_THERMTRIP_LATCH_LVT3_N
                                  H20      FM_CPU1_THERMTRIP_LATCH_LVT3_N
                                  H21      GND                     
                                  H22      GND                     
                                  J1       PD_USB_BMC_P1_DP        
                                  J2       PD_USB_BMC_P1_DN        
                                  J3       SGPIO_BMC_DIN           
                                  J4       SGPIO_BMC_LD_R_N        
                                  J5       SGPIO_BMC_CLK_R         
                                  J6       P3V3_STBY               
                                  J9       GND                     
                                  J10      GND                     
                                  J11      GND                     
                                  J12      GND                     
                                  J13      GND                     
                                  J14      GND                     
                                  J17      P3V3_STBY               
                                  J18      SMB_SLOTX24_STBY_LVC3_SDA_R
                                  J19      SMB_SLOTX24_STBY_LVC3_SCL_R
                                  J20      FM_BIOS_SMI_ACTIVE_N    
                                  J21      FM_BMC_HEARTBEAT_N      
                                  J22      FM_PE_BMC_WAKE_N        
                                  K1       P3V3_STBY_BMC_ADCVREFP  
                                  K2       P3V3_STBY_BMC_ADCVREFN  
                                  K3       USB_PCH_BMC_P4_DN       
                                  K4       USB_PCH_BMC_P4_DP       
                                  K5       SGPIO_BMC_DOUT_R        
                                  K6       P1V26_BMC_STBY          
                                  K9       GND                     
                                  K10      GND                     
                                  K11      GND                     
                                  K12      GND                     
                                  K13      GND                     
                                  K14      GND                     
                                  K17      P1V26_BMC_STBY          
                                  K18      FM_ROMA<23>             
                                  K19      RST_PLTRST_BUF_N        
                                  K20      FM_BMC_ONCTL_R_N        
                                  K21      SMB_LAN_STBY_LVC3_SCL_R 
                                  K22      SMB_LAN_STBY_LVC3_SDA_R 
                                  L1       A_PVNN_STBY_PCH_SENSOR  
                                  L2       A_P1V05_STBY_PCH_SENSOR 
                                  L3       A_P12V_STBY_SCALED      
                                  L4       A_P5V_SCALED            
                                  L5       A_P3V3_SCALED           
                                  L6       P1V26_BMC_STBY          
                                  L9       GND                     
                                  L10      GND                     
                                  L11      GND                     
                                  L12      GND                     
                                  L13      GND                     
                                  L14      GND                     
                                  L17      P1V26_BMC_STBY          
                                  L18      FM_ROMA<12>             
                                  L19      FM_ROMA<13>             
                                  L20      FM_ROMA<14>             
                                  L21      FM_ROMA<15>             
                                  L22      FM_ROMA<22>             
                                  M1       GND                     
                                  M2       GND                     
                                  M3       A_P3V_BAT_SCALED        
                                  M4       A_P5V_STBY_SCALED       
                                  M5       A_P3V3_STBY_SCALED      
                                  M6       P3V3_STBY               
                                  M9       GND                     
                                  M10      GND                     
                                  M11      GND                     
                                  M12      GND                     
                                  M13      GND                     
                                  M14      GND                     
                                  M17      P3V3_STBY               
                                  M18      FM_ROMA<19>             
                                  M19      FM_ROMA<8>              
                                  M20      FM_ROMA<9>              
                                  M21      FM_ROMA<10>             
                                  M22      FM_ROMA<11>             
                                  N1       GND                     
                                  N2       GND                     
                                  N3       GND                     
                                  N4       GND                     
                                  N5       GND                     
                                  N6       P3V3_STBY               
                                  N9       GND                     
                                  N10      GND                     
                                  N11      GND                     
                                  N12      GND                     
                                  N13      GND                     
                                  N14      GND                     
                                  N17      P3V3_STBY               
                                  N18      FM_ROMA<17>             
                                  N19      FM_ROMA<18>             
                                  N20      FM_ROMA<21>             
                                  N21      FM_CPU_ERR2_LVT3_N      
                                  N22      FM_ROMA<20>             
                                  P1       P3V3_STBY               
                                  P2       PD_ADCREXT              
                                  P3       P3V3_STBY_BMC_ADCAV33   
                                  P4       GND                     
                                  P5       GND                     
                                  P6       P1V26_BMC_STBY          
                                  P9       GND                     
                                  P10      GND                     
                                  P11      GND                     
                                  P12      GND                     
                                  P13      GND                     
                                  P14      GND                     
                                  P17      P1V26_BMC_STBY          
                                  P18      FM_ROMA<3>              
                                  P19      FM_ROMA<4>              
                                  P20      FM_ROMA<5>              
                                  P21      FM_ROMA<6>              
                                  P22      FM_ROMA<7>              
                                  R1       A_DACRSET               
                                  R2       TP_DACR                 
                                  R3       TP_DACG                 
                                  R4       TP_DACB                 
                                  R5       GND                     
                                  R6       P1V26_BMC_STBY          
                                  R17      P1V26_BMC_STBY          
                                  R18      FM_SOL_UART_CH_SEL      
                                  R19      SPI_BMC_BT_CS_R_N       
                                  R20      FM_ROMA<0>              
                                  R21      FM_ROMA<1>              
                                  R22      FM_ROMA<2>              
                                  T1       TP_DDCDAT_GPIOJ7        
                                  T2       TP_DDCCLK_GPIOJ6        
                                  T3       P3V3_STBY               
                                  T4       TP_VGAHS_GPIOJ4         
                                  T5       IRQ_OC_DETECT_N         
                                  T18      FM_ROMA<16>             
                                  T19      FM_BOARD_REV_ID1        
                                  T20      SPI_BMC_BT_DI           
                                  T21      SPI_BMC_BT_DO_R         
                                  T22      SPI_BMC_BT_CLK_R        
                                  U1       IRQ_UV_DETECT_N         
                                  U2       TP_VGAVS_GPIOJ5         
                                  U3       FM_HSC_TIMER_EXP_N      
                                  U4       FM_MEM_THERM_EVENT_PCH_N
                                  U5       SP1_BMC_HOST_UART_RX    
                                  U8       P3V3_STBY               
                                  U9       P3V3_STBY               
                                  U10      P1V538_BMC_STBY         
                                  U11      P1V538_BMC_STBY         
                                  U12      P1V26_BMC_STBY          
                                  U13      P1V26_BMC_STBY          
                                  U14      P1V538_BMC_STBY         
                                  U15      P1V538_BMC_STBY         
                                  U18      IRQ_DIMM_SAVE_LVT3_N    
                                  U19      FM_FLASH_DESC_OVERRIDE_R
                                  U20      FM_BIOS_MRC_DEBUG_MSG_DIS_N
                                  U21      FM_BOARD_REV_ID0        
                                  U22      TP_SPI_BMC_BT_D2        
                                  V1       FM_BIOS_TOP_SWAP        
                                  V2       FM_PMBUS_ALERT_BUF_EN_N 
                                  V3       FM_CPU0_RC_ERROR_N      
                                  V4       FM_OC_DETECT_EN_N       
                                  V5       SP2_BMC_CM_UART_RX      
                                  V6       FAN_TACH0               
                                  V7       FM_XRC_READY_N          
                                  V8       M_BMC_DDR3_MDM_1        
                                  V9       M_BMC_DDR3_DQ<13>       
                                  V10      M_BMC_DDR3_DQ<8>        
                                  V11      M_BMC_DDR3_DQ<6>        
                                  V12      M_BMC_DDR3_DQ<1>        
                                  V13      M_BMC_DDR3_MVREF        
                                  V14      M_BMC_DDR3_MODT         
                                  V15      M_BMC_DDR3_MA<2>        
                                  V16      TP_M_BMC_DDR3_MIOZ      
                                  V17      P3V3_STBY_BMC_HPLLAV33  
                                  V18      GND                     
                                  V19      PVCCIO_CPU0             
                                  V20      FM_MB_SLOT_ID0          
                                  V21      FM_THROTTLE_N           
                                  V22      FM_BOARD_REV_ID2        
                                  W1       SP1_BMC_HOST_UART_TX    
                                  W2       FM_CPU1_RC_ERROR_N      
                                  W3       FM_BOARD_SKU_ID4        
                                  W4       FAN_PWM_OUT_SYS0        
                                  W5       FM_BACKUP_BIOS_SEL_N    
                                  W6       FM_MP_PS_FAIL_N         
                                  W7       FM_BOARD_SKU_ID2        
                                  W8       M_BMC_DDR3_DQ<15>       
                                  W9       M_BMC_DDR3_DQ<12>       
                                  W10      M_BMC_DDR3_MDM_0        
                                  W11      M_BMC_DDR3_DQ<5>        
                                  W12      M_BMC_DDR3_DQ<0>        
                                  W13      M_BMC_DDR3_MRAS_N       
                                  W14      M_BMC_DDR3_MBA_0        
                                  W15      M_BMC_DDR3_MA<1>        
                                  W16      M_BMC_DDR3_MA<5>        
                                  W17      M_BMC_DDR3_MA<12>       
                                  W18      P3V3_STBY               
                                  W19      P1V26_BMC_STBY_V1PLLAV12
                                  W20      RST_BMC_SRST_N          
                                  W21      FM_MB_SLOT_ID1          
                                  W22      TP_GPIOR5_ROMA25_VPOR7  
                                  Y1       IRQ_BOARD_BMC_ALERT_N   
                                  Y2       TP_GPIOM5_NRTS2_VPIB7   
                                  Y3       FAN_PWM_OUT_SYS1        
                                  Y4       FM_BIOS_SPI_BMC_CTRL    
                                  Y5       FAN_TACH1               
                                  Y6       FM_BOARD_SKU_ID0        
                                  Y7       IRQ_PVCCIN_CPU1_VRHOT_LVC3_N
                                  Y8       M_BMC_DDR3_DQ<14>       
                                  Y9       M_BMC_DDR3_DQ<11>       
                                  Y10      M_BMC_DDR3_DQ<7>        
                                  Y11      M_BMC_DDR3_DQ<4>        
                                  Y12      M_BMC_DDR3_MCKE         
                                  Y13      M_BMC_DDR3_MWE_N        
                                  Y14      M_BMC_DDR3_MBA_2        
                                  Y15      M_BMC_DDR3_MA<10>       
                                  Y16      M_BMC_DDR3_MA<3>        
                                  Y17      M_BMC_DDR3_MA<13>       
                                  Y18      P1V26_BMC_STBY          
                                  Y19      GND                     
                                  Y20      P1V26_BMC_STBY_V1PLLAV12
                                  Y21      CLK_48M_USB_BMC         
                                  Y22      FM_MB_SLOT_ID2          
U9F5             K4B1G16_BGA1-IC,G38649-001 A1       P1V538_BMC_STBY         
                                  A2       M_BMC_DDR3_DQ<15>       
                                  A3       M_BMC_DDR3_DQ<14>       
                                  A7       M_BMC_DDR3_DQ<10>       
                                  A8       P1V538_BMC_STBY         
                                  A9       GND                     
                                  B1       GND                     
                                  B2       P1V538_BMC_STBY         
                                  B3       GND                     
                                  B7       M_BMC_DDR3_MDQS_1_DN    
                                  B8       M_BMC_DDR3_DQ<9>        
                                  B9       GND                     
                                  C1       P1V538_BMC_STBY         
                                  C2       M_BMC_DDR3_DQ<12>       
                                  C3       M_BMC_DDR3_DQ<11>       
                                  C7       M_BMC_DDR3_MDQS_1_DP    
                                  C8       M_BMC_DDR3_DQ<13>       
                                  C9       P1V538_BMC_STBY         
                                  D1       GND                     
                                  D2       P1V538_BMC_STBY         
                                  D3       M_BMC_DDR3_MDM_1        
                                  D7       M_BMC_DDR3_DQ<8>        
                                  D8       GND                     
                                  D9       P1V538_BMC_STBY         
                                  E1       GND                     
                                  E2       GND                     
                                  E3       M_BMC_DDR3_DQ<7>        
                                  E7       M_BMC_DDR3_MDM_0        
                                  E8       GND                     
                                  E9       P1V538_BMC_STBY         
                                  F1       P1V538_BMC_STBY         
                                  F2       M_BMC_DDR3_DQ<4>        
                                  F3       M_BMC_DDR3_MDQS_0_DP    
                                  F7       M_BMC_DDR3_DQ<3>        
                                  F8       M_BMC_DDR3_DQ<2>        
                                  F9       GND                     
                                  G1       GND                     
                                  G2       M_BMC_DDR3_DQ<5>        
                                  G3       M_BMC_DDR3_MDQS_0_DN    
                                  G7       P1V538_BMC_STBY         
                                  G8       GND                     
                                  G9       GND                     
                                  H1       M_BMC_DDR3_MVREF        
                                  H2       P1V538_BMC_STBY         
                                  H3       M_BMC_DDR3_DQ<1>        
                                  H7       M_BMC_DDR3_DQ<0>        
                                  H8       M_BMC_DDR3_DQ<6>        
                                  H9       P1V538_BMC_STBY         
                                  J1       TP_K4B1G16_BMC_NC0      
                                  J2       GND                     
                                  J3       M_BMC_DDR3_MRAS_N       
                                  J7       M_BMC_DDR3_MCK_P        
                                  J8       GND                     
                                  J9       TP_K4B1G16_BMC_NC1      
                                  K1       M_BMC_DDR3_MODT         
                                  K2       P1V538_BMC_STBY         
                                  K3       M_BMC_DDR3_MCAS_N       
                                  K7       M_BMC_DDR3_MCK_N        
                                  K8       P1V538_BMC_STBY         
                                  K9       M_BMC_DDR3_MCKE         
                                  L1       TP_K4B1G16_BMC_NC2      
                                  L2       M_BMC_DDR3_MCS_N        
                                  L3       M_BMC_DDR3_MWE_N        
                                  L7       M_BMC_DDR3_MA<10>       
                                  L8       A_M_BMC_ZQ              
                                  L9       TP_K4B1G16_BMC_NC3      
                                  M1       GND                     
                                  M2       M_BMC_DDR3_MBA_0        
                                  M3       M_BMC_DDR3_MBA_2        
                                  M7       TP_K4B1G16_BMC_NC4      
                                  M8       M_BMC_DDR3_MVREF        
                                  M9       GND                     
                                  N1       P1V538_BMC_STBY         
                                  N2       M_BMC_DDR3_MA<3>        
                                  N3       M_BMC_DDR3_MA<0>        
                                  N7       M_BMC_DDR3_MA<12>       
                                  N8       M_BMC_DDR3_MBA_1        
                                  N9       P1V538_BMC_STBY         
                                  P1       GND                     
                                  P2       M_BMC_DDR3_MA<5>        
                                  P3       M_BMC_DDR3_MA<2>        
                                  P7       M_BMC_DDR3_MA<1>        
                                  P8       M_BMC_DDR3_MA<4>        
                                  P9       GND                     
                                  R1       P1V538_BMC_STBY         
                                  R2       M_BMC_DDR3_MA<7>        
                                  R3       M_BMC_DDR3_MA<9>        
                                  R7       M_BMC_DDR3_MA<11>       
                                  R8       M_BMC_DDR3_MA<6>        
                                  R9       P1V538_BMC_STBY         
                                  T1       GND                     
                                  T2       RST_BMC_DDR3_N          
                                  T3       M_BMC_DDR3_MA<13>       
                                  T7       M_BMC_DDR3_MA<14>       
                                  T8       M_BMC_DDR3_MA<8>        
                                  T9       GND                     
U9G1             GTL2014_SM-IC,D66151-001 1        PD_DIR_2                
                                  2        H_CPU1_MEMKLM_MEMHOT_G_R_N
                                  3        H_CPU1_MEMGHJ_MEMHOT_G_R_N
                                  4        P0V7_GTL2014_2          
                                  5        H_CPU0_MEMDEF_MEMHOT_G_R_N
                                  6        H_CPU0_MEMABC_MEMHOT_G_R_N
                                  7        GND                     
                                  8        GND                     
                                  9        H_CPU0_ABC_MEMHOT_LVT3_R_N
                                  10       H_CPU0_DEF_MEMHOT_LVT3_R_N
                                  11       GND                     
                                  12       H_CPU1_GHJ_MEMHOT_LVT3_R_N
                                  13       H_CPU1_KLM_MEMHOT_LVT3_R_N
                                  14       P3V3                    
U9P1             TPS3700_SM-IC,H69492-001 1        A_P12V_STBY_FPH_GATE    
                                  2        P12V_STBY               
                                  3        A_P12V_STBY_FP_TRIGGER  
                                  4        A_P12V_STBY_ADR_TRIGGER 
                                  5        GND                     
                                  6        FM_UV_ADR_TRIGGER_N     
U9P2             TPS3700_SM-IC,H69492-001 1        FM_HSC_TIMER_EXP_N      
                                  2        P3V3_STBY               
                                  3        A_HSC_TIMER_R           
                                  4        A_HSC_INAP              
                                  5        GND                     
                                  6        PWRGD_DSW_PWROK         
VR1D1            ZENER_SM-13V,IC,H69095-001 1        P12V_PSU                
                                  2        GND                     
XBT8G1           VERT_BATT_3PIN_PIP-3PVERT,C686A 1        P3V_BAT_SOURCE          
                                  2        P3V_BAT_SOURCE          
                                  3        GND                     
Y3F1             OSC_C_6P10-156.25MHZ,OSC,G6383A 1        FM_CPU1_STL_BRD_OSC_EN  
                                  2        NC_CLK_156M_CPU1_OSC    
                                  3        GND                     
                                  4        CLK_156M_OSC_BRD_CPU1_DP
                                  5        CLK_156M_OSC_BRD_CPU1_DN
                                  6        P3V3                    
Y6F1             OSC_C_6P10-156.25MHZ,OSC,G6383A 1        FM_CPU0_STL_BRD_OSC_EN  
                                  2        NC_CLK_156M_CPU0_OSC    
                                  3        GND                     
                                  4        CLK_156M_OSC_BRD_CPU0_DP
                                  5        CLK_156M_OSC_BRD_CPU0_DN
                                  6        P3V3                    
Y7C1             CRYSTAL_2013-48.000MHZ,IC,D717A 1        XTAL_PCH_48M_IN         
                                  3        XTAL_PCH_48M_OUT        
Y7C2             CRYSTAL_SM-32.768KHZ,IC,C13544A 1        XTAL_33K_RTC1           
                                  2        XTAL_33K_RTC2           
Y8C1             CRYSTAL_2013-25.000MHZ,IC,H196A 1        XTAL_KR_25M_IN          
                                  3        XTAL_KR_25M_OUT         
Y8F1             CRYSTAL_2013LF-25.000MHZ,IC,D7B 1        XTAL_CK_MNG_IN          
                                  3        XTAL_CK_MNG_OUT         
Y9E1             CRYSTAL_2013-25.000MHZ,IC,D717A 1        XTAL_25MHZ_IN           
                                  3        XTAL_25MHZ_OUT_R        
Y9F1             CRYSTAL_SM-24.000MHZ,IC,D95126A 1        XTAL_24MHZ_PI7C9X1172_IN
                                  2        XTAL_24MHZ_PI7C9X1172_OUT
Y9F2             OSC_C_SM4-24MHZ,OSC,D34520-021 1        PU_24M_OSC_OE           
                                  2        GND                     
                                  3        CLK_24M_BMC_CLKIN_R     
                                  4        P3V3_STBY               
END BODY ORDERED NET LIST
